FILE_TYPE=EXPANDEDPARTLIST;
{ Allegro Design Entry HDL run on 15:44:04 Wednesday, September 02, 2020 }
DIRECTIVES
 PST_VERSION='PST_HDL_CENTRIC_VERSION_0';
 ROOT_DRAWING='T6G';
 POST_TIME='15:44:04 Wednesday, September 02, 2020';
 SOURCE_TOOL='PACKAGER_XL';
 VAR_0_MPS = '' ;
 VAR_DEF_MPS = '' ;
 VDES_MPS = '*' ;
 VDNI_MPS = 'DNI' ;
 VPROP_MPS = 'VARIANT' ;
 ALTERNATE_VALUE = '3' ;
END_DIRECTIVES;

PART_NAME
 R3356 'Q_RES_0402LF-27.4,1%,1/16W,CHIP,CS02742FB03':
;

SECTION_NUMBER 1
 '@T6G_MB_LIB.T6G(SCH_1):PAGE209_I82@PURE_QUANTA.Q_RES(CHIPS)':
 C_PATH='@t6g_mb_lib.t6g(sch_1):page209_i82@pure_quanta.q_res(chips)';

PART_NAME
 R3355 'Q_RES_0402LF-27.4,1%,1/16W,CHIP,CS02742FB03':
;

SECTION_NUMBER 1
 '@T6G_MB_LIB.T6G(SCH_1):PAGE209_I81@PURE_QUANTA.Q_RES(CHIPS)':
 C_PATH='@t6g_mb_lib.t6g(sch_1):page209_i81@pure_quanta.q_res(chips)';

PART_NAME
 R3354 'Q_RES_0402LF-27.4,1%,1/16W,CHIP,CS02742FB03':
;

SECTION_NUMBER 1
 '@T6G_MB_LIB.T6G(SCH_1):PAGE209_I73@PURE_QUANTA.Q_RES(CHIPS)':
 C_PATH='@t6g_mb_lib.t6g(sch_1):page209_i73@pure_quanta.q_res(chips)';

PART_NAME
 R3312 'Q_RES_0402LF-27.4,1%,1/16W,CHIP,CS02742FB03':
;

SECTION_NUMBER 1
 '@T6G_MB_LIB.T6G(SCH_1):PAGE209_I74@PURE_QUANTA.Q_RES(CHIPS)':
 C_PATH='@t6g_mb_lib.t6g(sch_1):page209_i74@pure_quanta.q_res(chips)';

PART_NAME
 R3311 'Q_RES_0402LF-27.4,1%,1/16W,CHIP,CS02742FB03':
;

SECTION_NUMBER 1
 '@T6G_MB_LIB.T6G(SCH_1):PAGE209_I72@PURE_QUANTA.Q_RES(CHIPS)':
 C_PATH='@t6g_mb_lib.t6g(sch_1):page209_i72@pure_quanta.q_res(chips)';

PART_NAME
 R3310 'Q_RES_0402LF-27.4,1%,1/16W,CHIP,CS02742FB03':
;

SECTION_NUMBER 1
 '@T6G_MB_LIB.T6G(SCH_1):PAGE209_I71@PURE_QUANTA.Q_RES(CHIPS)':
 C_PATH='@t6g_mb_lib.t6g(sch_1):page209_i71@pure_quanta.q_res(chips)';

PART_NAME
 R3309 'Q_RES_0402LF-27.4,1%,1/16W,CHIP,CS02742FB03':
;

SECTION_NUMBER 1
 '@T6G_MB_LIB.T6G(SCH_1):PAGE209_I70@PURE_QUANTA.Q_RES(CHIPS)':
 C_PATH='@t6g_mb_lib.t6g(sch_1):page209_i70@pure_quanta.q_res(chips)';

PART_NAME
 R3308 'Q_RES_0402LF-27.4,1%,1/16W,CHIP,CS02742FB03':
;

SECTION_NUMBER 1
 '@T6G_MB_LIB.T6G(SCH_1):PAGE209_I69@PURE_QUANTA.Q_RES(CHIPS)':
 C_PATH='@t6g_mb_lib.t6g(sch_1):page209_i69@pure_quanta.q_res(chips)';

PART_NAME
 R3307 'Q_RES_0402LF-27.4,1%,1/16W,CHIP,CS02742FB03':
;

SECTION_NUMBER 1
 '@T6G_MB_LIB.T6G(SCH_1):PAGE209_I84@PURE_QUANTA.Q_RES(CHIPS)':
 C_PATH='@t6g_mb_lib.t6g(sch_1):page209_i84@pure_quanta.q_res(chips)';

PART_NAME
 R3304 'Q_RES_0402LF-27.4,1%,1/16W,CHIP,CS02742FB03':
;

SECTION_NUMBER 1
 '@T6G_MB_LIB.T6G(SCH_1):PAGE209_I83@PURE_QUANTA.Q_RES(CHIPS)':
 C_PATH='@t6g_mb_lib.t6g(sch_1):page209_i83@pure_quanta.q_res(chips)';

PART_NAME
 R3303 'Q_RES_0402LF-27.4,1%,1/16W,CHIP,CS02742FB03':
;

SECTION_NUMBER 1
 '@T6G_MB_LIB.T6G(SCH_1):PAGE209_I79@PURE_QUANTA.Q_RES(CHIPS)':
 C_PATH='@t6g_mb_lib.t6g(sch_1):page209_i79@pure_quanta.q_res(chips)';

PART_NAME
 R3302 'Q_RES_0402LF-27.4,1%,1/16W,CHIP,CS02742FB03':
;

SECTION_NUMBER 1
 '@T6G_MB_LIB.T6G(SCH_1):PAGE209_I80@PURE_QUANTA.Q_RES(CHIPS)':
 C_PATH='@t6g_mb_lib.t6g(sch_1):page209_i80@pure_quanta.q_res(chips)';

PART_NAME
 R3301 'Q_RES_0402LF-27.4,1%,1/16W,CHIP,CS02742FB03':
;

SECTION_NUMBER 1
 '@T6G_MB_LIB.T6G(SCH_1):PAGE209_I78@PURE_QUANTA.Q_RES(CHIPS)':
 C_PATH='@t6g_mb_lib.t6g(sch_1):page209_i78@pure_quanta.q_res(chips)';

PART_NAME
 R3300 'Q_RES_0402LF-27.4,1%,1/16W,CHIP,CS02742FB03':
;

SECTION_NUMBER 1
 '@T6G_MB_LIB.T6G(SCH_1):PAGE209_I77@PURE_QUANTA.Q_RES(CHIPS)':
 C_PATH='@t6g_mb_lib.t6g(sch_1):page209_i77@pure_quanta.q_res(chips)';

PART_NAME
 R3299 'Q_RES_0402LF-27.4,1%,1/16W,CHIP,CS02742FB03':
;

SECTION_NUMBER 1
 '@T6G_MB_LIB.T6G(SCH_1):PAGE209_I76@PURE_QUANTA.Q_RES(CHIPS)':
 C_PATH='@t6g_mb_lib.t6g(sch_1):page209_i76@pure_quanta.q_res(chips)';

PART_NAME
 R3298 'Q_RES_0402LF-27.4,1%,1/16W,CHIP,CS02742FB03':
;

SECTION_NUMBER 1
 '@T6G_MB_LIB.T6G(SCH_1):PAGE209_I75@PURE_QUANTA.Q_RES(CHIPS)':
 C_PATH='@t6g_mb_lib.t6g(sch_1):page209_i75@pure_quanta.q_res(chips)';

PART_NAME
 R2647 'Q_RES_0402LF-200,1%,1/16W,CHIP,CS12002FB25':;

SECTION_NUMBER 1
 '@T6G_MB_LIB.T6G(SCH_1):PAGE184_I21@PURE_QUANTA.Q_RES(CHIPS)':
 C_PATH='@t6g_mb_lib.t6g(sch_1):page184_i21@pure_quanta.q_res(chips)';

PART_NAME
 R2470 'Q_RES_0402LF-0,5%,1/16W,CHIP,CS00002JB38':;

SECTION_NUMBER 1
 '@T6G_MB_LIB.T6G(SCH_1):PAGE183_I74@PURE_QUANTA.Q_RES(CHIPS)':
 C_PATH='@t6g_mb_lib.t6g(sch_1):page183_i74@pure_quanta.q_res(chips)';

PART_NAME
 R2468 'Q_RES_0402LF-0,5%,1/16W,EMPTY,CS00002JB38':;

SECTION_NUMBER 1
 '@T6G_MB_LIB.T6G(SCH_1):PAGE183_I73@PURE_QUANTA.Q_RES(CHIPS)':
 C_PATH='@t6g_mb_lib.t6g(sch_1):page183_i73@pure_quanta.q_res(chips)';

PART_NAME
 R1971 'Q_RES_0402LF-27.4,1%,1/16W,CHIP,CS02742FB03':
;

SECTION_NUMBER 1
 '@T6G_MB_LIB.T6G(SCH_1):PAGE210_I33@PURE_QUANTA.Q_RES(CHIPS)':
 C_PATH='@t6g_mb_lib.t6g(sch_1):page210_i33@pure_quanta.q_res(chips)';

PART_NAME
 R1970 'Q_RES_0402LF-27.4,1%,1/16W,CHIP,CS02742FB03':
;

SECTION_NUMBER 1
 '@T6G_MB_LIB.T6G(SCH_1):PAGE210_I11@PURE_QUANTA.Q_RES(CHIPS)':
 C_PATH='@t6g_mb_lib.t6g(sch_1):page210_i11@pure_quanta.q_res(chips)';

PART_NAME
 R1967 'Q_RES_0402LF-27.4,1%,1/16W,CHIP,CS02742FB03':
;

SECTION_NUMBER 1
 '@T6G_MB_LIB.T6G(SCH_1):PAGE210_I44@PURE_QUANTA.Q_RES(CHIPS)':
 C_PATH='@t6g_mb_lib.t6g(sch_1):page210_i44@pure_quanta.q_res(chips)';

PART_NAME
 R1966 'Q_RES_0402LF-27.4,1%,1/16W,CHIP,CS02742FB03':
;

SECTION_NUMBER 1
 '@T6G_MB_LIB.T6G(SCH_1):PAGE210_I43@PURE_QUANTA.Q_RES(CHIPS)':
 C_PATH='@t6g_mb_lib.t6g(sch_1):page210_i43@pure_quanta.q_res(chips)';

PART_NAME
 R1965 'Q_RES_0402LF-27.4,1%,1/16W,CHIP,CS02742FB03':
;

SECTION_NUMBER 1
 '@T6G_MB_LIB.T6G(SCH_1):PAGE210_I41@PURE_QUANTA.Q_RES(CHIPS)':
 C_PATH='@t6g_mb_lib.t6g(sch_1):page210_i41@pure_quanta.q_res(chips)';

PART_NAME
 R1964 'Q_RES_0402LF-27.4,1%,1/16W,CHIP,CS02742FB03':
;

SECTION_NUMBER 1
 '@T6G_MB_LIB.T6G(SCH_1):PAGE210_I42@PURE_QUANTA.Q_RES(CHIPS)':
 C_PATH='@t6g_mb_lib.t6g(sch_1):page210_i42@pure_quanta.q_res(chips)';

PART_NAME
 R1963 'Q_RES_0402LF-27.4,1%,1/16W,CHIP,CS02742FB03':
;

SECTION_NUMBER 1
 '@T6G_MB_LIB.T6G(SCH_1):PAGE210_I35@PURE_QUANTA.Q_RES(CHIPS)':
 C_PATH='@t6g_mb_lib.t6g(sch_1):page210_i35@pure_quanta.q_res(chips)';

PART_NAME
 R1962 'Q_RES_0402LF-27.4,1%,1/16W,CHIP,CS02742FB03':
;

SECTION_NUMBER 1
 '@T6G_MB_LIB.T6G(SCH_1):PAGE210_I36@PURE_QUANTA.Q_RES(CHIPS)':
 C_PATH='@t6g_mb_lib.t6g(sch_1):page210_i36@pure_quanta.q_res(chips)';

PART_NAME
 R1961 'Q_RES_0402LF-27.4,1%,1/16W,CHIP,CS02742FB03':
;

SECTION_NUMBER 1
 '@T6G_MB_LIB.T6G(SCH_1):PAGE210_I34@PURE_QUANTA.Q_RES(CHIPS)':
 C_PATH='@t6g_mb_lib.t6g(sch_1):page210_i34@pure_quanta.q_res(chips)';

PART_NAME
 R1954 'Q_RES_0402LF-27.4,1%,1/16W,CHIP,CS02742FB03':
;

SECTION_NUMBER 1
 '@T6G_MB_LIB.T6G(SCH_1):PAGE210_I23@PURE_QUANTA.Q_RES(CHIPS)':
 C_PATH='@t6g_mb_lib.t6g(sch_1):page210_i23@pure_quanta.q_res(chips)';

PART_NAME
 R1953 'Q_RES_0402LF-27.4,1%,1/16W,CHIP,CS02742FB03':
;

SECTION_NUMBER 1
 '@T6G_MB_LIB.T6G(SCH_1):PAGE210_I24@PURE_QUANTA.Q_RES(CHIPS)':
 C_PATH='@t6g_mb_lib.t6g(sch_1):page210_i24@pure_quanta.q_res(chips)';

PART_NAME
 R1952 'Q_RES_0402LF-27.4,1%,1/16W,CHIP,CS02742FB03':
;

SECTION_NUMBER 1
 '@T6G_MB_LIB.T6G(SCH_1):PAGE210_I22@PURE_QUANTA.Q_RES(CHIPS)':
 C_PATH='@t6g_mb_lib.t6g(sch_1):page210_i22@pure_quanta.q_res(chips)';

PART_NAME
 R1951 'Q_RES_0402LF-27.4,1%,1/16W,CHIP,CS02742FB03':
;

SECTION_NUMBER 1
 '@T6G_MB_LIB.T6G(SCH_1):PAGE210_I21@PURE_QUANTA.Q_RES(CHIPS)':
 C_PATH='@t6g_mb_lib.t6g(sch_1):page210_i21@pure_quanta.q_res(chips)';

PART_NAME
 R1950 'Q_RES_0402LF-27.4,1%,1/16W,CHIP,CS02742FB03':
;

SECTION_NUMBER 1
 '@T6G_MB_LIB.T6G(SCH_1):PAGE210_I12@PURE_QUANTA.Q_RES(CHIPS)':
 C_PATH='@t6g_mb_lib.t6g(sch_1):page210_i12@pure_quanta.q_res(chips)';

PART_NAME
 R1949 'Q_RES_0402LF-27.4,1%,1/16W,CHIP,CS02742FB03':
;

SECTION_NUMBER 1
 '@T6G_MB_LIB.T6G(SCH_1):PAGE210_I10@PURE_QUANTA.Q_RES(CHIPS)':
 C_PATH='@t6g_mb_lib.t6g(sch_1):page210_i10@pure_quanta.q_res(chips)';

PART_NAME
 R1948 'Q_RES_0402LF-27.4,1%,1/16W,CHIP,CS02742FB03':
;

SECTION_NUMBER 1
 '@T6G_MB_LIB.T6G(SCH_1):PAGE210_I9@PURE_QUANTA.Q_RES(CHIPS)':
 C_PATH='@t6g_mb_lib.t6g(sch_1):page210_i9@pure_quanta.q_res(chips)';

PART_NAME
 U121 'INA183A1IDBVR-INA183A1IDBVR,SMLF,EMPTY,AL000183000':;

SECTION_NUMBER 1
 '@T6G_MB_LIB.T6G(SCH_1):PAGE100_I23@PURE_QUANTA.INA183A1IDBVR(CHIPS)':
 C_PATH='@t6g_mb_lib.t6g(sch_1):page100_i23@pure_quanta.ina183a1idbvr(chips)',
 CDSVAR_REPCELL_MPS='pure_quanta|ina183a1idbvr',
 VAR_0_MPS='VALUE|INA183A1IDBVR|PART_TYPE|SMLF|MATERIAL|IC|PART_NUMBER|AL0001830~
00|STANDARD||LIFECYCLE||PART_NUMBER|AL000183000|JEDEC_TYPE|SOT23-5_0-95_2-9X1-6X~
D|DESCRIPTION|IC AMPL(5P)INA183A1IDBVR(SOT23)|MANUFTR|TIC|MANUF_PN|INA183A1IDBVR~
|RD_CMPLS_LVL|EP(V1)|CMPLS_LVL||FROM_PJ|S9S-KIMI|CLASS|IC|DIP_SMD||DATA|TIC_INA1~
83A1IDBVR.PDF|EE_CHECK_LIST||FP_ECN||PSL||CREATOR||STATUS||MSD|NA|ESD_CDM|na|ESD~
_HBM|na|ESD_MM|na|PIN_LENGTH_SHORT_PIN|0 MILS|PIN_LENGTH_LONG_PIN|0 MILS|CREATED~
AY|20200514|VARIANT_DEVICE_TYPE|INA183A1IDBVR-INA183A1IDBVR,SM';

PART_NAME
 U120 'INA183A1IDBVR-INA183A1IDBVR,SMLF,EMPTY,AL000183000':;

SECTION_NUMBER 1
 '@T6G_MB_LIB.T6G(SCH_1):PAGE100_I24@PURE_QUANTA.INA183A1IDBVR(CHIPS)':
 C_PATH='@t6g_mb_lib.t6g(sch_1):page100_i24@pure_quanta.ina183a1idbvr(chips)',
 CDSVAR_REPCELL_MPS='pure_quanta|ina183a1idbvr',
 VAR_0_MPS='VALUE|INA183A1IDBVR|PART_TYPE|SMLF|MATERIAL|IC|PART_NUMBER|AL0001830~
00|STANDARD||LIFECYCLE||PART_NUMBER|AL000183000|JEDEC_TYPE|SOT23-5_0-95_2-9X1-6X~
D|DESCRIPTION|IC AMPL(5P)INA183A1IDBVR(SOT23)|MANUFTR|TIC|MANUF_PN|INA183A1IDBVR~
|RD_CMPLS_LVL|EP(V1)|CMPLS_LVL||FROM_PJ|S9S-KIMI|CLASS|IC|DIP_SMD||DATA|TIC_INA1~
83A1IDBVR.PDF|EE_CHECK_LIST||FP_ECN||PSL||CREATOR||STATUS||MSD|NA|ESD_CDM|na|ESD~
_HBM|na|ESD_MM|na|PIN_LENGTH_SHORT_PIN|0 MILS|PIN_LENGTH_LONG_PIN|0 MILS|CREATED~
AY|20200514|VARIANT_DEVICE_TYPE|INA183A1IDBVR-INA183A1IDBVR,SM';

PART_NAME
 R1838 'Q_RES_4P_12-0.001,1%,3W,SMLF,CHIP,SP_CS+001DFR00':;

SECTION_NUMBER 1
 '@T6G_MB_LIB.T6G(SCH_1):PAGE100_I16@PURE_QUANTA.Q_RES_4P_12(CHIPS)':
 C_PATH='@t6g_mb_lib.t6g(sch_1):page100_i16@pure_quanta.q_res_4p_12(chips)';

PART_NAME
 R1837 'Q_RES_4P_12-0.001,1%,3W,SMLF,CHIP,SP_CS+001DFR00':;

SECTION_NUMBER 1
 '@T6G_MB_LIB.T6G(SCH_1):PAGE100_I18@PURE_QUANTA.Q_RES_4P_12(CHIPS)':
 C_PATH='@t6g_mb_lib.t6g(sch_1):page100_i18@pure_quanta.q_res_4p_12(chips)';

PART_NAME
 R3715 'Q_RES_0402LF-0,5%,1/16W,EMPTY,CS00002JB38':;

SECTION_NUMBER 1
 '@T6G_MB_LIB.T6G(SCH_1):PAGE240_I350@PURE_QUANTA.Q_RES(CHIPS)':
 C_PATH='@t6g_mb_lib.t6g(sch_1):page240_i350@pure_quanta.q_res(chips)';

PART_NAME
 R1681 'Q_RES_0402LF-10K,1%,1/16W,CHIP,TMP_QCS31002FB26':;

SECTION_NUMBER 1
 '@T6G_MB_LIB.T6G(SCH_1):PAGE240_I323@PURE_QUANTA.Q_RES(CHIPS)':
 C_PATH='@t6g_mb_lib.t6g(sch_1):page240_i323@pure_quanta.q_res(chips)';

PART_NAME
 R1530 'Q_RES_0402LF-113,1%,1/16W,CHIP,CS11132FB01':;

SECTION_NUMBER 1
 '@T6G_MB_LIB.T6G(SCH_1):PAGE177_I131@PURE_QUANTA.Q_RES(CHIPS)':
 C_PATH='@t6g_mb_lib.t6g(sch_1):page177_i131@pure_quanta.q_res(chips)';

PART_NAME
 R1503 'Q_RES_0402LF-10K,1%,1/16W,EMPTY,TMP_QCS31002FB26':;

SECTION_NUMBER 1
 '@T6G_MB_LIB.T6G(SCH_1):PAGE18_I164@PURE_QUANTA.Q_RES(CHIPS)':
 C_PATH='@t6g_mb_lib.t6g(sch_1):page18_i164@pure_quanta.q_res(chips)';

PART_NAME
 R2467 'Q_RES_0402LF-0,5%,1/16W,CHIP,CS00002JB38':;

SECTION_NUMBER 1
 '@T6G_MB_LIB.T6G(SCH_1):PAGE88_I53@PURE_QUANTA.Q_RES(CHIPS)':
 C_PATH='@t6g_mb_lib.t6g(sch_1):page88_i53@pure_quanta.q_res(chips)';

PART_NAME
 R2466 'Q_RES_0402LF-0,5%,1/16W,CHIP,CS00002JB38':;

SECTION_NUMBER 1
 '@T6G_MB_LIB.T6G(SCH_1):PAGE88_I44@PURE_QUANTA.Q_RES(CHIPS)':
 C_PATH='@t6g_mb_lib.t6g(sch_1):page88_i44@pure_quanta.q_res(chips)';

PART_NAME
 R1244 'Q_RES_0402LF-301,1%,1/16W,CHIP,TMP_QCS13012FB14':;

SECTION_NUMBER 1
 '@T6G_MB_LIB.T6G(SCH_1):PAGE88_I47@PURE_QUANTA.Q_RES(CHIPS)':
 C_PATH='@t6g_mb_lib.t6g(sch_1):page88_i47@pure_quanta.q_res(chips)';

PART_NAME
 R1243 'Q_RES_0402LF-249,1%,1/16W,CHIP,CS12492FB12':;

SECTION_NUMBER 1
 '@T6G_MB_LIB.T6G(SCH_1):PAGE88_I50@PURE_QUANTA.Q_RES(CHIPS)':
 C_PATH='@t6g_mb_lib.t6g(sch_1):page88_i50@pure_quanta.q_res(chips)';

PART_NAME
 R1242 'Q_RES_0402LF-301,1%,1/16W,CHIP,TMP_QCS13012FB14':;

SECTION_NUMBER 1
 '@T6G_MB_LIB.T6G(SCH_1):PAGE88_I45@PURE_QUANTA.Q_RES(CHIPS)':
 C_PATH='@t6g_mb_lib.t6g(sch_1):page88_i45@pure_quanta.q_res(chips)';

PART_NAME
 R1241 'Q_RES_0402LF-249,1%,1/16W,CHIP,CS12492FB12':;

SECTION_NUMBER 1
 '@T6G_MB_LIB.T6G(SCH_1):PAGE88_I43@PURE_QUANTA.Q_RES(CHIPS)':
 C_PATH='@t6g_mb_lib.t6g(sch_1):page88_i43@pure_quanta.q_res(chips)';

PART_NAME
 R1683 'Q_RES_0402LF-1K,1%,1/16W,CHIP,TMP_QCS21002FB24':;

SECTION_NUMBER 1
 '@T6G_MB_LIB.T6G(SCH_1):PAGE190_I17@PURE_QUANTA.Q_RES(CHIPS)':
 C_PATH='@t6g_mb_lib.t6g(sch_1):page190_i17@pure_quanta.q_res(chips)';

PART_NAME
 R1682 'Q_RES_0402LF-1K,1%,1/16W,EMPTY,TMP_QCS21002FB24':;

SECTION_NUMBER 1
 '@T6G_MB_LIB.T6G(SCH_1):PAGE190_I14@PURE_QUANTA.Q_RES(CHIPS)':
 C_PATH='@t6g_mb_lib.t6g(sch_1):page190_i14@pure_quanta.q_res(chips)';

PART_NAME
 R1680 'Q_RES_0402LF-10K,1%,1/16W,CHIP,TMP_QCS31002FB26':;

SECTION_NUMBER 1
 '@T6G_MB_LIB.T6G(SCH_1):PAGE190_I12@PURE_QUANTA.Q_RES(CHIPS)':
 C_PATH='@t6g_mb_lib.t6g(sch_1):page190_i12@pure_quanta.q_res(chips)';

PART_NAME
 R1679 'Q_RES_0402LF-1K,1%,1/16W,EMPTY,TMP_QCS21002FB24':;

SECTION_NUMBER 1
 '@T6G_MB_LIB.T6G(SCH_1):PAGE190_I9@PURE_QUANTA.Q_RES(CHIPS)':
 C_PATH='@t6g_mb_lib.t6g(sch_1):page190_i9@pure_quanta.q_res(chips)';

PART_NAME
 R1678 'Q_RES_0402LF-10K,1%,1/16W,CHIP,TMP_QCS31002FB26':;

SECTION_NUMBER 1
 '@T6G_MB_LIB.T6G(SCH_1):PAGE190_I4@PURE_QUANTA.Q_RES(CHIPS)':
 C_PATH='@t6g_mb_lib.t6g(sch_1):page190_i4@pure_quanta.q_res(chips)';

PART_NAME
 R1677 'Q_RES_0402LF-1K,5%,1/16W,EMPTY,TMP_QCS21002JB34':;

SECTION_NUMBER 1
 '@T6G_MB_LIB.T6G(SCH_1):PAGE190_I2@PURE_QUANTA.Q_RES(CHIPS)':
 C_PATH='@t6g_mb_lib.t6g(sch_1):page190_i2@pure_quanta.q_res(chips)';

PART_NAME
 R1674 'Q_RES_0402LF-1K,1%,1/16W,EMPTY,TMP_QCS21002FB24':;

SECTION_NUMBER 1
 '@T6G_MB_LIB.T6G(SCH_1):PAGE190_I30@PURE_QUANTA.Q_RES(CHIPS)':
 C_PATH='@t6g_mb_lib.t6g(sch_1):page190_i30@pure_quanta.q_res(chips)';

PART_NAME
 R1673 'Q_RES_0402LF-10K,1%,1/16W,CHIP,TMP_QCS31002FB26':;

SECTION_NUMBER 1
 '@T6G_MB_LIB.T6G(SCH_1):PAGE190_I29@PURE_QUANTA.Q_RES(CHIPS)':
 C_PATH='@t6g_mb_lib.t6g(sch_1):page190_i29@pure_quanta.q_res(chips)';

PART_NAME
 R1672 'Q_RES_0402LF-1K,1%,1/16W,CHIP,TMP_QCS21002FB24':;

SECTION_NUMBER 1
 '@T6G_MB_LIB.T6G(SCH_1):PAGE190_I25@PURE_QUANTA.Q_RES(CHIPS)':
 C_PATH='@t6g_mb_lib.t6g(sch_1):page190_i25@pure_quanta.q_res(chips)';

PART_NAME
 R1666 'Q_RES_0402LF-1K,1%,1/16W,EMPTY,TMP_QCS21002FB24':;

SECTION_NUMBER 1
 '@T6G_MB_LIB.T6G(SCH_1):PAGE190_I24@PURE_QUANTA.Q_RES(CHIPS)':
 C_PATH='@t6g_mb_lib.t6g(sch_1):page190_i24@pure_quanta.q_res(chips)';

PART_NAME
 R1665 'Q_RES_0402LF-10K,1%,1/16W,CHIP,TMP_QCS31002FB26':;

SECTION_NUMBER 1
 '@T6G_MB_LIB.T6G(SCH_1):PAGE190_I21@PURE_QUANTA.Q_RES(CHIPS)':
 C_PATH='@t6g_mb_lib.t6g(sch_1):page190_i21@pure_quanta.q_res(chips)';

PART_NAME
 R1655 'Q_RES_0402LF-1K,5%,1/16W,EMPTY,TMP_QCS21002JB34':;

SECTION_NUMBER 1
 '@T6G_MB_LIB.T6G(SCH_1):PAGE190_I19@PURE_QUANTA.Q_RES(CHIPS)':
 C_PATH='@t6g_mb_lib.t6g(sch_1):page190_i19@pure_quanta.q_res(chips)';

PART_NAME
 R1654 'Q_RES_0402LF-1K,1%,1/16W,EMPTY,TMP_QCS21002FB24':;

SECTION_NUMBER 1
 '@T6G_MB_LIB.T6G(SCH_1):PAGE190_I40@PURE_QUANTA.Q_RES(CHIPS)':
 C_PATH='@t6g_mb_lib.t6g(sch_1):page190_i40@pure_quanta.q_res(chips)';

PART_NAME
 R1653 'Q_RES_0402LF-10K,1%,1/16W,CHIP,TMP_QCS31002FB26':;

SECTION_NUMBER 1
 '@T6G_MB_LIB.T6G(SCH_1):PAGE190_I37@PURE_QUANTA.Q_RES(CHIPS)':
 C_PATH='@t6g_mb_lib.t6g(sch_1):page190_i37@pure_quanta.q_res(chips)';

PART_NAME
 R1646 'Q_RES_0402LF-1K,5%,1/16W,EMPTY,TMP_QCS21002JB34':;

SECTION_NUMBER 1
 '@T6G_MB_LIB.T6G(SCH_1):PAGE190_I35@PURE_QUANTA.Q_RES(CHIPS)':
 C_PATH='@t6g_mb_lib.t6g(sch_1):page190_i35@pure_quanta.q_res(chips)';

PART_NAME
 R1222 'Q_RES_0402LF-5.11K,1%,1/16W,CHIP,TMP_QCS25112FB15':;

SECTION_NUMBER 1
 '@T6G_MB_LIB.T6G(SCH_1):PAGE190_I39@PURE_QUANTA.Q_RES(CHIPS)':
 C_PATH='@t6g_mb_lib.t6g(sch_1):page190_i39@pure_quanta.q_res(chips)';

PART_NAME
 R1221 'Q_RES_0402LF-1K,1%,1/16W,CHIP,TMP_QCS21002FB24':;

SECTION_NUMBER 1
 '@T6G_MB_LIB.T6G(SCH_1):PAGE190_I44@PURE_QUANTA.Q_RES(CHIPS)':
 C_PATH='@t6g_mb_lib.t6g(sch_1):page190_i44@pure_quanta.q_res(chips)';

PART_NAME
 R1220 'Q_RES_0402LF-1K,1%,1/16W,EMPTY,TMP_QCS21002FB24':;

SECTION_NUMBER 1
 '@T6G_MB_LIB.T6G(SCH_1):PAGE190_I43@PURE_QUANTA.Q_RES(CHIPS)':
 C_PATH='@t6g_mb_lib.t6g(sch_1):page190_i43@pure_quanta.q_res(chips)';

PART_NAME
 R2174 'Q_RES_0402LF-33,5%,1/16W,CHIP,CS03302JB29':;

SECTION_NUMBER 1
 '@T6G_MB_LIB.T6G(SCH_1):PAGE246_I31@PURE_QUANTA.Q_RES(CHIPS)':
 C_PATH='@t6g_mb_lib.t6g(sch_1):page246_i31@pure_quanta.q_res(chips)';

PART_NAME
 R2160 'Q_RES_0402LF-33,5%,1/16W,CHIP,CS03302JB29':;

SECTION_NUMBER 1
 '@T6G_MB_LIB.T6G(SCH_1):PAGE246_I30@PURE_QUANTA.Q_RES(CHIPS)':
 C_PATH='@t6g_mb_lib.t6g(sch_1):page246_i30@pure_quanta.q_res(chips)';

PART_NAME
 R2157 'Q_RES_0402LF-33,5%,1/16W,CHIP,CS03302JB29':;

SECTION_NUMBER 1
 '@T6G_MB_LIB.T6G(SCH_1):PAGE246_I16@PURE_QUANTA.Q_RES(CHIPS)':
 C_PATH='@t6g_mb_lib.t6g(sch_1):page246_i16@pure_quanta.q_res(chips)';

PART_NAME
 R2147 'Q_RES_0402LF-33,5%,1/16W,CHIP,CS03302JB29':;

SECTION_NUMBER 1
 '@T6G_MB_LIB.T6G(SCH_1):PAGE246_I15@PURE_QUANTA.Q_RES(CHIPS)':
 C_PATH='@t6g_mb_lib.t6g(sch_1):page246_i15@pure_quanta.q_res(chips)';

PART_NAME
 R2145 'Q_RES_0402LF-33,5%,1/16W,CHIP,CS03302JB29':;

SECTION_NUMBER 1
 '@T6G_MB_LIB.T6G(SCH_1):PAGE246_I14@PURE_QUANTA.Q_RES(CHIPS)':
 C_PATH='@t6g_mb_lib.t6g(sch_1):page246_i14@pure_quanta.q_res(chips)';

PART_NAME
 R2144 'Q_RES_0402LF-33,5%,1/16W,CHIP,CS03302JB29':;

SECTION_NUMBER 1
 '@T6G_MB_LIB.T6G(SCH_1):PAGE246_I13@PURE_QUANTA.Q_RES(CHIPS)':
 C_PATH='@t6g_mb_lib.t6g(sch_1):page246_i13@pure_quanta.q_res(chips)';

PART_NAME
 R2142 'Q_RES_0402LF-33,5%,1/16W,CHIP,CS03302JB29':;

SECTION_NUMBER 1
 '@T6G_MB_LIB.T6G(SCH_1):PAGE246_I37@PURE_QUANTA.Q_RES(CHIPS)':
 C_PATH='@t6g_mb_lib.t6g(sch_1):page246_i37@pure_quanta.q_res(chips)';

PART_NAME
 R2139 'Q_RES_0402LF-33,5%,1/16W,CHIP,CS03302JB29':;

SECTION_NUMBER 1
 '@T6G_MB_LIB.T6G(SCH_1):PAGE246_I36@PURE_QUANTA.Q_RES(CHIPS)':
 C_PATH='@t6g_mb_lib.t6g(sch_1):page246_i36@pure_quanta.q_res(chips)';

PART_NAME
 R2138 'Q_RES_0402LF-33,5%,1/16W,CHIP,CS03302JB29':;

SECTION_NUMBER 1
 '@T6G_MB_LIB.T6G(SCH_1):PAGE246_I32@PURE_QUANTA.Q_RES(CHIPS)':
 C_PATH='@t6g_mb_lib.t6g(sch_1):page246_i32@pure_quanta.q_res(chips)';

PART_NAME
 R2135 'Q_RES_0402LF-33,5%,1/16W,CHIP,CS03302JB29':;

SECTION_NUMBER 1
 '@T6G_MB_LIB.T6G(SCH_1):PAGE246_I12@PURE_QUANTA.Q_RES(CHIPS)':
 C_PATH='@t6g_mb_lib.t6g(sch_1):page246_i12@pure_quanta.q_res(chips)';

PART_NAME
 R2132 'Q_RES_0402LF-33,5%,1/16W,CHIP,CS03302JB29':;

SECTION_NUMBER 1
 '@T6G_MB_LIB.T6G(SCH_1):PAGE246_I11@PURE_QUANTA.Q_RES(CHIPS)':
 C_PATH='@t6g_mb_lib.t6g(sch_1):page246_i11@pure_quanta.q_res(chips)';

PART_NAME
 R2129 'Q_RES_0402LF-33,5%,1/16W,CHIP,CS03302JB29':;

SECTION_NUMBER 1
 '@T6G_MB_LIB.T6G(SCH_1):PAGE246_I10@PURE_QUANTA.Q_RES(CHIPS)':
 C_PATH='@t6g_mb_lib.t6g(sch_1):page246_i10@pure_quanta.q_res(chips)';

PART_NAME
 R2128 'Q_RES_0402LF-33,5%,1/16W,CHIP,CS03302JB29':;

SECTION_NUMBER 1
 '@T6G_MB_LIB.T6G(SCH_1):PAGE246_I73@PURE_QUANTA.Q_RES(CHIPS)':
 C_PATH='@t6g_mb_lib.t6g(sch_1):page246_i73@pure_quanta.q_res(chips)';

PART_NAME
 R2096 'Q_RES_0402LF-33,5%,1/16W,CHIP,CS03302JB29':;

SECTION_NUMBER 1
 '@T6G_MB_LIB.T6G(SCH_1):PAGE246_I72@PURE_QUANTA.Q_RES(CHIPS)':
 C_PATH='@t6g_mb_lib.t6g(sch_1):page246_i72@pure_quanta.q_res(chips)';

PART_NAME
 R2095 'Q_RES_0402LF-33,5%,1/16W,CHIP,CS03302JB29':;

SECTION_NUMBER 1
 '@T6G_MB_LIB.T6G(SCH_1):PAGE246_I70@PURE_QUANTA.Q_RES(CHIPS)':
 C_PATH='@t6g_mb_lib.t6g(sch_1):page246_i70@pure_quanta.q_res(chips)';

PART_NAME
 R2094 'Q_RES_0402LF-33,5%,1/16W,CHIP,CS03302JB29':;

SECTION_NUMBER 1
 '@T6G_MB_LIB.T6G(SCH_1):PAGE246_I68@PURE_QUANTA.Q_RES(CHIPS)':
 C_PATH='@t6g_mb_lib.t6g(sch_1):page246_i68@pure_quanta.q_res(chips)';

PART_NAME
 R2093 'Q_RES_0402LF-33,5%,1/16W,CHIP,CS03302JB29':;

SECTION_NUMBER 1
 '@T6G_MB_LIB.T6G(SCH_1):PAGE246_I67@PURE_QUANTA.Q_RES(CHIPS)':
 C_PATH='@t6g_mb_lib.t6g(sch_1):page246_i67@pure_quanta.q_res(chips)';

PART_NAME
 R2088 'Q_RES_0402LF-33,5%,1/16W,CHIP,CS03302JB29':;

SECTION_NUMBER 1
 '@T6G_MB_LIB.T6G(SCH_1):PAGE246_I66@PURE_QUANTA.Q_RES(CHIPS)':
 C_PATH='@t6g_mb_lib.t6g(sch_1):page246_i66@pure_quanta.q_res(chips)';

PART_NAME
 R2087 'Q_RES_0402LF-33,5%,1/16W,CHIP,CS03302JB29':;

SECTION_NUMBER 1
 '@T6G_MB_LIB.T6G(SCH_1):PAGE246_I65@PURE_QUANTA.Q_RES(CHIPS)':
 C_PATH='@t6g_mb_lib.t6g(sch_1):page246_i65@pure_quanta.q_res(chips)';

PART_NAME
 R2084 'Q_RES_0402LF-33,5%,1/16W,CHIP,CS03302JB29':;

SECTION_NUMBER 1
 '@T6G_MB_LIB.T6G(SCH_1):PAGE246_I52@PURE_QUANTA.Q_RES(CHIPS)':
 C_PATH='@t6g_mb_lib.t6g(sch_1):page246_i52@pure_quanta.q_res(chips)';

PART_NAME
 R2083 'Q_RES_0402LF-33,5%,1/16W,CHIP,CS03302JB29':;

SECTION_NUMBER 1
 '@T6G_MB_LIB.T6G(SCH_1):PAGE246_I51@PURE_QUANTA.Q_RES(CHIPS)':
 C_PATH='@t6g_mb_lib.t6g(sch_1):page246_i51@pure_quanta.q_res(chips)';

PART_NAME
 R2074 'Q_RES_0402LF-33,5%,1/16W,CHIP,CS03302JB29':;

SECTION_NUMBER 1
 '@T6G_MB_LIB.T6G(SCH_1):PAGE246_I50@PURE_QUANTA.Q_RES(CHIPS)':
 C_PATH='@t6g_mb_lib.t6g(sch_1):page246_i50@pure_quanta.q_res(chips)';

PART_NAME
 R2073 'Q_RES_0402LF-33,5%,1/16W,CHIP,CS03302JB29':;

SECTION_NUMBER 1
 '@T6G_MB_LIB.T6G(SCH_1):PAGE246_I49@PURE_QUANTA.Q_RES(CHIPS)':
 C_PATH='@t6g_mb_lib.t6g(sch_1):page246_i49@pure_quanta.q_res(chips)';

PART_NAME
 R2072 'Q_RES_0402LF-33,5%,1/16W,CHIP,CS03302JB29':;

SECTION_NUMBER 1
 '@T6G_MB_LIB.T6G(SCH_1):PAGE246_I48@PURE_QUANTA.Q_RES(CHIPS)':
 C_PATH='@t6g_mb_lib.t6g(sch_1):page246_i48@pure_quanta.q_res(chips)';

PART_NAME
 R1919 'Q_RES_0402LF-33,5%,1/16W,CHIP,CS03302JB29':;

SECTION_NUMBER 1
 '@T6G_MB_LIB.T6G(SCH_1):PAGE246_I71@PURE_QUANTA.Q_RES(CHIPS)':
 C_PATH='@t6g_mb_lib.t6g(sch_1):page246_i71@pure_quanta.q_res(chips)';

PART_NAME
 R1751 'Q_RES_0402LF-33,5%,1/16W,CHIP,CS03302JB29':;

SECTION_NUMBER 1
 '@T6G_MB_LIB.T6G(SCH_1):PAGE246_I9@PURE_QUANTA.Q_RES(CHIPS)':
 C_PATH='@t6g_mb_lib.t6g(sch_1):page246_i9@pure_quanta.q_res(chips)';

PART_NAME
 R1101 'Q_RES_0402LF-200,1%,1/16W,CHIP,CS12002FB25':;

SECTION_NUMBER 1
 '@T6G_MB_LIB.T6G(SCH_1):PAGE246_I69@PURE_QUANTA.Q_RES(CHIPS)':
 C_PATH='@t6g_mb_lib.t6g(sch_1):page246_i69@pure_quanta.q_res(chips)';

PART_NAME
 R988 'Q_RES_0402LF-33,5%,1/16W,CHIP,CS03302JB29':;

SECTION_NUMBER 1
 '@T6G_MB_LIB.T6G(SCH_1):PAGE246_I55@PURE_QUANTA.Q_RES(CHIPS)':
 C_PATH='@t6g_mb_lib.t6g(sch_1):page246_i55@pure_quanta.q_res(chips)';

PART_NAME
 R987 'Q_RES_0402LF-33,5%,1/16W,CHIP,CS03302JB29':;

SECTION_NUMBER 1
 '@T6G_MB_LIB.T6G(SCH_1):PAGE246_I54@PURE_QUANTA.Q_RES(CHIPS)':
 C_PATH='@t6g_mb_lib.t6g(sch_1):page246_i54@pure_quanta.q_res(chips)';

PART_NAME
 R986 'Q_RES_0402LF-33,5%,1/16W,CHIP,CS03302JB29':;

SECTION_NUMBER 1
 '@T6G_MB_LIB.T6G(SCH_1):PAGE246_I53@PURE_QUANTA.Q_RES(CHIPS)':
 C_PATH='@t6g_mb_lib.t6g(sch_1):page246_i53@pure_quanta.q_res(chips)';

PART_NAME
 R1817 'Q_RES_0402LF-0,5%,1/16W,CHIP,CS00002JB38':;

SECTION_NUMBER 1
 '@T6G_MB_LIB.T6G(SCH_1):PAGE193_I27@PURE_QUANTA.Q_RES(CHIPS)':
 C_PATH='@t6g_mb_lib.t6g(sch_1):page193_i27@pure_quanta.q_res(chips)';

PART_NAME
 R1456 'Q_RES_0402LF-49.9     ,1%  ,1/16W,CHIP,CS04992FB31':;

SECTION_NUMBER 1
 '@T6G_MB_LIB.T6G(SCH_1):PAGE193_I25@PURE_QUANTA.Q_RES(CHIPS)':
 C_PATH='@t6g_mb_lib.t6g(sch_1):page193_i25@pure_quanta.q_res(chips)';

PART_NAME
 R1455 'Q_RES_0402LF-49.9     ,1%  ,1/16W,CHIP,CS04992FB31':;

SECTION_NUMBER 1
 '@T6G_MB_LIB.T6G(SCH_1):PAGE193_I19@PURE_QUANTA.Q_RES(CHIPS)':
 C_PATH='@t6g_mb_lib.t6g(sch_1):page193_i19@pure_quanta.q_res(chips)';

PART_NAME
 R1313 'Q_RES_0402LF-33,5%,1/16W,CHIP,CS03302JB29':;

SECTION_NUMBER 1
 '@T6G_MB_LIB.T6G(SCH_1):PAGE193_I17@PURE_QUANTA.Q_RES(CHIPS)':
 C_PATH='@t6g_mb_lib.t6g(sch_1):page193_i17@pure_quanta.q_res(chips)';

PART_NAME
 R1310 'Q_RES_0402LF-33,5%,1/16W,CHIP,CS03302JB29':;

SECTION_NUMBER 1
 '@T6G_MB_LIB.T6G(SCH_1):PAGE193_I15@PURE_QUANTA.Q_RES(CHIPS)':
 C_PATH='@t6g_mb_lib.t6g(sch_1):page193_i15@pure_quanta.q_res(chips)';

PART_NAME
 R1309 'Q_RES_0402LF-33,5%,1/16W,CHIP,CS03302JB29':;

SECTION_NUMBER 1
 '@T6G_MB_LIB.T6G(SCH_1):PAGE193_I16@PURE_QUANTA.Q_RES(CHIPS)':
 C_PATH='@t6g_mb_lib.t6g(sch_1):page193_i16@pure_quanta.q_res(chips)';

PART_NAME
 R1307 'Q_RES_0402LF-33,5%,1/16W,CHIP,CS03302JB29':;

SECTION_NUMBER 1
 '@T6G_MB_LIB.T6G(SCH_1):PAGE193_I11@PURE_QUANTA.Q_RES(CHIPS)':
 C_PATH='@t6g_mb_lib.t6g(sch_1):page193_i11@pure_quanta.q_res(chips)';

PART_NAME
 R1306 'Q_RES_0402LF-33,5%,1/16W,CHIP,CS03302JB29':;

SECTION_NUMBER 1
 '@T6G_MB_LIB.T6G(SCH_1):PAGE193_I12@PURE_QUANTA.Q_RES(CHIPS)':
 C_PATH='@t6g_mb_lib.t6g(sch_1):page193_i12@pure_quanta.q_res(chips)';

PART_NAME
 R1300 'Q_RES_0402LF-33,5%,1/16W,CHIP,CS03302JB29':;

SECTION_NUMBER 1
 '@T6G_MB_LIB.T6G(SCH_1):PAGE193_I18@PURE_QUANTA.Q_RES(CHIPS)':
 C_PATH='@t6g_mb_lib.t6g(sch_1):page193_i18@pure_quanta.q_res(chips)';

PART_NAME
 R698 'Q_RES_0402LF-49.9     ,1%  ,1/16W,CHIP,CS04992FB31':;

SECTION_NUMBER 1
 '@T6G_MB_LIB.T6G(SCH_1):PAGE193_I26@PURE_QUANTA.Q_RES(CHIPS)':
 C_PATH='@t6g_mb_lib.t6g(sch_1):page193_i26@pure_quanta.q_res(chips)';

PART_NAME
 R624 'Q_RES_0402LF-10K,1%,1/16W,CHIP,TMP_QCS31002FB26':;

SECTION_NUMBER 1
 '@T6G_MB_LIB.T6G(SCH_1):PAGE189_I185@PURE_QUANTA.Q_RES(CHIPS)':
 C_PATH='@t6g_mb_lib.t6g(sch_1):page189_i185@pure_quanta.q_res(chips)';

PART_NAME
 R623 'Q_RES_0402LF-1K,5%,1/16W,EMPTY,TMP_QCS21002JB34':;

SECTION_NUMBER 1
 '@T6G_MB_LIB.T6G(SCH_1):PAGE189_I184@PURE_QUANTA.Q_RES(CHIPS)':
 C_PATH='@t6g_mb_lib.t6g(sch_1):page189_i184@pure_quanta.q_res(chips)';

PART_NAME
 R622 'Q_RES_0402LF-1K,5%,1/16W,CHIP,TMP_QCS21002JB34':;

SECTION_NUMBER 1
 '@T6G_MB_LIB.T6G(SCH_1):PAGE189_I181@PURE_QUANTA.Q_RES(CHIPS)':
 C_PATH='@t6g_mb_lib.t6g(sch_1):page189_i181@pure_quanta.q_res(chips)';

PART_NAME
 R621 'Q_RES_0402LF-1K,5%,1/16W,EMPTY,TMP_QCS21002JB34':;

SECTION_NUMBER 1
 '@T6G_MB_LIB.T6G(SCH_1):PAGE189_I180@PURE_QUANTA.Q_RES(CHIPS)':
 C_PATH='@t6g_mb_lib.t6g(sch_1):page189_i180@pure_quanta.q_res(chips)';

PART_NAME
 R620 'Q_RES_0402LF-1K,5%,1/16W,EMPTY,TMP_QCS21002JB34':;

SECTION_NUMBER 1
 '@T6G_MB_LIB.T6G(SCH_1):PAGE189_I175@PURE_QUANTA.Q_RES(CHIPS)':
 C_PATH='@t6g_mb_lib.t6g(sch_1):page189_i175@pure_quanta.q_res(chips)';

PART_NAME
 R619 'Q_RES_0402LF-10K,1%,1/16W,CHIP,TMP_QCS31002FB26':;

SECTION_NUMBER 1
 '@T6G_MB_LIB.T6G(SCH_1):PAGE189_I174@PURE_QUANTA.Q_RES(CHIPS)':
 C_PATH='@t6g_mb_lib.t6g(sch_1):page189_i174@pure_quanta.q_res(chips)';

PART_NAME
 R618 'Q_RES_0402LF-10K,1%,1/16W,CHIP,TMP_QCS31002FB26':;

SECTION_NUMBER 1
 '@T6G_MB_LIB.T6G(SCH_1):PAGE189_I201@PURE_QUANTA.Q_RES(CHIPS)':
 C_PATH='@t6g_mb_lib.t6g(sch_1):page189_i201@pure_quanta.q_res(chips)';

PART_NAME
 R617 'Q_RES_0402LF-1K,5%,1/16W,EMPTY,TMP_QCS21002JB34':;

SECTION_NUMBER 1
 '@T6G_MB_LIB.T6G(SCH_1):PAGE189_I200@PURE_QUANTA.Q_RES(CHIPS)':
 C_PATH='@t6g_mb_lib.t6g(sch_1):page189_i200@pure_quanta.q_res(chips)';

PART_NAME
 R616 'Q_RES_0402LF-10K,1%,1/16W,EMPTY,TMP_QCS31002FB26':;

SECTION_NUMBER 1
 '@T6G_MB_LIB.T6G(SCH_1):PAGE189_I196@PURE_QUANTA.Q_RES(CHIPS)':
 C_PATH='@t6g_mb_lib.t6g(sch_1):page189_i196@pure_quanta.q_res(chips)';

PART_NAME
 R615 'Q_RES_0402LF-1K,5%,1/16W,CHIP,TMP_QCS21002JB34':;

SECTION_NUMBER 1
 '@T6G_MB_LIB.T6G(SCH_1):PAGE189_I195@PURE_QUANTA.Q_RES(CHIPS)':
 C_PATH='@t6g_mb_lib.t6g(sch_1):page189_i195@pure_quanta.q_res(chips)';

PART_NAME
 R614 'Q_RES_0402LF-1K,5%,1/16W,EMPTY,TMP_QCS21002JB34':;

SECTION_NUMBER 1
 '@T6G_MB_LIB.T6G(SCH_1):PAGE189_I190@PURE_QUANTA.Q_RES(CHIPS)':
 C_PATH='@t6g_mb_lib.t6g(sch_1):page189_i190@pure_quanta.q_res(chips)';

PART_NAME
 R613 'Q_RES_0402LF-10K,1%,1/16W,CHIP,TMP_QCS31002FB26':;

SECTION_NUMBER 1
 '@T6G_MB_LIB.T6G(SCH_1):PAGE189_I189@PURE_QUANTA.Q_RES(CHIPS)':
 C_PATH='@t6g_mb_lib.t6g(sch_1):page189_i189@pure_quanta.q_res(chips)';

PART_NAME
 R612 'Q_RES_0402LF-10K,1%,1/16W,EMPTY,TMP_QCS31002FB26':;

SECTION_NUMBER 1
 '@T6G_MB_LIB.T6G(SCH_1):PAGE189_I215@PURE_QUANTA.Q_RES(CHIPS)':
 C_PATH='@t6g_mb_lib.t6g(sch_1):page189_i215@pure_quanta.q_res(chips)';

PART_NAME
 R611 'Q_RES_0402LF-1K,5%,1/16W,CHIP,TMP_QCS21002JB34':;

SECTION_NUMBER 1
 '@T6G_MB_LIB.T6G(SCH_1):PAGE189_I214@PURE_QUANTA.Q_RES(CHIPS)':
 C_PATH='@t6g_mb_lib.t6g(sch_1):page189_i214@pure_quanta.q_res(chips)';

PART_NAME
 R610 'Q_RES_0402LF-10K,1%,1/16W,CHIP,TMP_QCS31002FB26':;

SECTION_NUMBER 1
 '@T6G_MB_LIB.T6G(SCH_1):PAGE189_I211@PURE_QUANTA.Q_RES(CHIPS)':
 C_PATH='@t6g_mb_lib.t6g(sch_1):page189_i211@pure_quanta.q_res(chips)';

PART_NAME
 R609 'Q_RES_0402LF-1K,5%,1/16W,EMPTY,TMP_QCS21002JB34':;

SECTION_NUMBER 1
 '@T6G_MB_LIB.T6G(SCH_1):PAGE189_I210@PURE_QUANTA.Q_RES(CHIPS)':
 C_PATH='@t6g_mb_lib.t6g(sch_1):page189_i210@pure_quanta.q_res(chips)';

PART_NAME
 R608 'Q_RES_0402LF-10K,1%,1/16W,CHIP,TMP_QCS31002FB26':;

SECTION_NUMBER 1
 '@T6G_MB_LIB.T6G(SCH_1):PAGE189_I207@PURE_QUANTA.Q_RES(CHIPS)':
 C_PATH='@t6g_mb_lib.t6g(sch_1):page189_i207@pure_quanta.q_res(chips)';

PART_NAME
 R607 'Q_RES_0402LF-1K,5%,1/16W,EMPTY,TMP_QCS21002JB34':;

SECTION_NUMBER 1
 '@T6G_MB_LIB.T6G(SCH_1):PAGE189_I206@PURE_QUANTA.Q_RES(CHIPS)':
 C_PATH='@t6g_mb_lib.t6g(sch_1):page189_i206@pure_quanta.q_res(chips)';

PART_NAME
 R2817 'Q_RES_0402LF-33,5%,1/16W,CHIP,CS03302JB29':
;

SECTION_NUMBER 1
 '@T6G_MB_LIB.T6G(SCH_1):PAGE101_I33@PURE_QUANTA.Q_RES(CHIPS)':
 C_PATH='@t6g_mb_lib.t6g(sch_1):page101_i33@pure_quanta.q_res(chips)';

PART_NAME
 R2816 'Q_RES_0402LF-33,5%,1/16W,CHIP,CS03302JB29':
;

SECTION_NUMBER 1
 '@T6G_MB_LIB.T6G(SCH_1):PAGE101_I59@PURE_QUANTA.Q_RES(CHIPS)':
 C_PATH='@t6g_mb_lib.t6g(sch_1):page101_i59@pure_quanta.q_res(chips)';

PART_NAME
 R2815 'Q_RES_0402LF-33,5%,1/16W,CHIP,CS03302JB29':
;

SECTION_NUMBER 1
 '@T6G_MB_LIB.T6G(SCH_1):PAGE101_I60@PURE_QUANTA.Q_RES(CHIPS)':
 C_PATH='@t6g_mb_lib.t6g(sch_1):page101_i60@pure_quanta.q_res(chips)';

PART_NAME
 R2814 'Q_RES_0402LF-33,5%,1/16W,CHIP,CS03302JB29':
;

SECTION_NUMBER 1
 '@T6G_MB_LIB.T6G(SCH_1):PAGE101_I104@PURE_QUANTA.Q_RES(CHIPS)':
 C_PATH='@t6g_mb_lib.t6g(sch_1):page101_i104@pure_quanta.q_res(chips)';

PART_NAME
 R2813 'Q_RES_0402LF-33,5%,1/16W,CHIP,CS03302JB29':
;

SECTION_NUMBER 1
 '@T6G_MB_LIB.T6G(SCH_1):PAGE101_I61@PURE_QUANTA.Q_RES(CHIPS)':
 C_PATH='@t6g_mb_lib.t6g(sch_1):page101_i61@pure_quanta.q_res(chips)';

PART_NAME
 R2812 'Q_RES_0402LF-33,5%,1/16W,CHIP,CS03302JB29':
;

SECTION_NUMBER 1
 '@T6G_MB_LIB.T6G(SCH_1):PAGE101_I62@PURE_QUANTA.Q_RES(CHIPS)':
 C_PATH='@t6g_mb_lib.t6g(sch_1):page101_i62@pure_quanta.q_res(chips)';

PART_NAME
 R2811 'Q_RES_0402LF-33,5%,1/16W,CHIP,CS03302JB29':
;

SECTION_NUMBER 1
 '@T6G_MB_LIB.T6G(SCH_1):PAGE101_I63@PURE_QUANTA.Q_RES(CHIPS)':
 C_PATH='@t6g_mb_lib.t6g(sch_1):page101_i63@pure_quanta.q_res(chips)';

PART_NAME
 R2810 'Q_RES_0402LF-33,5%,1/16W,CHIP,CS03302JB29':
;

SECTION_NUMBER 1
 '@T6G_MB_LIB.T6G(SCH_1):PAGE101_I64@PURE_QUANTA.Q_RES(CHIPS)':
 C_PATH='@t6g_mb_lib.t6g(sch_1):page101_i64@pure_quanta.q_res(chips)';

PART_NAME
 R2809 'Q_RES_0402LF-33,5%,1/16W,CHIP,CS03302JB29':
;

SECTION_NUMBER 1
 '@T6G_MB_LIB.T6G(SCH_1):PAGE101_I65@PURE_QUANTA.Q_RES(CHIPS)':
 C_PATH='@t6g_mb_lib.t6g(sch_1):page101_i65@pure_quanta.q_res(chips)';

PART_NAME
 R2808 'Q_RES_0402LF-33,5%,1/16W,CHIP,CS03302JB29':
;

SECTION_NUMBER 1
 '@T6G_MB_LIB.T6G(SCH_1):PAGE101_I66@PURE_QUANTA.Q_RES(CHIPS)':
 C_PATH='@t6g_mb_lib.t6g(sch_1):page101_i66@pure_quanta.q_res(chips)';

PART_NAME
 R2807 'Q_RES_0402LF-33,5%,1/16W,CHIP,CS03302JB29':
;

SECTION_NUMBER 1
 '@T6G_MB_LIB.T6G(SCH_1):PAGE101_I71@PURE_QUANTA.Q_RES(CHIPS)':
 C_PATH='@t6g_mb_lib.t6g(sch_1):page101_i71@pure_quanta.q_res(chips)';

PART_NAME
 R2806 'Q_RES_0402LF-33,5%,1/16W,CHIP,CS03302JB29':
;

SECTION_NUMBER 1
 '@T6G_MB_LIB.T6G(SCH_1):PAGE101_I72@PURE_QUANTA.Q_RES(CHIPS)':
 C_PATH='@t6g_mb_lib.t6g(sch_1):page101_i72@pure_quanta.q_res(chips)';

PART_NAME
 R2805 'Q_RES_0402LF-33,5%,1/16W,CHIP,CS03302JB29':
;

SECTION_NUMBER 1
 '@T6G_MB_LIB.T6G(SCH_1):PAGE101_I73@PURE_QUANTA.Q_RES(CHIPS)':
 C_PATH='@t6g_mb_lib.t6g(sch_1):page101_i73@pure_quanta.q_res(chips)';

PART_NAME
 R2804 'Q_RES_0402LF-33,5%,1/16W,CHIP,CS03302JB29':
;

SECTION_NUMBER 1
 '@T6G_MB_LIB.T6G(SCH_1):PAGE101_I74@PURE_QUANTA.Q_RES(CHIPS)':
 C_PATH='@t6g_mb_lib.t6g(sch_1):page101_i74@pure_quanta.q_res(chips)';

PART_NAME
 R2803 'Q_RES_0402LF-33,5%,1/16W,CHIP,CS03302JB29':
;

SECTION_NUMBER 1
 '@T6G_MB_LIB.T6G(SCH_1):PAGE101_I75@PURE_QUANTA.Q_RES(CHIPS)':
 C_PATH='@t6g_mb_lib.t6g(sch_1):page101_i75@pure_quanta.q_res(chips)';

PART_NAME
 R2802 'Q_RES_0402LF-33,5%,1/16W,CHIP,CS03302JB29':
;

SECTION_NUMBER 1
 '@T6G_MB_LIB.T6G(SCH_1):PAGE101_I76@PURE_QUANTA.Q_RES(CHIPS)':
 C_PATH='@t6g_mb_lib.t6g(sch_1):page101_i76@pure_quanta.q_res(chips)';

PART_NAME
 R2801 'Q_RES_0402LF-33,5%,1/16W,CHIP,CS03302JB29':
;

SECTION_NUMBER 1
 '@T6G_MB_LIB.T6G(SCH_1):PAGE101_I106@PURE_QUANTA.Q_RES(CHIPS)':
 C_PATH='@t6g_mb_lib.t6g(sch_1):page101_i106@pure_quanta.q_res(chips)';

PART_NAME
 R2800 'Q_RES_0402LF-33,5%,1/16W,CHIP,CS03302JB29':
;

SECTION_NUMBER 1
 '@T6G_MB_LIB.T6G(SCH_1):PAGE101_I12@PURE_QUANTA.Q_RES(CHIPS)':
 C_PATH='@t6g_mb_lib.t6g(sch_1):page101_i12@pure_quanta.q_res(chips)';

PART_NAME
 R2799 'Q_RES_0402LF-33,5%,1/16W,CHIP,CS03302JB29':
;

SECTION_NUMBER 1
 '@T6G_MB_LIB.T6G(SCH_1):PAGE101_I13@PURE_QUANTA.Q_RES(CHIPS)':
 C_PATH='@t6g_mb_lib.t6g(sch_1):page101_i13@pure_quanta.q_res(chips)';

PART_NAME
 R2798 'Q_RES_0402LF-33,5%,1/16W,CHIP,CS03302JB29':
;

SECTION_NUMBER 1
 '@T6G_MB_LIB.T6G(SCH_1):PAGE101_I14@PURE_QUANTA.Q_RES(CHIPS)':
 C_PATH='@t6g_mb_lib.t6g(sch_1):page101_i14@pure_quanta.q_res(chips)';

PART_NAME
 R2797 'Q_RES_0402LF-33,5%,1/16W,CHIP,CS03302JB29':
;

SECTION_NUMBER 1
 '@T6G_MB_LIB.T6G(SCH_1):PAGE101_I105@PURE_QUANTA.Q_RES(CHIPS)':
 C_PATH='@t6g_mb_lib.t6g(sch_1):page101_i105@pure_quanta.q_res(chips)';

PART_NAME
 R2796 'Q_RES_0402LF-33,5%,1/16W,CHIP,CS03302JB29':
;

SECTION_NUMBER 1
 '@T6G_MB_LIB.T6G(SCH_1):PAGE101_I15@PURE_QUANTA.Q_RES(CHIPS)':
 C_PATH='@t6g_mb_lib.t6g(sch_1):page101_i15@pure_quanta.q_res(chips)';

PART_NAME
 R2795 'Q_RES_0402LF-33,5%,1/16W,CHIP,CS03302JB29':
;

SECTION_NUMBER 1
 '@T6G_MB_LIB.T6G(SCH_1):PAGE101_I16@PURE_QUANTA.Q_RES(CHIPS)':
 C_PATH='@t6g_mb_lib.t6g(sch_1):page101_i16@pure_quanta.q_res(chips)';

PART_NAME
 R2794 'Q_RES_0402LF-33,5%,1/16W,CHIP,CS03302JB29':
;

SECTION_NUMBER 1
 '@T6G_MB_LIB.T6G(SCH_1):PAGE101_I17@PURE_QUANTA.Q_RES(CHIPS)':
 C_PATH='@t6g_mb_lib.t6g(sch_1):page101_i17@pure_quanta.q_res(chips)';

PART_NAME
 R2793 'Q_RES_0402LF-33,5%,1/16W,CHIP,CS03302JB29':
;

SECTION_NUMBER 1
 '@T6G_MB_LIB.T6G(SCH_1):PAGE101_I18@PURE_QUANTA.Q_RES(CHIPS)':
 C_PATH='@t6g_mb_lib.t6g(sch_1):page101_i18@pure_quanta.q_res(chips)';

PART_NAME
 R2792 'Q_RES_0402LF-33,5%,1/16W,CHIP,CS03302JB29':
;

SECTION_NUMBER 1
 '@T6G_MB_LIB.T6G(SCH_1):PAGE101_I19@PURE_QUANTA.Q_RES(CHIPS)':
 C_PATH='@t6g_mb_lib.t6g(sch_1):page101_i19@pure_quanta.q_res(chips)';

PART_NAME
 R2791 'Q_RES_0402LF-33,5%,1/16W,CHIP,CS03302JB29':
;

SECTION_NUMBER 1
 '@T6G_MB_LIB.T6G(SCH_1):PAGE101_I20@PURE_QUANTA.Q_RES(CHIPS)':
 C_PATH='@t6g_mb_lib.t6g(sch_1):page101_i20@pure_quanta.q_res(chips)';

PART_NAME
 R2790 'Q_RES_0402LF-33,5%,1/16W,CHIP,CS03302JB29':
;

SECTION_NUMBER 1
 '@T6G_MB_LIB.T6G(SCH_1):PAGE101_I26@PURE_QUANTA.Q_RES(CHIPS)':
 C_PATH='@t6g_mb_lib.t6g(sch_1):page101_i26@pure_quanta.q_res(chips)';

PART_NAME
 R2789 'Q_RES_0402LF-33,5%,1/16W,CHIP,CS03302JB29':
;

SECTION_NUMBER 1
 '@T6G_MB_LIB.T6G(SCH_1):PAGE101_I27@PURE_QUANTA.Q_RES(CHIPS)':
 C_PATH='@t6g_mb_lib.t6g(sch_1):page101_i27@pure_quanta.q_res(chips)';

PART_NAME
 R2788 'Q_RES_0402LF-33,5%,1/16W,CHIP,CS03302JB29':
;

SECTION_NUMBER 1
 '@T6G_MB_LIB.T6G(SCH_1):PAGE101_I28@PURE_QUANTA.Q_RES(CHIPS)':
 C_PATH='@t6g_mb_lib.t6g(sch_1):page101_i28@pure_quanta.q_res(chips)';

PART_NAME
 R1667 'Q_RES_0402LF-33,5%,1/16W,CHIP,CS03302JB29':
;

SECTION_NUMBER 1
 '@T6G_MB_LIB.T6G(SCH_1):PAGE101_I29@PURE_QUANTA.Q_RES(CHIPS)':
 C_PATH='@t6g_mb_lib.t6g(sch_1):page101_i29@pure_quanta.q_res(chips)';

PART_NAME
 R1659 'Q_RES_0402LF-33,5%,1/16W,CHIP,CS03302JB29':
;

SECTION_NUMBER 1
 '@T6G_MB_LIB.T6G(SCH_1):PAGE101_I30@PURE_QUANTA.Q_RES(CHIPS)':
 C_PATH='@t6g_mb_lib.t6g(sch_1):page101_i30@pure_quanta.q_res(chips)';

PART_NAME
 R766 'Q_RES_0402LF-1K,1%,1/16W,CHIP,CS21002FB06':
;

SECTION_NUMBER 1
 '@T6G_MB_LIB.T6G(SCH_1):PAGE101_I87@PURE_QUANTA.Q_RES(CHIPS)':
 C_PATH='@t6g_mb_lib.t6g(sch_1):page101_i87@pure_quanta.q_res(chips)';

PART_NAME
 R765 'Q_RES_0402LF-1K,1%,1/16W,CHIP,CS21002FB06':
;

SECTION_NUMBER 1
 '@T6G_MB_LIB.T6G(SCH_1):PAGE101_I98@PURE_QUANTA.Q_RES(CHIPS)':
 C_PATH='@t6g_mb_lib.t6g(sch_1):page101_i98@pure_quanta.q_res(chips)';

PART_NAME
 R588 'Q_RES_0402LF-1K,1%,1/16W,CHIP,CS21002FB06':
;

SECTION_NUMBER 1
 '@T6G_MB_LIB.T6G(SCH_1):PAGE101_I84@PURE_QUANTA.Q_RES(CHIPS)':
 C_PATH='@t6g_mb_lib.t6g(sch_1):page101_i84@pure_quanta.q_res(chips)';

PART_NAME
 R587 'Q_RES_0402LF-1K,1%,1/16W,CHIP,CS21002FB06':
;

SECTION_NUMBER 1
 '@T6G_MB_LIB.T6G(SCH_1):PAGE101_I85@PURE_QUANTA.Q_RES(CHIPS)':
 C_PATH='@t6g_mb_lib.t6g(sch_1):page101_i85@pure_quanta.q_res(chips)';

PART_NAME
 R586 'Q_RES_0402LF-1K,1%,1/16W,CHIP,CS21002FB06':
;

SECTION_NUMBER 1
 '@T6G_MB_LIB.T6G(SCH_1):PAGE101_I86@PURE_QUANTA.Q_RES(CHIPS)':
 C_PATH='@t6g_mb_lib.t6g(sch_1):page101_i86@pure_quanta.q_res(chips)';

PART_NAME
 R585 'Q_RES_0402LF-1K,1%,1/16W,CHIP,CS21002FB06':
;

SECTION_NUMBER 1
 '@T6G_MB_LIB.T6G(SCH_1):PAGE101_I94@PURE_QUANTA.Q_RES(CHIPS)':
 C_PATH='@t6g_mb_lib.t6g(sch_1):page101_i94@pure_quanta.q_res(chips)';

PART_NAME
 R584 'Q_RES_0402LF-1K,1%,1/16W,CHIP,CS21002FB06':
;

SECTION_NUMBER 1
 '@T6G_MB_LIB.T6G(SCH_1):PAGE101_I95@PURE_QUANTA.Q_RES(CHIPS)':
 C_PATH='@t6g_mb_lib.t6g(sch_1):page101_i95@pure_quanta.q_res(chips)';

PART_NAME
 R583 'Q_RES_0402LF-1K,1%,1/16W,CHIP,CS21002FB06':
;

SECTION_NUMBER 1
 '@T6G_MB_LIB.T6G(SCH_1):PAGE101_I96@PURE_QUANTA.Q_RES(CHIPS)':
 C_PATH='@t6g_mb_lib.t6g(sch_1):page101_i96@pure_quanta.q_res(chips)';

PART_NAME
 R3872 'Q_RES_0402LF-4.7K,5%,1/16W,CHIP,TMP_QCS24702JB38':
;

SECTION_NUMBER 1
 '@T6G_MB_LIB.T6G(SCH_1):PAGE254_I29@PURE_QUANTA.Q_RES(CHIPS)':
 C_PATH='@t6g_mb_lib.t6g(sch_1):page254_i29@pure_quanta.q_res(chips)';

PART_NAME
 R3871 'Q_RES_0402LF-4.7K,5%,1/16W,CHIP,TMP_QCS24702JB38':
;

SECTION_NUMBER 1
 '@T6G_MB_LIB.T6G(SCH_1):PAGE254_I27@PURE_QUANTA.Q_RES(CHIPS)':
 C_PATH='@t6g_mb_lib.t6g(sch_1):page254_i27@pure_quanta.q_res(chips)';

PART_NAME
 R1395 'Q_RES_0402LF-33,5%,1/16W,CHIP,CS03302JB29':;

SECTION_NUMBER 1
 '@T6G_MB_LIB.T6G(SCH_1):PAGE254_I16@PURE_QUANTA.Q_RES(CHIPS)':
 C_PATH='@t6g_mb_lib.t6g(sch_1):page254_i16@pure_quanta.q_res(chips)';

PART_NAME
 R1299 'Q_RES_0402LF-33,5%,1/16W,CHIP,CS03302JB29':;

SECTION_NUMBER 1
 '@T6G_MB_LIB.T6G(SCH_1):PAGE254_I14@PURE_QUANTA.Q_RES(CHIPS)':
 C_PATH='@t6g_mb_lib.t6g(sch_1):page254_i14@pure_quanta.q_res(chips)';

PART_NAME
 R1298 'Q_RES_0402LF-33,5%,1/16W,CHIP,CS03302JB29':;

SECTION_NUMBER 1
 '@T6G_MB_LIB.T6G(SCH_1):PAGE254_I13@PURE_QUANTA.Q_RES(CHIPS)':
 C_PATH='@t6g_mb_lib.t6g(sch_1):page254_i13@pure_quanta.q_res(chips)';

PART_NAME
 R1296 'Q_RES_0402LF-33,5%,1/16W,CHIP,CS03302JB29':;

SECTION_NUMBER 1
 '@T6G_MB_LIB.T6G(SCH_1):PAGE254_I8@PURE_QUANTA.Q_RES(CHIPS)':
 C_PATH='@t6g_mb_lib.t6g(sch_1):page254_i8@pure_quanta.q_res(chips)';

PART_NAME
 R1295 'Q_RES_0402LF-33,5%,1/16W,CHIP,CS03302JB29':;

SECTION_NUMBER 1
 '@T6G_MB_LIB.T6G(SCH_1):PAGE254_I7@PURE_QUANTA.Q_RES(CHIPS)':
 C_PATH='@t6g_mb_lib.t6g(sch_1):page254_i7@pure_quanta.q_res(chips)';

PART_NAME
 R917 'Q_RES_0402LF-33,5%,1/16W,CHIP,CS03302JB29':;

SECTION_NUMBER 1
 '@T6G_MB_LIB.T6G(SCH_1):PAGE254_I15@PURE_QUANTA.Q_RES(CHIPS)':
 C_PATH='@t6g_mb_lib.t6g(sch_1):page254_i15@pure_quanta.q_res(chips)';

PART_NAME
 R501 'Q_RES_0402LF-33,5%,1/16W,CHIP,CS03302JB29':;

SECTION_NUMBER 1
 '@T6G_MB_LIB.T6G(SCH_1):PAGE254_I5@PURE_QUANTA.Q_RES(CHIPS)':
 C_PATH='@t6g_mb_lib.t6g(sch_1):page254_i5@pure_quanta.q_res(chips)';

PART_NAME
 R500 'Q_RES_0402LF-33,5%,1/16W,CHIP,CS03302JB29':;

SECTION_NUMBER 1
 '@T6G_MB_LIB.T6G(SCH_1):PAGE254_I6@PURE_QUANTA.Q_RES(CHIPS)':
 C_PATH='@t6g_mb_lib.t6g(sch_1):page254_i6@pure_quanta.q_res(chips)';

PART_NAME
 R1736 'Q_RES_0402LF-0,5%,1/16W,CHIP,CS00002JB38':;

SECTION_NUMBER 1
 '@T6G_MB_LIB.T6G(SCH_1):PAGE179_I297@PURE_QUANTA.Q_RES(CHIPS)':
 C_PATH='@t6g_mb_lib.t6g(sch_1):page179_i297@pure_quanta.q_res(chips)';

PART_NAME
 R1676 'Q_RES_0402LF-1K,1%,1/16W,CHIP,TMP_QCS21002FB24':;

SECTION_NUMBER 1
 '@T6G_MB_LIB.T6G(SCH_1):PAGE179_I260@PURE_QUANTA.Q_RES(CHIPS)':
 C_PATH='@t6g_mb_lib.t6g(sch_1):page179_i260@pure_quanta.q_res(chips)';

PART_NAME
 R1675 'Q_RES_0402LF-2.49K,1%,1/16W,EMPTY,TMP_QCS22492FB22':;

SECTION_NUMBER 1
 '@T6G_MB_LIB.T6G(SCH_1):PAGE179_I259@PURE_QUANTA.Q_RES(CHIPS)':
 C_PATH='@t6g_mb_lib.t6g(sch_1):page179_i259@pure_quanta.q_res(chips)';

PART_NAME
 R1591 'Q_RES_0402LF-200,1%,1/16W,EMPTY,CS12002FB25':;

SECTION_NUMBER 1
 '@T6G_MB_LIB.T6G(SCH_1):PAGE179_I239@PURE_QUANTA.Q_RES(CHIPS)':
 C_PATH='@t6g_mb_lib.t6g(sch_1):page179_i239@pure_quanta.q_res(chips)';

PART_NAME
 R1590 'Q_RES_0402LF-200,1%,1/16W,EMPTY,CS12002FB25':;

SECTION_NUMBER 1
 '@T6G_MB_LIB.T6G(SCH_1):PAGE179_I242@PURE_QUANTA.Q_RES(CHIPS)':
 C_PATH='@t6g_mb_lib.t6g(sch_1):page179_i242@pure_quanta.q_res(chips)';

PART_NAME
 R1589 'Q_RES_0402LF-49.9     ,1%  ,1/16W,CHIP,CS04992FB31':;

SECTION_NUMBER 1
 '@T6G_MB_LIB.T6G(SCH_1):PAGE179_I248@PURE_QUANTA.Q_RES(CHIPS)':
 C_PATH='@t6g_mb_lib.t6g(sch_1):page179_i248@pure_quanta.q_res(chips)';

PART_NAME
 R1588 'Q_RES_0402LF-100,1%,1/16W,CHIP,TMP_QCS11002FB22':;

SECTION_NUMBER 1
 '@T6G_MB_LIB.T6G(SCH_1):PAGE179_I247@PURE_QUANTA.Q_RES(CHIPS)':
 C_PATH='@t6g_mb_lib.t6g(sch_1):page179_i247@pure_quanta.q_res(chips)';

PART_NAME
 R1586 'Q_RES_0402LF-1K,1%,1/16W,CHIP,TMP_QCS21002FB24':;

SECTION_NUMBER 1
 '@T6G_MB_LIB.T6G(SCH_1):PAGE179_I256@PURE_QUANTA.Q_RES(CHIPS)':
 C_PATH='@t6g_mb_lib.t6g(sch_1):page179_i256@pure_quanta.q_res(chips)';

PART_NAME
 R1585 'Q_RES_0402LF-75,1%,1/16W,EMPTY,CS07502FB17':;

SECTION_NUMBER 1
 '@T6G_MB_LIB.T6G(SCH_1):PAGE179_I284@PURE_QUANTA.Q_RES(CHIPS)':
 C_PATH='@t6g_mb_lib.t6g(sch_1):page179_i284@pure_quanta.q_res(chips)';

PART_NAME
 R1579 'Q_RES_0402LF-100,1%,1/16W,CHIP,TMP_QCS11002FB22':;

SECTION_NUMBER 1
 '@T6G_MB_LIB.T6G(SCH_1):PAGE179_I286@PURE_QUANTA.Q_RES(CHIPS)':
 C_PATH='@t6g_mb_lib.t6g(sch_1):page179_i286@pure_quanta.q_res(chips)';

PART_NAME
 R1578 'Q_RES_0402LF-1K,5%,1/16W,EMPTY,TMP_QCS21002JB34':;

SECTION_NUMBER 1
 '@T6G_MB_LIB.T6G(SCH_1):PAGE179_I279@PURE_QUANTA.Q_RES(CHIPS)':
 C_PATH='@t6g_mb_lib.t6g(sch_1):page179_i279@pure_quanta.q_res(chips)';

PART_NAME
 R1577 'Q_RES_0402LF-10K,1%,1/16W,CHIP,TMP_QCS31002FB26':;

SECTION_NUMBER 1
 '@T6G_MB_LIB.T6G(SCH_1):PAGE179_I283@PURE_QUANTA.Q_RES(CHIPS)':
 C_PATH='@t6g_mb_lib.t6g(sch_1):page179_i283@pure_quanta.q_res(chips)';

PART_NAME
 R697 'Q_RES_0402LF-33,5%,1/16W,CHIP,CS03302JB29':;

SECTION_NUMBER 1
 '@T6G_MB_LIB.T6G(SCH_1):PAGE179_I292@PURE_QUANTA.Q_RES(CHIPS)':
 C_PATH='@t6g_mb_lib.t6g(sch_1):page179_i292@pure_quanta.q_res(chips)';

PART_NAME
 R696 'Q_RES_0402LF-4.7K,5%,1/16W,CHIP,TMP_QCS24702JB38':;

SECTION_NUMBER 1
 '@T6G_MB_LIB.T6G(SCH_1):PAGE179_I265@PURE_QUANTA.Q_RES(CHIPS)':
 C_PATH='@t6g_mb_lib.t6g(sch_1):page179_i265@pure_quanta.q_res(chips)';

PART_NAME
 R453 'Q_RES_0402LF-10K,1%,1/16W,CHIP,TMP_QCS31002FB26':;

SECTION_NUMBER 1
 '@T6G_MB_LIB.T6G(SCH_1):PAGE179_I281@PURE_QUANTA.Q_RES(CHIPS)':
 C_PATH='@t6g_mb_lib.t6g(sch_1):page179_i281@pure_quanta.q_res(chips)';

PART_NAME
 R2317 'Q_RES_0402LF-0,5%,1/16W,CHIP,CS00002JB38':;

SECTION_NUMBER 1
 '@T6G_MB_LIB.T6G(SCH_1):PAGE238_I121@PURE_QUANTA.Q_RES(CHIPS)':
 C_PATH='@t6g_mb_lib.t6g(sch_1):page238_i121@pure_quanta.q_res(chips)';

PART_NAME
 R1606 'Q_RES_0402LF-0,5%,1/16W,CHIP,CS00002JB38':;

SECTION_NUMBER 1
 '@T6G_MB_LIB.T6G(SCH_1):PAGE238_I119@PURE_QUANTA.Q_RES(CHIPS)':
 C_PATH='@t6g_mb_lib.t6g(sch_1):page238_i119@pure_quanta.q_res(chips)';

PART_NAME
 R1556 'Q_RES_0402LF-0,5%,1/16W,EMPTY,CS00002JB38':;

SECTION_NUMBER 1
 '@T6G_MB_LIB.T6G(SCH_1):PAGE238_I120@PURE_QUANTA.Q_RES(CHIPS)':
 C_PATH='@t6g_mb_lib.t6g(sch_1):page238_i120@pure_quanta.q_res(chips)';

PART_NAME
 R1551 'Q_RES_0402LF-4.7K,1%,1/16W,EMPTY,CS24702FB10':;

SECTION_NUMBER 1
 '@T6G_MB_LIB.T6G(SCH_1):PAGE238_I110@PURE_QUANTA.Q_RES(CHIPS)':
 C_PATH='@t6g_mb_lib.t6g(sch_1):page238_i110@pure_quanta.q_res(chips)';

PART_NAME
 R1547 'Q_RES_0402LF-0,5%,1/16W,CHIP,CS00002JB38':;

SECTION_NUMBER 1
 '@T6G_MB_LIB.T6G(SCH_1):PAGE238_I118@PURE_QUANTA.Q_RES(CHIPS)':
 C_PATH='@t6g_mb_lib.t6g(sch_1):page238_i118@pure_quanta.q_res(chips)';

PART_NAME
 R1467 'Q_RES_0402LF-4.7K,1%,1/16W,EMPTY,CS24702FB10':;

SECTION_NUMBER 1
 '@T6G_MB_LIB.T6G(SCH_1):PAGE238_I113@PURE_QUANTA.Q_RES(CHIPS)':
 C_PATH='@t6g_mb_lib.t6g(sch_1):page238_i113@pure_quanta.q_res(chips)';

PART_NAME
 R1466 'Q_RES_0402LF-1K,1%,1/16W,EMPTY,TMP_QCS21002FB24':;

SECTION_NUMBER 1
 '@T6G_MB_LIB.T6G(SCH_1):PAGE238_I148@PURE_QUANTA.Q_RES(CHIPS)':
 C_PATH='@t6g_mb_lib.t6g(sch_1):page238_i148@pure_quanta.q_res(chips)';

PART_NAME
 R1465 'Q_RES_0402LF-10K,1%,1/16W,EMPTY,TMP_QCS31002FB26':;

SECTION_NUMBER 1
 '@T6G_MB_LIB.T6G(SCH_1):PAGE238_I147@PURE_QUANTA.Q_RES(CHIPS)':
 C_PATH='@t6g_mb_lib.t6g(sch_1):page238_i147@pure_quanta.q_res(chips)';

PART_NAME
 R446 'Q_RES_0402LF-0,5%,1/16W,CHIP,CS00002JB38':;

SECTION_NUMBER 1
 '@T6G_MB_LIB.T6G(SCH_1):PAGE238_I152@PURE_QUANTA.Q_RES(CHIPS)':
 C_PATH='@t6g_mb_lib.t6g(sch_1):page238_i152@pure_quanta.q_res(chips)';

PART_NAME
 R476 'Q_RES_0402LF-0,5%,1/16W,CHIP,CS00002JB38':;

SECTION_NUMBER 1
 '@T6G_MB_LIB.T6G(SCH_1):PAGE212_I122@PURE_QUANTA.Q_RES(CHIPS)':
 C_PATH='@t6g_mb_lib.t6g(sch_1):page212_i122@pure_quanta.q_res(chips)';

PART_NAME
 R474 'Q_RES_0402LF-0,5%,1/16W,CHIP,CS00002JB38':;

SECTION_NUMBER 1
 '@T6G_MB_LIB.T6G(SCH_1):PAGE212_I124@PURE_QUANTA.Q_RES(CHIPS)':
 C_PATH='@t6g_mb_lib.t6g(sch_1):page212_i124@pure_quanta.q_res(chips)';

PART_NAME
 R473 'Q_RES_0402LF-0,5%,1/16W,CHIP,CS00002JB38':;

SECTION_NUMBER 1
 '@T6G_MB_LIB.T6G(SCH_1):PAGE212_I123@PURE_QUANTA.Q_RES(CHIPS)':
 C_PATH='@t6g_mb_lib.t6g(sch_1):page212_i123@pure_quanta.q_res(chips)';

PART_NAME
 R472 'Q_RES_0402LF-0,5%,1/16W,CHIP,CS00002JB38':;

SECTION_NUMBER 1
 '@T6G_MB_LIB.T6G(SCH_1):PAGE212_I126@PURE_QUANTA.Q_RES(CHIPS)':
 C_PATH='@t6g_mb_lib.t6g(sch_1):page212_i126@pure_quanta.q_res(chips)';

PART_NAME
 R469 'Q_RES_0402LF-0,5%,1/16W,CHIP,CS00002JB38':;

SECTION_NUMBER 1
 '@T6G_MB_LIB.T6G(SCH_1):PAGE212_I125@PURE_QUANTA.Q_RES(CHIPS)':
 C_PATH='@t6g_mb_lib.t6g(sch_1):page212_i125@pure_quanta.q_res(chips)';

PART_NAME
 R468 'Q_RES_0402LF-0,5%,1/16W,CHIP,CS00002JB38':;

SECTION_NUMBER 1
 '@T6G_MB_LIB.T6G(SCH_1):PAGE212_I127@PURE_QUANTA.Q_RES(CHIPS)':
 C_PATH='@t6g_mb_lib.t6g(sch_1):page212_i127@pure_quanta.q_res(chips)';

PART_NAME
 R462 'Q_RES_0402LF-0,5%,1/16W,CHIP,CS00002JB38':;

SECTION_NUMBER 1
 '@T6G_MB_LIB.T6G(SCH_1):PAGE212_I128@PURE_QUANTA.Q_RES(CHIPS)':
 C_PATH='@t6g_mb_lib.t6g(sch_1):page212_i128@pure_quanta.q_res(chips)';

PART_NAME
 R461 'Q_RES_0402LF-0,5%,1/16W,CHIP,CS00002JB38':;

SECTION_NUMBER 1
 '@T6G_MB_LIB.T6G(SCH_1):PAGE212_I129@PURE_QUANTA.Q_RES(CHIPS)':
 C_PATH='@t6g_mb_lib.t6g(sch_1):page212_i129@pure_quanta.q_res(chips)';

PART_NAME
 R459 'Q_RES_0402LF-0,5%,1/16W,CHIP,CS00002JB38':;

SECTION_NUMBER 1
 '@T6G_MB_LIB.T6G(SCH_1):PAGE212_I131@PURE_QUANTA.Q_RES(CHIPS)':
 C_PATH='@t6g_mb_lib.t6g(sch_1):page212_i131@pure_quanta.q_res(chips)';

PART_NAME
 R447 'Q_RES_0402LF-0,5%,1/16W,CHIP,CS00002JB38':;

SECTION_NUMBER 1
 '@T6G_MB_LIB.T6G(SCH_1):PAGE212_I130@PURE_QUANTA.Q_RES(CHIPS)':
 C_PATH='@t6g_mb_lib.t6g(sch_1):page212_i130@pure_quanta.q_res(chips)';

PART_NAME
 R444 'Q_RES_0402LF-0,5%,1/16W,CHIP,CS00002JB38':;

SECTION_NUMBER 1
 '@T6G_MB_LIB.T6G(SCH_1):PAGE212_I132@PURE_QUANTA.Q_RES(CHIPS)':
 C_PATH='@t6g_mb_lib.t6g(sch_1):page212_i132@pure_quanta.q_res(chips)';

PART_NAME
 R443 'Q_RES_0402LF-0,5%,1/16W,CHIP,CS00002JB38':;

SECTION_NUMBER 1
 '@T6G_MB_LIB.T6G(SCH_1):PAGE212_I134@PURE_QUANTA.Q_RES(CHIPS)':
 C_PATH='@t6g_mb_lib.t6g(sch_1):page212_i134@pure_quanta.q_res(chips)';

PART_NAME
 R442 'Q_RES_0402LF-0,5%,1/16W,CHIP,CS00002JB38':;

SECTION_NUMBER 1
 '@T6G_MB_LIB.T6G(SCH_1):PAGE212_I133@PURE_QUANTA.Q_RES(CHIPS)':
 C_PATH='@t6g_mb_lib.t6g(sch_1):page212_i133@pure_quanta.q_res(chips)';

PART_NAME
 R441 'Q_RES_0402LF-0,5%,1/16W,CHIP,CS00002JB38':;

SECTION_NUMBER 1
 '@T6G_MB_LIB.T6G(SCH_1):PAGE212_I135@PURE_QUANTA.Q_RES(CHIPS)':
 C_PATH='@t6g_mb_lib.t6g(sch_1):page212_i135@pure_quanta.q_res(chips)';

PART_NAME
 R437 'Q_RES_0402LF-0,5%,1/16W,CHIP,CS00002JB38':;

SECTION_NUMBER 1
 '@T6G_MB_LIB.T6G(SCH_1):PAGE212_I136@PURE_QUANTA.Q_RES(CHIPS)':
 C_PATH='@t6g_mb_lib.t6g(sch_1):page212_i136@pure_quanta.q_res(chips)';

PART_NAME
 R436 'Q_RES_0402LF-0,5%,1/16W,CHIP,CS00002JB38':;

SECTION_NUMBER 1
 '@T6G_MB_LIB.T6G(SCH_1):PAGE212_I137@PURE_QUANTA.Q_RES(CHIPS)':
 C_PATH='@t6g_mb_lib.t6g(sch_1):page212_i137@pure_quanta.q_res(chips)';

PART_NAME
 R435 'Q_RES_0402LF-0,5%,1/16W,CHIP,CS00002JB38':;

SECTION_NUMBER 1
 '@T6G_MB_LIB.T6G(SCH_1):PAGE212_I138@PURE_QUANTA.Q_RES(CHIPS)':
 C_PATH='@t6g_mb_lib.t6g(sch_1):page212_i138@pure_quanta.q_res(chips)';

PART_NAME
 R434 'Q_RES_0402LF-0,5%,1/16W,CHIP,CS00002JB38':;

SECTION_NUMBER 1
 '@T6G_MB_LIB.T6G(SCH_1):PAGE212_I121@PURE_QUANTA.Q_RES(CHIPS)':
 C_PATH='@t6g_mb_lib.t6g(sch_1):page212_i121@pure_quanta.q_res(chips)';

PART_NAME
 R1810 'Q_RES_0402LF-1K,5%,1/16W,EMPTY,TMP_QCS21002JB34':;

SECTION_NUMBER 1
 '@T6G_MB_LIB.T6G(SCH_1):PAGE188_I33@PURE_QUANTA.Q_RES(CHIPS)':
 C_PATH='@t6g_mb_lib.t6g(sch_1):page188_i33@pure_quanta.q_res(chips)';

PART_NAME
 R1809 'Q_RES_0402LF-20K,1%,1/16W,CHIP,CS32002FB29':;

SECTION_NUMBER 1
 '@T6G_MB_LIB.T6G(SCH_1):PAGE188_I30@PURE_QUANTA.Q_RES(CHIPS)':
 C_PATH='@t6g_mb_lib.t6g(sch_1):page188_i30@pure_quanta.q_res(chips)';

PART_NAME
 R1645 'Q_RES_0402LF-20K,5%,1/16W,CHIP,TMP_QCS32002JB12':;

SECTION_NUMBER 1
 '@T6G_MB_LIB.T6G(SCH_1):PAGE188_I3@PURE_QUANTA.Q_RES(CHIPS)':
 C_PATH='@t6g_mb_lib.t6g(sch_1):page188_i3@pure_quanta.q_res(chips)';

PART_NAME
 R1643 'Q_RES_0402LF-1K,5%,1/16W,CHIP,TMP_QCS21002JB34':;

SECTION_NUMBER 1
 '@T6G_MB_LIB.T6G(SCH_1):PAGE188_I10@PURE_QUANTA.Q_RES(CHIPS)':
 C_PATH='@t6g_mb_lib.t6g(sch_1):page188_i10@pure_quanta.q_res(chips)';

PART_NAME
 R1642 'Q_RES_0402LF-1K,5%,1/16W,EMPTY,TMP_QCS21002JB34':;

SECTION_NUMBER 1
 '@T6G_MB_LIB.T6G(SCH_1):PAGE188_I8@PURE_QUANTA.Q_RES(CHIPS)':
 C_PATH='@t6g_mb_lib.t6g(sch_1):page188_i8@pure_quanta.q_res(chips)';

PART_NAME
 R1641 'Q_RES_0402LF-10K,1%,1/16W,CHIP,TMP_QCS31002FB26':;

SECTION_NUMBER 1
 '@T6G_MB_LIB.T6G(SCH_1):PAGE188_I19@PURE_QUANTA.Q_RES(CHIPS)':
 C_PATH='@t6g_mb_lib.t6g(sch_1):page188_i19@pure_quanta.q_res(chips)';

PART_NAME
 R1640 'Q_RES_0402LF-10K,1%,1/16W,CHIP,TMP_QCS31002FB26':;

SECTION_NUMBER 1
 '@T6G_MB_LIB.T6G(SCH_1):PAGE188_I26@PURE_QUANTA.Q_RES(CHIPS)':
 C_PATH='@t6g_mb_lib.t6g(sch_1):page188_i26@pure_quanta.q_res(chips)';

PART_NAME
 R1639 'Q_RES_0402LF-1K,5%,1/16W,EMPTY,TMP_QCS21002JB34':;

SECTION_NUMBER 1
 '@T6G_MB_LIB.T6G(SCH_1):PAGE188_I25@PURE_QUANTA.Q_RES(CHIPS)':
 C_PATH='@t6g_mb_lib.t6g(sch_1):page188_i25@pure_quanta.q_res(chips)';

PART_NAME
 R1638 'Q_RES_0402LF-1K,5%,1/16W,EMPTY,TMP_QCS21002JB34':;

SECTION_NUMBER 1
 '@T6G_MB_LIB.T6G(SCH_1):PAGE188_I22@PURE_QUANTA.Q_RES(CHIPS)':
 C_PATH='@t6g_mb_lib.t6g(sch_1):page188_i22@pure_quanta.q_res(chips)';

PART_NAME
 R1637 'Q_RES_0402LF-10K,1%,1/16W,CHIP,TMP_QCS31002FB26':;

SECTION_NUMBER 1
 '@T6G_MB_LIB.T6G(SCH_1):PAGE188_I16@PURE_QUANTA.Q_RES(CHIPS)':
 C_PATH='@t6g_mb_lib.t6g(sch_1):page188_i16@pure_quanta.q_res(chips)';

PART_NAME
 R1636 'Q_RES_0402LF-1K,5%,1/16W,EMPTY,TMP_QCS21002JB34':;

SECTION_NUMBER 1
 '@T6G_MB_LIB.T6G(SCH_1):PAGE188_I15@PURE_QUANTA.Q_RES(CHIPS)':
 C_PATH='@t6g_mb_lib.t6g(sch_1):page188_i15@pure_quanta.q_res(chips)';

PART_NAME
 R518 'Q_RES_0402LF-20K,5%,1/16W,EMPTY,TMP_QCS32002JB12':;

SECTION_NUMBER 1
 '@T6G_MB_LIB.T6G(SCH_1):PAGE188_I4@PURE_QUANTA.Q_RES(CHIPS)':
 C_PATH='@t6g_mb_lib.t6g(sch_1):page188_i4@pure_quanta.q_res(chips)';

PART_NAME
 R376 'Q_RES_0402LF-1K,5%,1/16W,CHIP,TMP_QCS21002JB34':;

SECTION_NUMBER 1
 '@T6G_MB_LIB.T6G(SCH_1):PAGE188_I21@PURE_QUANTA.Q_RES(CHIPS)':
 C_PATH='@t6g_mb_lib.t6g(sch_1):page188_i21@pure_quanta.q_res(chips)';

PART_NAME
 R370 'Q_RES_0402LF-1K,5%,1/16W,EMPTY,TMP_QCS21002JB34':;

SECTION_NUMBER 1
 '@T6G_MB_LIB.T6G(SCH_1):PAGE188_I40@PURE_QUANTA.Q_RES(CHIPS)':
 C_PATH='@t6g_mb_lib.t6g(sch_1):page188_i40@pure_quanta.q_res(chips)';

PART_NAME
 R369 'Q_RES_0402LF-1K,5%,1/16W,CHIP,TMP_QCS21002JB34':;

SECTION_NUMBER 1
 '@T6G_MB_LIB.T6G(SCH_1):PAGE188_I39@PURE_QUANTA.Q_RES(CHIPS)':
 C_PATH='@t6g_mb_lib.t6g(sch_1):page188_i39@pure_quanta.q_res(chips)';

PART_NAME
 R368 'Q_RES_0402LF-100,1%,1/16W,EMPTY,TMP_QCS11002FB22':;

SECTION_NUMBER 1
 '@T6G_MB_LIB.T6G(SCH_1):PAGE188_I36@PURE_QUANTA.Q_RES(CHIPS)':
 C_PATH='@t6g_mb_lib.t6g(sch_1):page188_i36@pure_quanta.q_res(chips)';

PART_NAME
 R367 'Q_RES_0402LF-1K,5%,1/16W,CHIP,TMP_QCS21002JB34':;

SECTION_NUMBER 1
 '@T6G_MB_LIB.T6G(SCH_1):PAGE188_I35@PURE_QUANTA.Q_RES(CHIPS)':
 C_PATH='@t6g_mb_lib.t6g(sch_1):page188_i35@pure_quanta.q_res(chips)';

PART_NAME
 R1239 'Q_RES_0402LF-240,1%,1/16W,EMPTY,CS12402FB03':;

SECTION_NUMBER 1
 '@T6G_MB_LIB.T6G(SCH_1):PAGE91_I220@PURE_QUANTA.Q_RES(CHIPS)':
 C_PATH='@t6g_mb_lib.t6g(sch_1):page91_i220@pure_quanta.q_res(chips)';

PART_NAME
 R1238 'Q_RES_0402LF-240,1%,1/16W,EMPTY,CS12402FB03':;

SECTION_NUMBER 1
 '@T6G_MB_LIB.T6G(SCH_1):PAGE91_I221@PURE_QUANTA.Q_RES(CHIPS)':
 C_PATH='@t6g_mb_lib.t6g(sch_1):page91_i221@pure_quanta.q_res(chips)';

PART_NAME
 R1237 'Q_RES_0402LF-240,1%,1/16W,EMPTY,CS12402FB03':;

SECTION_NUMBER 1
 '@T6G_MB_LIB.T6G(SCH_1):PAGE91_I222@PURE_QUANTA.Q_RES(CHIPS)':
 C_PATH='@t6g_mb_lib.t6g(sch_1):page91_i222@pure_quanta.q_res(chips)';

PART_NAME
 R1236 'Q_RES_0402LF-240,1%,1/16W,EMPTY,CS12402FB03':;

SECTION_NUMBER 1
 '@T6G_MB_LIB.T6G(SCH_1):PAGE91_I175@PURE_QUANTA.Q_RES(CHIPS)':
 C_PATH='@t6g_mb_lib.t6g(sch_1):page91_i175@pure_quanta.q_res(chips)';

PART_NAME
 R1235 'Q_RES_0402LF-240,1%,1/16W,EMPTY,CS12402FB03':;

SECTION_NUMBER 1
 '@T6G_MB_LIB.T6G(SCH_1):PAGE91_I184@PURE_QUANTA.Q_RES(CHIPS)':
 C_PATH='@t6g_mb_lib.t6g(sch_1):page91_i184@pure_quanta.q_res(chips)';

PART_NAME
 R1234 'Q_RES_0402LF-240,1%,1/16W,EMPTY,CS12402FB03':;

SECTION_NUMBER 1
 '@T6G_MB_LIB.T6G(SCH_1):PAGE91_I183@PURE_QUANTA.Q_RES(CHIPS)':
 C_PATH='@t6g_mb_lib.t6g(sch_1):page91_i183@pure_quanta.q_res(chips)';

PART_NAME
 R1233 'Q_RES_0402LF-240,1%,1/16W,EMPTY,CS12402FB03':;

SECTION_NUMBER 1
 '@T6G_MB_LIB.T6G(SCH_1):PAGE91_I192@PURE_QUANTA.Q_RES(CHIPS)':
 C_PATH='@t6g_mb_lib.t6g(sch_1):page91_i192@pure_quanta.q_res(chips)';

PART_NAME
 R1232 'Q_RES_0402LF-240,1%,1/16W,EMPTY,CS12402FB03':;

SECTION_NUMBER 1
 '@T6G_MB_LIB.T6G(SCH_1):PAGE91_I193@PURE_QUANTA.Q_RES(CHIPS)':
 C_PATH='@t6g_mb_lib.t6g(sch_1):page91_i193@pure_quanta.q_res(chips)';

PART_NAME
 R1231 'Q_RES_0402LF-240,1%,1/16W,CHIP,CS12402FB03':;

SECTION_NUMBER 1
 '@T6G_MB_LIB.T6G(SCH_1):PAGE91_I194@PURE_QUANTA.Q_RES(CHIPS)':
 C_PATH='@t6g_mb_lib.t6g(sch_1):page91_i194@pure_quanta.q_res(chips)';

PART_NAME
 R1230 'Q_RES_0402LF-240,1%,1/16W,EMPTY,CS12402FB03':;

SECTION_NUMBER 1
 '@T6G_MB_LIB.T6G(SCH_1):PAGE91_I149@PURE_QUANTA.Q_RES(CHIPS)':
 C_PATH='@t6g_mb_lib.t6g(sch_1):page91_i149@pure_quanta.q_res(chips)';

PART_NAME
 R1229 'Q_RES_0402LF-240,1%,1/16W,EMPTY,CS12402FB03':;

SECTION_NUMBER 1
 '@T6G_MB_LIB.T6G(SCH_1):PAGE91_I150@PURE_QUANTA.Q_RES(CHIPS)':
 C_PATH='@t6g_mb_lib.t6g(sch_1):page91_i150@pure_quanta.q_res(chips)';

PART_NAME
 R1228 'Q_RES_0402LF-240,1%,1/16W,CHIP,CS12402FB03':;

SECTION_NUMBER 1
 '@T6G_MB_LIB.T6G(SCH_1):PAGE91_I151@PURE_QUANTA.Q_RES(CHIPS)':
 C_PATH='@t6g_mb_lib.t6g(sch_1):page91_i151@pure_quanta.q_res(chips)';

PART_NAME
 R1009 'Q_RES_0402LF-1K,1%,1/16W,EMPTY,TMP_QCS21002FB24':;

SECTION_NUMBER 1
 '@T6G_MB_LIB.T6G(SCH_1):PAGE91_I161@PURE_QUANTA.Q_RES(CHIPS)':
 C_PATH='@t6g_mb_lib.t6g(sch_1):page91_i161@pure_quanta.q_res(chips)';

PART_NAME
 R1008 'Q_RES_0402LF-1K,1%,1/16W,EMPTY,TMP_QCS21002FB24':;

SECTION_NUMBER 1
 '@T6G_MB_LIB.T6G(SCH_1):PAGE91_I147@PURE_QUANTA.Q_RES(CHIPS)':
 C_PATH='@t6g_mb_lib.t6g(sch_1):page91_i147@pure_quanta.q_res(chips)';

PART_NAME
 R295 'Q_RES_0402LF-240,1%,1/16W,EMPTY,CS12402FB03':;

SECTION_NUMBER 1
 '@T6G_MB_LIB.T6G(SCH_1):PAGE91_I223@PURE_QUANTA.Q_RES(CHIPS)':
 C_PATH='@t6g_mb_lib.t6g(sch_1):page91_i223@pure_quanta.q_res(chips)';

PART_NAME
 R294 'Q_RES_0402LF-240,1%,1/16W,EMPTY,CS12402FB03':;

SECTION_NUMBER 1
 '@T6G_MB_LIB.T6G(SCH_1):PAGE91_I224@PURE_QUANTA.Q_RES(CHIPS)':
 C_PATH='@t6g_mb_lib.t6g(sch_1):page91_i224@pure_quanta.q_res(chips)';

PART_NAME
 R293 'Q_RES_0402LF-240,1%,1/16W,EMPTY,CS12402FB03':;

SECTION_NUMBER 1
 '@T6G_MB_LIB.T6G(SCH_1):PAGE91_I225@PURE_QUANTA.Q_RES(CHIPS)':
 C_PATH='@t6g_mb_lib.t6g(sch_1):page91_i225@pure_quanta.q_res(chips)';

PART_NAME
 R292 'Q_RES_0402LF-240,1%,1/16W,EMPTY,CS12402FB03':;

SECTION_NUMBER 1
 '@T6G_MB_LIB.T6G(SCH_1):PAGE91_I226@PURE_QUANTA.Q_RES(CHIPS)':
 C_PATH='@t6g_mb_lib.t6g(sch_1):page91_i226@pure_quanta.q_res(chips)';

PART_NAME
 R291 'Q_RES_0402LF-240,1%,1/16W,EMPTY,CS12402FB03':;

SECTION_NUMBER 1
 '@T6G_MB_LIB.T6G(SCH_1):PAGE91_I186@PURE_QUANTA.Q_RES(CHIPS)':
 C_PATH='@t6g_mb_lib.t6g(sch_1):page91_i186@pure_quanta.q_res(chips)';

PART_NAME
 R290 'Q_RES_0402LF-240,1%,1/16W,CHIP,CS12402FB03':;

SECTION_NUMBER 1
 '@T6G_MB_LIB.T6G(SCH_1):PAGE91_I185@PURE_QUANTA.Q_RES(CHIPS)':
 C_PATH='@t6g_mb_lib.t6g(sch_1):page91_i185@pure_quanta.q_res(chips)';

PART_NAME
 R289 'Q_RES_0402LF-240,1%,1/16W,EMPTY,CS12402FB03':;

SECTION_NUMBER 1
 '@T6G_MB_LIB.T6G(SCH_1):PAGE91_I188@PURE_QUANTA.Q_RES(CHIPS)':
 C_PATH='@t6g_mb_lib.t6g(sch_1):page91_i188@pure_quanta.q_res(chips)';

PART_NAME
 R288 'Q_RES_0402LF-240,1%,1/16W,EMPTY,CS12402FB03':;

SECTION_NUMBER 1
 '@T6G_MB_LIB.T6G(SCH_1):PAGE91_I187@PURE_QUANTA.Q_RES(CHIPS)':
 C_PATH='@t6g_mb_lib.t6g(sch_1):page91_i187@pure_quanta.q_res(chips)';

PART_NAME
 R287 'Q_RES_0402LF-10K,1%,1/16W,CHIP,TMP_QCS31002FB26':;

SECTION_NUMBER 1
 '@T6G_MB_LIB.T6G(SCH_1):PAGE91_I190@PURE_QUANTA.Q_RES(CHIPS)':
 C_PATH='@t6g_mb_lib.t6g(sch_1):page91_i190@pure_quanta.q_res(chips)';

PART_NAME
 R286 'Q_RES_0402LF-10K,1%,1/16W,CHIP,TMP_QCS31002FB26':;

SECTION_NUMBER 1
 '@T6G_MB_LIB.T6G(SCH_1):PAGE91_I189@PURE_QUANTA.Q_RES(CHIPS)':
 C_PATH='@t6g_mb_lib.t6g(sch_1):page91_i189@pure_quanta.q_res(chips)';

PART_NAME
 R285 'Q_RES_0402LF-10K,1%,1/16W,CHIP,TMP_QCS31002FB26':;

SECTION_NUMBER 1
 '@T6G_MB_LIB.T6G(SCH_1):PAGE91_I216@PURE_QUANTA.Q_RES(CHIPS)':
 C_PATH='@t6g_mb_lib.t6g(sch_1):page91_i216@pure_quanta.q_res(chips)';

PART_NAME
 R284 'Q_RES_0402LF-10K,1%,1/16W,CHIP,TMP_QCS31002FB26':;

SECTION_NUMBER 1
 '@T6G_MB_LIB.T6G(SCH_1):PAGE91_I215@PURE_QUANTA.Q_RES(CHIPS)':
 C_PATH='@t6g_mb_lib.t6g(sch_1):page91_i215@pure_quanta.q_res(chips)';

PART_NAME
 R283 'Q_RES_0402LF-10K,1%,1/16W,CHIP,TMP_QCS31002FB26':;

SECTION_NUMBER 1
 '@T6G_MB_LIB.T6G(SCH_1):PAGE91_I218@PURE_QUANTA.Q_RES(CHIPS)':
 C_PATH='@t6g_mb_lib.t6g(sch_1):page91_i218@pure_quanta.q_res(chips)';

PART_NAME
 R282 'Q_RES_0402LF-240,1%,1/16W,CHIP,CS12402FB03':;

SECTION_NUMBER 1
 '@T6G_MB_LIB.T6G(SCH_1):PAGE91_I195@PURE_QUANTA.Q_RES(CHIPS)':
 C_PATH='@t6g_mb_lib.t6g(sch_1):page91_i195@pure_quanta.q_res(chips)';

PART_NAME
 R281 'Q_RES_0402LF-240,1%,1/16W,EMPTY,CS12402FB03':;

SECTION_NUMBER 1
 '@T6G_MB_LIB.T6G(SCH_1):PAGE91_I196@PURE_QUANTA.Q_RES(CHIPS)':
 C_PATH='@t6g_mb_lib.t6g(sch_1):page91_i196@pure_quanta.q_res(chips)';

PART_NAME
 R280 'Q_RES_0402LF-240,1%,1/16W,EMPTY,CS12402FB03':;

SECTION_NUMBER 1
 '@T6G_MB_LIB.T6G(SCH_1):PAGE91_I197@PURE_QUANTA.Q_RES(CHIPS)':
 C_PATH='@t6g_mb_lib.t6g(sch_1):page91_i197@pure_quanta.q_res(chips)';

PART_NAME
 R279 'Q_RES_0402LF-240,1%,1/16W,EMPTY,CS12402FB03':;

SECTION_NUMBER 1
 '@T6G_MB_LIB.T6G(SCH_1):PAGE91_I198@PURE_QUANTA.Q_RES(CHIPS)':
 C_PATH='@t6g_mb_lib.t6g(sch_1):page91_i198@pure_quanta.q_res(chips)';

PART_NAME
 R278 'Q_RES_0402LF-240,1%,1/16W,CHIP,CS12402FB03':;

SECTION_NUMBER 1
 '@T6G_MB_LIB.T6G(SCH_1):PAGE91_I199@PURE_QUANTA.Q_RES(CHIPS)':
 C_PATH='@t6g_mb_lib.t6g(sch_1):page91_i199@pure_quanta.q_res(chips)';

PART_NAME
 R277 'Q_RES_0402LF-240,1%,1/16W,CHIP,CS12402FB03':;

SECTION_NUMBER 1
 '@T6G_MB_LIB.T6G(SCH_1):PAGE91_I200@PURE_QUANTA.Q_RES(CHIPS)':
 C_PATH='@t6g_mb_lib.t6g(sch_1):page91_i200@pure_quanta.q_res(chips)';

PART_NAME
 R276 'Q_RES_0402LF-240,1%,1/16W,EMPTY,CS12402FB03':;

SECTION_NUMBER 1
 '@T6G_MB_LIB.T6G(SCH_1):PAGE91_I201@PURE_QUANTA.Q_RES(CHIPS)':
 C_PATH='@t6g_mb_lib.t6g(sch_1):page91_i201@pure_quanta.q_res(chips)';

PART_NAME
 R275 'Q_RES_0402LF-240,1%,1/16W,EMPTY,CS12402FB03':;

SECTION_NUMBER 1
 '@T6G_MB_LIB.T6G(SCH_1):PAGE91_I202@PURE_QUANTA.Q_RES(CHIPS)':
 C_PATH='@t6g_mb_lib.t6g(sch_1):page91_i202@pure_quanta.q_res(chips)';

PART_NAME
 R274 'Q_RES_0402LF-10K,1%,1/16W,CHIP,TMP_QCS31002FB26':;

SECTION_NUMBER 1
 '@T6G_MB_LIB.T6G(SCH_1):PAGE91_I169@PURE_QUANTA.Q_RES(CHIPS)':
 C_PATH='@t6g_mb_lib.t6g(sch_1):page91_i169@pure_quanta.q_res(chips)';

PART_NAME
 R273 'Q_RES_0402LF-10K,1%,1/16W,CHIP,TMP_QCS31002FB26':;

SECTION_NUMBER 1
 '@T6G_MB_LIB.T6G(SCH_1):PAGE91_I168@PURE_QUANTA.Q_RES(CHIPS)':
 C_PATH='@t6g_mb_lib.t6g(sch_1):page91_i168@pure_quanta.q_res(chips)';

PART_NAME
 R272 'Q_RES_0402LF-10K,1%,1/16W,CHIP,TMP_QCS31002FB26':;

SECTION_NUMBER 1
 '@T6G_MB_LIB.T6G(SCH_1):PAGE91_I171@PURE_QUANTA.Q_RES(CHIPS)':
 C_PATH='@t6g_mb_lib.t6g(sch_1):page91_i171@pure_quanta.q_res(chips)';

PART_NAME
 R271 'Q_RES_0402LF-10K,1%,1/16W,CHIP,TMP_QCS31002FB26':;

SECTION_NUMBER 1
 '@T6G_MB_LIB.T6G(SCH_1):PAGE91_I170@PURE_QUANTA.Q_RES(CHIPS)':
 C_PATH='@t6g_mb_lib.t6g(sch_1):page91_i170@pure_quanta.q_res(chips)';

PART_NAME
 R270 'Q_RES_0402LF-10K,1%,1/16W,CHIP,TMP_QCS31002FB26':;

SECTION_NUMBER 1
 '@T6G_MB_LIB.T6G(SCH_1):PAGE91_I173@PURE_QUANTA.Q_RES(CHIPS)':
 C_PATH='@t6g_mb_lib.t6g(sch_1):page91_i173@pure_quanta.q_res(chips)';

PART_NAME
 R268 'Q_RES_0402LF-240,1%,1/16W,EMPTY,CS12402FB03':;

SECTION_NUMBER 1
 '@T6G_MB_LIB.T6G(SCH_1):PAGE91_I152@PURE_QUANTA.Q_RES(CHIPS)':
 C_PATH='@t6g_mb_lib.t6g(sch_1):page91_i152@pure_quanta.q_res(chips)';

PART_NAME
 R267 'Q_RES_0402LF-240,1%,1/16W,EMPTY,CS12402FB03':;

SECTION_NUMBER 1
 '@T6G_MB_LIB.T6G(SCH_1):PAGE91_I153@PURE_QUANTA.Q_RES(CHIPS)':
 C_PATH='@t6g_mb_lib.t6g(sch_1):page91_i153@pure_quanta.q_res(chips)';

PART_NAME
 R266 'Q_RES_0402LF-240,1%,1/16W,EMPTY,CS12402FB03':;

SECTION_NUMBER 1
 '@T6G_MB_LIB.T6G(SCH_1):PAGE91_I154@PURE_QUANTA.Q_RES(CHIPS)':
 C_PATH='@t6g_mb_lib.t6g(sch_1):page91_i154@pure_quanta.q_res(chips)';

PART_NAME
 R265 'Q_RES_0402LF-240,1%,1/16W,CHIP,CS12402FB03':;

SECTION_NUMBER 1
 '@T6G_MB_LIB.T6G(SCH_1):PAGE91_I155@PURE_QUANTA.Q_RES(CHIPS)':
 C_PATH='@t6g_mb_lib.t6g(sch_1):page91_i155@pure_quanta.q_res(chips)';

PART_NAME
 R264 'Q_RES_0402LF-240,1%,1/16W,CHIP,CS12402FB03':;

SECTION_NUMBER 1
 '@T6G_MB_LIB.T6G(SCH_1):PAGE91_I156@PURE_QUANTA.Q_RES(CHIPS)':
 C_PATH='@t6g_mb_lib.t6g(sch_1):page91_i156@pure_quanta.q_res(chips)';

PART_NAME
 R263 'Q_RES_0402LF-240,1%,1/16W,EMPTY,CS12402FB03':;

SECTION_NUMBER 1
 '@T6G_MB_LIB.T6G(SCH_1):PAGE91_I157@PURE_QUANTA.Q_RES(CHIPS)':
 C_PATH='@t6g_mb_lib.t6g(sch_1):page91_i157@pure_quanta.q_res(chips)';

PART_NAME
 R262 'Q_RES_0402LF-240,1%,1/16W,EMPTY,CS12402FB03':;

SECTION_NUMBER 1
 '@T6G_MB_LIB.T6G(SCH_1):PAGE91_I159@PURE_QUANTA.Q_RES(CHIPS)':
 C_PATH='@t6g_mb_lib.t6g(sch_1):page91_i159@pure_quanta.q_res(chips)';

PART_NAME
 R261 'Q_RES_0402LF-240,1%,1/16W,EMPTY,CS12402FB03':;

SECTION_NUMBER 1
 '@T6G_MB_LIB.T6G(SCH_1):PAGE91_I160@PURE_QUANTA.Q_RES(CHIPS)':
 C_PATH='@t6g_mb_lib.t6g(sch_1):page91_i160@pure_quanta.q_res(chips)';

PART_NAME
 R1394 'Q_RES_0402LF-240,1%,1/16W,EMPTY,CS12402FB03':;

SECTION_NUMBER 1
 '@T6G_MB_LIB.T6G(SCH_1):PAGE92_I47@PURE_QUANTA.Q_RES(CHIPS)':
 C_PATH='@t6g_mb_lib.t6g(sch_1):page92_i47@pure_quanta.q_res(chips)';

PART_NAME
 R1393 'Q_RES_0402LF-240,1%,1/16W,EMPTY,CS12402FB03':;

SECTION_NUMBER 1
 '@T6G_MB_LIB.T6G(SCH_1):PAGE92_I46@PURE_QUANTA.Q_RES(CHIPS)':
 C_PATH='@t6g_mb_lib.t6g(sch_1):page92_i46@pure_quanta.q_res(chips)';

PART_NAME
 R1392 'Q_RES_0402LF-240,1%,1/16W,EMPTY,CS12402FB03':;

SECTION_NUMBER 1
 '@T6G_MB_LIB.T6G(SCH_1):PAGE92_I42@PURE_QUANTA.Q_RES(CHIPS)':
 C_PATH='@t6g_mb_lib.t6g(sch_1):page92_i42@pure_quanta.q_res(chips)';

PART_NAME
 R1391 'Q_RES_0402LF-240,1%,1/16W,EMPTY,CS12402FB03':;

SECTION_NUMBER 1
 '@T6G_MB_LIB.T6G(SCH_1):PAGE92_I40@PURE_QUANTA.Q_RES(CHIPS)':
 C_PATH='@t6g_mb_lib.t6g(sch_1):page92_i40@pure_quanta.q_res(chips)';

PART_NAME
 R695 'Q_RES_0402LF-240,1%,1/16W,EMPTY,CS12402FB03':;

SECTION_NUMBER 1
 '@T6G_MB_LIB.T6G(SCH_1):PAGE92_I45@PURE_QUANTA.Q_RES(CHIPS)':
 C_PATH='@t6g_mb_lib.t6g(sch_1):page92_i45@pure_quanta.q_res(chips)';

PART_NAME
 R517 'Q_RES_0402LF-240,1%,1/16W,EMPTY,CS12402FB03':;

SECTION_NUMBER 1
 '@T6G_MB_LIB.T6G(SCH_1):PAGE92_I39@PURE_QUANTA.Q_RES(CHIPS)':
 C_PATH='@t6g_mb_lib.t6g(sch_1):page92_i39@pure_quanta.q_res(chips)';

PART_NAME
 R260 'Q_RES_0402LF-240,1%,1/16W,CHIP,CS12402FB03':;

SECTION_NUMBER 1
 '@T6G_MB_LIB.T6G(SCH_1):PAGE92_I72@PURE_QUANTA.Q_RES(CHIPS)':
 C_PATH='@t6g_mb_lib.t6g(sch_1):page92_i72@pure_quanta.q_res(chips)';

PART_NAME
 R259 'Q_RES_0402LF-240,1%,1/16W,CHIP,CS12402FB03':;

SECTION_NUMBER 1
 '@T6G_MB_LIB.T6G(SCH_1):PAGE92_I73@PURE_QUANTA.Q_RES(CHIPS)':
 C_PATH='@t6g_mb_lib.t6g(sch_1):page92_i73@pure_quanta.q_res(chips)';

PART_NAME
 R258 'Q_RES_0402LF-240,1%,1/16W,CHIP,CS12402FB03':;

SECTION_NUMBER 1
 '@T6G_MB_LIB.T6G(SCH_1):PAGE92_I71@PURE_QUANTA.Q_RES(CHIPS)':
 C_PATH='@t6g_mb_lib.t6g(sch_1):page92_i71@pure_quanta.q_res(chips)';

PART_NAME
 R257 'Q_RES_0402LF-240,1%,1/16W,EMPTY,CS12402FB03':;

SECTION_NUMBER 1
 '@T6G_MB_LIB.T6G(SCH_1):PAGE92_I70@PURE_QUANTA.Q_RES(CHIPS)':
 C_PATH='@t6g_mb_lib.t6g(sch_1):page92_i70@pure_quanta.q_res(chips)';

PART_NAME
 R256 'Q_RES_0402LF-240,1%,1/16W,EMPTY,CS12402FB03':;

SECTION_NUMBER 1
 '@T6G_MB_LIB.T6G(SCH_1):PAGE92_I69@PURE_QUANTA.Q_RES(CHIPS)':
 C_PATH='@t6g_mb_lib.t6g(sch_1):page92_i69@pure_quanta.q_res(chips)';

PART_NAME
 R255 'Q_RES_0402LF-240,1%,1/16W,EMPTY,CS12402FB03':;

SECTION_NUMBER 1
 '@T6G_MB_LIB.T6G(SCH_1):PAGE92_I68@PURE_QUANTA.Q_RES(CHIPS)':
 C_PATH='@t6g_mb_lib.t6g(sch_1):page92_i68@pure_quanta.q_res(chips)';

PART_NAME
 R254 'Q_RES_0402LF-240,1%,1/16W,CHIP,CS12402FB03':;

SECTION_NUMBER 1
 '@T6G_MB_LIB.T6G(SCH_1):PAGE92_I66@PURE_QUANTA.Q_RES(CHIPS)':
 C_PATH='@t6g_mb_lib.t6g(sch_1):page92_i66@pure_quanta.q_res(chips)';

PART_NAME
 R253 'Q_RES_0402LF-240,1%,1/16W,CHIP,CS12402FB03':;

SECTION_NUMBER 1
 '@T6G_MB_LIB.T6G(SCH_1):PAGE92_I64@PURE_QUANTA.Q_RES(CHIPS)':
 C_PATH='@t6g_mb_lib.t6g(sch_1):page92_i64@pure_quanta.q_res(chips)';

PART_NAME
 R252 'Q_RES_0402LF-240,1%,1/16W,CHIP,CS12402FB03':;

SECTION_NUMBER 1
 '@T6G_MB_LIB.T6G(SCH_1):PAGE92_I65@PURE_QUANTA.Q_RES(CHIPS)':
 C_PATH='@t6g_mb_lib.t6g(sch_1):page92_i65@pure_quanta.q_res(chips)';

PART_NAME
 R251 'Q_RES_0402LF-240,1%,1/16W,EMPTY,CS12402FB03':;

SECTION_NUMBER 1
 '@T6G_MB_LIB.T6G(SCH_1):PAGE92_I63@PURE_QUANTA.Q_RES(CHIPS)':
 C_PATH='@t6g_mb_lib.t6g(sch_1):page92_i63@pure_quanta.q_res(chips)';

PART_NAME
 R250 'Q_RES_0402LF-240,1%,1/16W,EMPTY,CS12402FB03':;

SECTION_NUMBER 1
 '@T6G_MB_LIB.T6G(SCH_1):PAGE92_I62@PURE_QUANTA.Q_RES(CHIPS)':
 C_PATH='@t6g_mb_lib.t6g(sch_1):page92_i62@pure_quanta.q_res(chips)';

PART_NAME
 R249 'Q_RES_0402LF-240,1%,1/16W,EMPTY,CS12402FB03':;

SECTION_NUMBER 1
 '@T6G_MB_LIB.T6G(SCH_1):PAGE92_I61@PURE_QUANTA.Q_RES(CHIPS)':
 C_PATH='@t6g_mb_lib.t6g(sch_1):page92_i61@pure_quanta.q_res(chips)';

PART_NAME
 R1989 'Q_RES_0402LF-0,5%,1/16W,CHIP,CS00002JB38':;

SECTION_NUMBER 1
 '@T6G_MB_LIB.T6G(SCH_1):PAGE204_I1@PURE_QUANTA.Q_RES(CHIPS)':
 C_PATH='@t6g_mb_lib.t6g(sch_1):page204_i1@pure_quanta.q_res(chips)';

PART_NAME
 R149 'Q_RES_0402LF-0,5%,1/16W,EMPTY,CS00002JB38':;

SECTION_NUMBER 1
 '@T6G_MB_LIB.T6G(SCH_1):PAGE204_I9@PURE_QUANTA.Q_RES(CHIPS)':
 C_PATH='@t6g_mb_lib.t6g(sch_1):page204_i9@pure_quanta.q_res(chips)';

PART_NAME
 R148 'Q_RES_0402LF-10K,1%,1/16W,CHIP,TMP_QCS31002FB26':;

SECTION_NUMBER 1
 '@T6G_MB_LIB.T6G(SCH_1):PAGE204_I4@PURE_QUANTA.Q_RES(CHIPS)':
 C_PATH='@t6g_mb_lib.t6g(sch_1):page204_i4@pure_quanta.q_res(chips)';

PART_NAME
 R147 'Q_RES_0402LF-348,1%,1/16W,CHIP,CS13482FB00':;

SECTION_NUMBER 1
 '@T6G_MB_LIB.T6G(SCH_1):PAGE204_I10@PURE_QUANTA.Q_RES(CHIPS)':
 C_PATH='@t6g_mb_lib.t6g(sch_1):page204_i10@pure_quanta.q_res(chips)';

PART_NAME
 R146 'Q_RES_0402LF-4.7K,5%,1/16W,EMPTY,TMP_QCS24702JB38':;

SECTION_NUMBER 1
 '@T6G_MB_LIB.T6G(SCH_1):PAGE204_I3@PURE_QUANTA.Q_RES(CHIPS)':
 C_PATH='@t6g_mb_lib.t6g(sch_1):page204_i3@pure_quanta.q_res(chips)';

PART_NAME
 R145 'Q_RES_0402LF-4.7K,5%,1/16W,EMPTY,TMP_QCS24702JB38':;

SECTION_NUMBER 1
 '@T6G_MB_LIB.T6G(SCH_1):PAGE204_I7@PURE_QUANTA.Q_RES(CHIPS)':
 C_PATH='@t6g_mb_lib.t6g(sch_1):page204_i7@pure_quanta.q_res(chips)';

PART_NAME
 R144 'Q_RES_0402LF-10,1%,1/16W,CHIP,TMP_QCS01002FB21':;

SECTION_NUMBER 1
 '@T6G_MB_LIB.T6G(SCH_1):PAGE204_I8@PURE_QUANTA.Q_RES(CHIPS)':
 C_PATH='@t6g_mb_lib.t6g(sch_1):page204_i8@pure_quanta.q_res(chips)';

PART_NAME
 R143 'Q_RES_0402LF-0,5%,1/16W,CHIP,CS00002JB38':;

SECTION_NUMBER 1
 '@T6G_MB_LIB.T6G(SCH_1):PAGE204_I12@PURE_QUANTA.Q_RES(CHIPS)':
 C_PATH='@t6g_mb_lib.t6g(sch_1):page204_i12@pure_quanta.q_res(chips)';

PART_NAME
 R2236 'Q_RES_0402LF-33,5%,1/16W,CHIP,CS03302JB29':;

SECTION_NUMBER 1
 '@T6G_MB_LIB.T6G(SCH_1):PAGE247_I14@PURE_QUANTA.Q_RES(CHIPS)':
 C_PATH='@t6g_mb_lib.t6g(sch_1):page247_i14@pure_quanta.q_res(chips)';

PART_NAME
 R2235 'Q_RES_0402LF-33,5%,1/16W,CHIP,CS03302JB29':;

SECTION_NUMBER 1
 '@T6G_MB_LIB.T6G(SCH_1):PAGE247_I15@PURE_QUANTA.Q_RES(CHIPS)':
 C_PATH='@t6g_mb_lib.t6g(sch_1):page247_i15@pure_quanta.q_res(chips)';

PART_NAME
 R2234 'Q_RES_0402LF-33,5%,1/16W,CHIP,CS03302JB29':;

SECTION_NUMBER 1
 '@T6G_MB_LIB.T6G(SCH_1):PAGE247_I13@PURE_QUANTA.Q_RES(CHIPS)':
 C_PATH='@t6g_mb_lib.t6g(sch_1):page247_i13@pure_quanta.q_res(chips)';

PART_NAME
 R2232 'Q_RES_0402LF-33,5%,1/16W,CHIP,CS03302JB29':;

SECTION_NUMBER 1
 '@T6G_MB_LIB.T6G(SCH_1):PAGE247_I23@PURE_QUANTA.Q_RES(CHIPS)':
 C_PATH='@t6g_mb_lib.t6g(sch_1):page247_i23@pure_quanta.q_res(chips)';

PART_NAME
 R2228 'Q_RES_0402LF-33,5%,1/16W,CHIP,CS03302JB29':;

SECTION_NUMBER 1
 '@T6G_MB_LIB.T6G(SCH_1):PAGE247_I19@PURE_QUANTA.Q_RES(CHIPS)':
 C_PATH='@t6g_mb_lib.t6g(sch_1):page247_i19@pure_quanta.q_res(chips)';

PART_NAME
 R2224 'Q_RES_0402LF-33,5%,1/16W,CHIP,CS03302JB29':;

SECTION_NUMBER 1
 '@T6G_MB_LIB.T6G(SCH_1):PAGE247_I47@PURE_QUANTA.Q_RES(CHIPS)':
 C_PATH='@t6g_mb_lib.t6g(sch_1):page247_i47@pure_quanta.q_res(chips)';

PART_NAME
 R2221 'Q_RES_0402LF-33,5%,1/16W,EMPTY,CS03302JB29':;

SECTION_NUMBER 1
 '@T6G_MB_LIB.T6G(SCH_1):PAGE247_I42@PURE_QUANTA.Q_RES(CHIPS)':
 C_PATH='@t6g_mb_lib.t6g(sch_1):page247_i42@pure_quanta.q_res(chips)';

PART_NAME
 R2203 'Q_RES_0402LF-100K,1%,1/16W,CHIP,TMP_QCS41002FB28':;

SECTION_NUMBER 1
 '@T6G_MB_LIB.T6G(SCH_1):PAGE247_I49@PURE_QUANTA.Q_RES(CHIPS)':
 C_PATH='@t6g_mb_lib.t6g(sch_1):page247_i49@pure_quanta.q_res(chips)';

PART_NAME
 R1996 'Q_RES_0402LF-33,5%,1/16W,CHIP,CS03302JB29':;

SECTION_NUMBER 1
 '@T6G_MB_LIB.T6G(SCH_1):PAGE247_I45@PURE_QUANTA.Q_RES(CHIPS)':
 C_PATH='@t6g_mb_lib.t6g(sch_1):page247_i45@pure_quanta.q_res(chips)';

PART_NAME
 R1995 'Q_RES_0402LF-33,5%,1/16W,CHIP,CS03302JB29':;

SECTION_NUMBER 1
 '@T6G_MB_LIB.T6G(SCH_1):PAGE247_I44@PURE_QUANTA.Q_RES(CHIPS)':
 C_PATH='@t6g_mb_lib.t6g(sch_1):page247_i44@pure_quanta.q_res(chips)';

PART_NAME
 R1744 'Q_RES_0402LF-0,5%,1/16W,CHIP,CS00002JB38':;

SECTION_NUMBER 1
 '@T6G_MB_LIB.T6G(SCH_1):PAGE247_I41@PURE_QUANTA.Q_RES(CHIPS)':
 C_PATH='@t6g_mb_lib.t6g(sch_1):page247_i41@pure_quanta.q_res(chips)';

PART_NAME
 R1207 'Q_RES_0402LF-33,5%,1/16W,CHIP,CS03302JB29':;

SECTION_NUMBER 1
 '@T6G_MB_LIB.T6G(SCH_1):PAGE247_I48@PURE_QUANTA.Q_RES(CHIPS)':
 C_PATH='@t6g_mb_lib.t6g(sch_1):page247_i48@pure_quanta.q_res(chips)';

PART_NAME
 R1205 'Q_RES_0402LF-33,5%,1/16W,CHIP,CS03302JB29':;

SECTION_NUMBER 1
 '@T6G_MB_LIB.T6G(SCH_1):PAGE247_I46@PURE_QUANTA.Q_RES(CHIPS)':
 C_PATH='@t6g_mb_lib.t6g(sch_1):page247_i46@pure_quanta.q_res(chips)';

PART_NAME
 R269 'Q_RES_0402LF-33,5%,1/16W,CHIP,CS03302JB29':;

SECTION_NUMBER 1
 '@T6G_MB_LIB.T6G(SCH_1):PAGE247_I25@PURE_QUANTA.Q_RES(CHIPS)':
 C_PATH='@t6g_mb_lib.t6g(sch_1):page247_i25@pure_quanta.q_res(chips)';

PART_NAME
 R110 'Q_RES_0402LF-33,5%,1/16W,CHIP,CS03302JB29':;

SECTION_NUMBER 1
 '@T6G_MB_LIB.T6G(SCH_1):PAGE247_I50@PURE_QUANTA.Q_RES(CHIPS)':
 C_PATH='@t6g_mb_lib.t6g(sch_1):page247_i50@pure_quanta.q_res(chips)';

PART_NAME
 R109 'Q_RES_0402LF-33,5%,1/16W,CHIP,CS03302JB29':;

SECTION_NUMBER 1
 '@T6G_MB_LIB.T6G(SCH_1):PAGE247_I43@PURE_QUANTA.Q_RES(CHIPS)':
 C_PATH='@t6g_mb_lib.t6g(sch_1):page247_i43@pure_quanta.q_res(chips)';

PART_NAME
 R119 'Q_RES_0402LF-10K,1%,1/16W,EMPTY,TMP_QCS31002FB26':;

SECTION_NUMBER 1
 '@T6G_MB_LIB.T6G(SCH_1):PAGE97_I49@PURE_QUANTA.Q_RES(CHIPS)':
 C_PATH='@t6g_mb_lib.t6g(sch_1):page97_i49@pure_quanta.q_res(chips)';

PART_NAME
 R118 'Q_RES_0402LF-10K,1%,1/16W,CHIP,TMP_QCS31002FB26':;

SECTION_NUMBER 1
 '@T6G_MB_LIB.T6G(SCH_1):PAGE97_I50@PURE_QUANTA.Q_RES(CHIPS)':
 C_PATH='@t6g_mb_lib.t6g(sch_1):page97_i50@pure_quanta.q_res(chips)';

PART_NAME
 R117 'Q_RES_0402LF-10K,1%,1/16W,CHIP,TMP_QCS31002FB26':;

SECTION_NUMBER 1
 '@T6G_MB_LIB.T6G(SCH_1):PAGE97_I51@PURE_QUANTA.Q_RES(CHIPS)':
 C_PATH='@t6g_mb_lib.t6g(sch_1):page97_i51@pure_quanta.q_res(chips)';

PART_NAME
 R116 'Q_RES_0402LF-10K,1%,1/16W,EMPTY,TMP_QCS31002FB26':;

SECTION_NUMBER 1
 '@T6G_MB_LIB.T6G(SCH_1):PAGE97_I52@PURE_QUANTA.Q_RES(CHIPS)':
 C_PATH='@t6g_mb_lib.t6g(sch_1):page97_i52@pure_quanta.q_res(chips)';

PART_NAME
 R115 'Q_RES_0402LF-10K,1%,1/16W,CHIP,TMP_QCS31002FB26':;

SECTION_NUMBER 1
 '@T6G_MB_LIB.T6G(SCH_1):PAGE97_I53@PURE_QUANTA.Q_RES(CHIPS)':
 C_PATH='@t6g_mb_lib.t6g(sch_1):page97_i53@pure_quanta.q_res(chips)';

PART_NAME
 R114 'Q_RES_0402LF-10K,1%,1/16W,CHIP,TMP_QCS31002FB26':;

SECTION_NUMBER 1
 '@T6G_MB_LIB.T6G(SCH_1):PAGE97_I54@PURE_QUANTA.Q_RES(CHIPS)':
 C_PATH='@t6g_mb_lib.t6g(sch_1):page97_i54@pure_quanta.q_res(chips)';

PART_NAME
 R105 'Q_RES_0402LF-33,5%,1/16W,CHIP,CS03302JB29':;

SECTION_NUMBER 1
 '@T6G_MB_LIB.T6G(SCH_1):PAGE97_I20@PURE_QUANTA.Q_RES(CHIPS)':
 C_PATH='@t6g_mb_lib.t6g(sch_1):page97_i20@pure_quanta.q_res(chips)';

PART_NAME
 R104 'Q_RES_0402LF-33,5%,1/16W,CHIP,CS03302JB29':;

SECTION_NUMBER 1
 '@T6G_MB_LIB.T6G(SCH_1):PAGE97_I28@PURE_QUANTA.Q_RES(CHIPS)':
 C_PATH='@t6g_mb_lib.t6g(sch_1):page97_i28@pure_quanta.q_res(chips)';

PART_NAME
 R103 'Q_RES_0402LF-33,5%,1/16W,CHIP,CS03302JB29':;

SECTION_NUMBER 1
 '@T6G_MB_LIB.T6G(SCH_1):PAGE97_I29@PURE_QUANTA.Q_RES(CHIPS)':
 C_PATH='@t6g_mb_lib.t6g(sch_1):page97_i29@pure_quanta.q_res(chips)';

PART_NAME
 R102 'Q_RES_0402LF-33,5%,1/16W,CHIP,CS03302JB29':;

SECTION_NUMBER 1
 '@T6G_MB_LIB.T6G(SCH_1):PAGE97_I30@PURE_QUANTA.Q_RES(CHIPS)':
 C_PATH='@t6g_mb_lib.t6g(sch_1):page97_i30@pure_quanta.q_res(chips)';

PART_NAME
 R101 'Q_RES_0402LF-33,5%,1/16W,CHIP,CS03302JB29':;

SECTION_NUMBER 1
 '@T6G_MB_LIB.T6G(SCH_1):PAGE97_I31@PURE_QUANTA.Q_RES(CHIPS)':
 C_PATH='@t6g_mb_lib.t6g(sch_1):page97_i31@pure_quanta.q_res(chips)';

PART_NAME
 R100 'Q_RES_0402LF-33,5%,1/16W,CHIP,CS03302JB29':;

SECTION_NUMBER 1
 '@T6G_MB_LIB.T6G(SCH_1):PAGE97_I32@PURE_QUANTA.Q_RES(CHIPS)':
 C_PATH='@t6g_mb_lib.t6g(sch_1):page97_i32@pure_quanta.q_res(chips)';

PART_NAME
 R99 'Q_RES_0402LF-33,5%,1/16W,CHIP,CS03302JB29':;

SECTION_NUMBER 1
 '@T6G_MB_LIB.T6G(SCH_1):PAGE97_I33@PURE_QUANTA.Q_RES(CHIPS)':
 C_PATH='@t6g_mb_lib.t6g(sch_1):page97_i33@pure_quanta.q_res(chips)';

PART_NAME
 R98 'Q_RES_0402LF-33,5%,1/16W,CHIP,CS03302JB29':;

SECTION_NUMBER 1
 '@T6G_MB_LIB.T6G(SCH_1):PAGE97_I34@PURE_QUANTA.Q_RES(CHIPS)':
 C_PATH='@t6g_mb_lib.t6g(sch_1):page97_i34@pure_quanta.q_res(chips)';

PART_NAME
 R97 'Q_RES_0402LF-240,1%,1/16W,EMPTY,CS12402FB03':;

SECTION_NUMBER 1
 '@T6G_MB_LIB.T6G(SCH_1):PAGE97_I12@PURE_QUANTA.Q_RES(CHIPS)':
 C_PATH='@t6g_mb_lib.t6g(sch_1):page97_i12@pure_quanta.q_res(chips)';

PART_NAME
 R96 'Q_RES_0402LF-240,1%,1/16W,EMPTY,CS12402FB03':;

SECTION_NUMBER 1
 '@T6G_MB_LIB.T6G(SCH_1):PAGE97_I13@PURE_QUANTA.Q_RES(CHIPS)':
 C_PATH='@t6g_mb_lib.t6g(sch_1):page97_i13@pure_quanta.q_res(chips)';

PART_NAME
 R95 'Q_RES_0402LF-240,1%,1/16W,EMPTY,CS12402FB03':;

SECTION_NUMBER 1
 '@T6G_MB_LIB.T6G(SCH_1):PAGE97_I14@PURE_QUANTA.Q_RES(CHIPS)':
 C_PATH='@t6g_mb_lib.t6g(sch_1):page97_i14@pure_quanta.q_res(chips)';

PART_NAME
 R94 'Q_RES_0402LF-240,1%,1/16W,EMPTY,CS12402FB03':;

SECTION_NUMBER 1
 '@T6G_MB_LIB.T6G(SCH_1):PAGE97_I15@PURE_QUANTA.Q_RES(CHIPS)':
 C_PATH='@t6g_mb_lib.t6g(sch_1):page97_i15@pure_quanta.q_res(chips)';

PART_NAME
 R93 'Q_RES_0402LF-240,1%,1/16W,EMPTY,CS12402FB03':;

SECTION_NUMBER 1
 '@T6G_MB_LIB.T6G(SCH_1):PAGE97_I4@PURE_QUANTA.Q_RES(CHIPS)':
 C_PATH='@t6g_mb_lib.t6g(sch_1):page97_i4@pure_quanta.q_res(chips)';

PART_NAME
 R92 'Q_RES_0402LF-240,1%,1/16W,EMPTY,CS12402FB03':;

SECTION_NUMBER 1
 '@T6G_MB_LIB.T6G(SCH_1):PAGE97_I5@PURE_QUANTA.Q_RES(CHIPS)':
 C_PATH='@t6g_mb_lib.t6g(sch_1):page97_i5@pure_quanta.q_res(chips)';

PART_NAME
 R91 'Q_RES_0402LF-240,1%,1/16W,EMPTY,CS12402FB03':;

SECTION_NUMBER 1
 '@T6G_MB_LIB.T6G(SCH_1):PAGE97_I6@PURE_QUANTA.Q_RES(CHIPS)':
 C_PATH='@t6g_mb_lib.t6g(sch_1):page97_i6@pure_quanta.q_res(chips)';

PART_NAME
 R90 'Q_RES_0402LF-240,1%,1/16W,EMPTY,CS12402FB03':;

SECTION_NUMBER 1
 '@T6G_MB_LIB.T6G(SCH_1):PAGE97_I7@PURE_QUANTA.Q_RES(CHIPS)':
 C_PATH='@t6g_mb_lib.t6g(sch_1):page97_i7@pure_quanta.q_res(chips)';

PART_NAME
 R1399 'Q_RES_0402LF-4.32K,1%,1/16W,CHIP,TMP_QCS24322FB14':;

SECTION_NUMBER 1
 '@T6G_MB_LIB.T6G(SCH_1):PAGE46_I15@PURE_QUANTA.Q_RES(CHIPS)':
 C_PATH='@t6g_mb_lib.t6g(sch_1):page46_i15@pure_quanta.q_res(chips)';

PART_NAME
 R1398 'Q_RES_0402LF-4.32K,1%,1/16W,CHIP,TMP_QCS24322FB14':;

SECTION_NUMBER 1
 '@T6G_MB_LIB.T6G(SCH_1):PAGE46_I16@PURE_QUANTA.Q_RES(CHIPS)':
 C_PATH='@t6g_mb_lib.t6g(sch_1):page46_i16@pure_quanta.q_res(chips)';

PART_NAME
 R1227 'Q_RES_0402LF-10K,1%,1/16W,CHIP,TMP_QCS31002FB26':;

SECTION_NUMBER 1
 '@T6G_MB_LIB.T6G(SCH_1):PAGE46_I29@PURE_QUANTA.Q_RES(CHIPS)':
 C_PATH='@t6g_mb_lib.t6g(sch_1):page46_i29@pure_quanta.q_res(chips)';

PART_NAME
 R1226 'Q_RES_0402LF-1K,1%,1/16W,CHIP,TMP_QCS21002FB24':;

SECTION_NUMBER 1
 '@T6G_MB_LIB.T6G(SCH_1):PAGE46_I30@PURE_QUANTA.Q_RES(CHIPS)':
 C_PATH='@t6g_mb_lib.t6g(sch_1):page46_i30@pure_quanta.q_res(chips)';

PART_NAME
 R1225 'Q_RES_0402LF-10K,1%,1/16W,CHIP,TMP_QCS31002FB26':;

SECTION_NUMBER 1
 '@T6G_MB_LIB.T6G(SCH_1):PAGE46_I27@PURE_QUANTA.Q_RES(CHIPS)':
 C_PATH='@t6g_mb_lib.t6g(sch_1):page46_i27@pure_quanta.q_res(chips)';

PART_NAME
 R1224 'Q_RES_0402LF-10K,1%,1/16W,CHIP,TMP_QCS31002FB26':;

SECTION_NUMBER 1
 '@T6G_MB_LIB.T6G(SCH_1):PAGE46_I28@PURE_QUANTA.Q_RES(CHIPS)':
 C_PATH='@t6g_mb_lib.t6g(sch_1):page46_i28@pure_quanta.q_res(chips)';

PART_NAME
 R1223 'Q_RES_0402LF-10K,1%,1/16W,EMPTY,TMP_QCS31002FB26':;

SECTION_NUMBER 1
 '@T6G_MB_LIB.T6G(SCH_1):PAGE46_I31@PURE_QUANTA.Q_RES(CHIPS)':
 C_PATH='@t6g_mb_lib.t6g(sch_1):page46_i31@pure_quanta.q_res(chips)';

PART_NAME
 R1219 'Q_RES_0402LF-33,5%,1/16W,CHIP,CS03302JB29':;

SECTION_NUMBER 1
 '@T6G_MB_LIB.T6G(SCH_1):PAGE46_I11@PURE_QUANTA.Q_RES(CHIPS)':
 C_PATH='@t6g_mb_lib.t6g(sch_1):page46_i11@pure_quanta.q_res(chips)';

PART_NAME
 R1218 'Q_RES_0402LF-33,5%,1/16W,CHIP,CS03302JB29':;

SECTION_NUMBER 1
 '@T6G_MB_LIB.T6G(SCH_1):PAGE46_I12@PURE_QUANTA.Q_RES(CHIPS)':
 C_PATH='@t6g_mb_lib.t6g(sch_1):page46_i12@pure_quanta.q_res(chips)';

PART_NAME
 R70 'Q_RES_0402LF-10K,5%,1/16W,CHIP,TMP_QCS31002JB28':;

SECTION_NUMBER 1
 '@T6G_MB_LIB.T6G(SCH_1):PAGE46_I3@PURE_QUANTA.Q_RES(CHIPS)':
 C_PATH='@t6g_mb_lib.t6g(sch_1):page46_i3@pure_quanta.q_res(chips)';

PART_NAME
 R69 'Q_RES_0402LF-10K,5%,1/16W,CHIP,TMP_QCS31002JB28':;

SECTION_NUMBER 1
 '@T6G_MB_LIB.T6G(SCH_1):PAGE46_I4@PURE_QUANTA.Q_RES(CHIPS)':
 C_PATH='@t6g_mb_lib.t6g(sch_1):page46_i4@pure_quanta.q_res(chips)';

PART_NAME
 R68 'Q_RES_0402LF-33,5%,1/16W,CHIP,CS03302JB29':;

SECTION_NUMBER 1
 '@T6G_MB_LIB.T6G(SCH_1):PAGE46_I13@PURE_QUANTA.Q_RES(CHIPS)':
 C_PATH='@t6g_mb_lib.t6g(sch_1):page46_i13@pure_quanta.q_res(chips)';

PART_NAME
 R67 'Q_RES_0402LF-33,5%,1/16W,CHIP,CS03302JB29':;

SECTION_NUMBER 1
 '@T6G_MB_LIB.T6G(SCH_1):PAGE46_I14@PURE_QUANTA.Q_RES(CHIPS)':
 C_PATH='@t6g_mb_lib.t6g(sch_1):page46_i14@pure_quanta.q_res(chips)';

PART_NAME
 R1270 'Q_RES_0402LF-240,1%,1/16W,EMPTY,CS12402FB03':;

SECTION_NUMBER 1
 '@T6G_MB_LIB.T6G(SCH_1):PAGE47_I614@PURE_QUANTA.Q_RES(CHIPS)':
 C_PATH='@t6g_mb_lib.t6g(sch_1):page47_i614@pure_quanta.q_res(chips)';

PART_NAME
 R66 'Q_RES_0402LF-100,1%,1/16W,CHIP,TMP_QCS11002FB22':;

SECTION_NUMBER 1
 '@T6G_MB_LIB.T6G(SCH_1):PAGE47_I638@PURE_QUANTA.Q_RES(CHIPS)':
 C_PATH='@t6g_mb_lib.t6g(sch_1):page47_i638@pure_quanta.q_res(chips)';

PART_NAME
 R65 'Q_RES_0402LF-100,1%,1/16W,CHIP,TMP_QCS11002FB22':;

SECTION_NUMBER 1
 '@T6G_MB_LIB.T6G(SCH_1):PAGE47_I637@PURE_QUANTA.Q_RES(CHIPS)':
 C_PATH='@t6g_mb_lib.t6g(sch_1):page47_i637@pure_quanta.q_res(chips)';

PART_NAME
 R64 'Q_RES_0402LF-200,1%,1/16W,CHIP,CS12002FB25':;

SECTION_NUMBER 1
 '@T6G_MB_LIB.T6G(SCH_1):PAGE47_I636@PURE_QUANTA.Q_RES(CHIPS)':
 C_PATH='@t6g_mb_lib.t6g(sch_1):page47_i636@pure_quanta.q_res(chips)';

PART_NAME
 R63 'Q_RES_0402LF-33,5%,1/16W,CHIP,CS03302JB29':;

SECTION_NUMBER 1
 '@T6G_MB_LIB.T6G(SCH_1):PAGE47_I635@PURE_QUANTA.Q_RES(CHIPS)':
 C_PATH='@t6g_mb_lib.t6g(sch_1):page47_i635@pure_quanta.q_res(chips)';

PART_NAME
 R62 'Q_RES_0402LF-100,1%,1/16W,CHIP,TMP_QCS11002FB22':;

SECTION_NUMBER 1
 '@T6G_MB_LIB.T6G(SCH_1):PAGE47_I631@PURE_QUANTA.Q_RES(CHIPS)':
 C_PATH='@t6g_mb_lib.t6g(sch_1):page47_i631@pure_quanta.q_res(chips)';

PART_NAME
 R61 'Q_RES_0402LF-10,1%,1/16W,CHIP,TMP_QCS01002FB21':;

SECTION_NUMBER 1
 '@T6G_MB_LIB.T6G(SCH_1):PAGE47_I632@PURE_QUANTA.Q_RES(CHIPS)':
 C_PATH='@t6g_mb_lib.t6g(sch_1):page47_i632@pure_quanta.q_res(chips)';

PART_NAME
 R3824 'Q_RES_0402LF-33,5%,1/16W,CHIP,CS03302JB29':;

SECTION_NUMBER 1
 '@T6G_MB_LIB.T6G(SCH_1):PAGE48_I293@PURE_QUANTA.Q_RES(CHIPS)':
 C_PATH='@t6g_mb_lib.t6g(sch_1):page48_i293@pure_quanta.q_res(chips)';

PART_NAME
 R3822 'Q_RES_0402LF-33,5%,1/16W,CHIP,CS03302JB29':;

SECTION_NUMBER 1
 '@T6G_MB_LIB.T6G(SCH_1):PAGE48_I290@PURE_QUANTA.Q_RES(CHIPS)':
 C_PATH='@t6g_mb_lib.t6g(sch_1):page48_i290@pure_quanta.q_res(chips)';

PART_NAME
 R3805 'Q_RES_0402LF-33,5%,1/16W,CHIP,CS03302JB29':;

SECTION_NUMBER 1
 '@T6G_MB_LIB.T6G(SCH_1):PAGE48_I288@PURE_QUANTA.Q_RES(CHIPS)':
 C_PATH='@t6g_mb_lib.t6g(sch_1):page48_i288@pure_quanta.q_res(chips)';

PART_NAME
 R560 'Q_RES_0402LF-49.9     ,1%  ,1/16W,CHIP,CS04992FB31':;

SECTION_NUMBER 1
 '@T6G_MB_LIB.T6G(SCH_1):PAGE48_I261@PURE_QUANTA.Q_RES(CHIPS)':
 C_PATH='@t6g_mb_lib.t6g(sch_1):page48_i261@pure_quanta.q_res(chips)';

PART_NAME
 R559 'Q_RES_0402LF-100,1%,1/16W,CHIP,TMP_QCS11002FB22':;

SECTION_NUMBER 1
 '@T6G_MB_LIB.T6G(SCH_1):PAGE48_I260@PURE_QUANTA.Q_RES(CHIPS)':
 C_PATH='@t6g_mb_lib.t6g(sch_1):page48_i260@pure_quanta.q_res(chips)';

PART_NAME
 R558 'Q_RES_0402LF-49.9     ,1%  ,1/16W,CHIP,CS04992FB31':;

SECTION_NUMBER 1
 '@T6G_MB_LIB.T6G(SCH_1):PAGE48_I259@PURE_QUANTA.Q_RES(CHIPS)':
 C_PATH='@t6g_mb_lib.t6g(sch_1):page48_i259@pure_quanta.q_res(chips)';

PART_NAME
 R557 'Q_RES_0402LF-100,1%,1/16W,CHIP,TMP_QCS11002FB22':;

SECTION_NUMBER 1
 '@T6G_MB_LIB.T6G(SCH_1):PAGE48_I258@PURE_QUANTA.Q_RES(CHIPS)':
 C_PATH='@t6g_mb_lib.t6g(sch_1):page48_i258@pure_quanta.q_res(chips)';

PART_NAME
 R516 'Q_RES_0402LF-49.9     ,1%  ,1/16W,CHIP,CS04992FB31':;

SECTION_NUMBER 1
 '@T6G_MB_LIB.T6G(SCH_1):PAGE48_I256@PURE_QUANTA.Q_RES(CHIPS)':
 C_PATH='@t6g_mb_lib.t6g(sch_1):page48_i256@pure_quanta.q_res(chips)';

PART_NAME
 R60 'Q_RES_0402LF-200,1%,1/16W,CHIP,CS12002FB25':;

SECTION_NUMBER 1
 '@T6G_MB_LIB.T6G(SCH_1):PAGE48_I254@PURE_QUANTA.Q_RES(CHIPS)':
 C_PATH='@t6g_mb_lib.t6g(sch_1):page48_i254@pure_quanta.q_res(chips)';

PART_NAME
 R59 'Q_RES_0402LF-0,5%,1/16W,CHIP,CS00002JB38':;

SECTION_NUMBER 1
 '@T6G_MB_LIB.T6G(SCH_1):PAGE48_I252@PURE_QUANTA.Q_RES(CHIPS)':
 C_PATH='@t6g_mb_lib.t6g(sch_1):page48_i252@pure_quanta.q_res(chips)';

PART_NAME
 R58 'Q_RES_0402LF-0,5%,1/16W,CHIP,CS00002JB38':;

SECTION_NUMBER 1
 '@T6G_MB_LIB.T6G(SCH_1):PAGE48_I251@PURE_QUANTA.Q_RES(CHIPS)':
 C_PATH='@t6g_mb_lib.t6g(sch_1):page48_i251@pure_quanta.q_res(chips)';

PART_NAME
 R57 'Q_RES_0402LF-200,1%,1/16W,CHIP,CS12002FB25':;

SECTION_NUMBER 1
 '@T6G_MB_LIB.T6G(SCH_1):PAGE48_I253@PURE_QUANTA.Q_RES(CHIPS)':
 C_PATH='@t6g_mb_lib.t6g(sch_1):page48_i253@pure_quanta.q_res(chips)';

PART_NAME
 R56 'Q_RES_0402LF-0,5%,1/16W,CHIP,CS00002JB38':;

SECTION_NUMBER 1
 '@T6G_MB_LIB.T6G(SCH_1):PAGE48_I250@PURE_QUANTA.Q_RES(CHIPS)':
 C_PATH='@t6g_mb_lib.t6g(sch_1):page48_i250@pure_quanta.q_res(chips)';

PART_NAME
 R55 'Q_RES_0402LF-0,5%,1/16W,CHIP,CS00002JB38':;

SECTION_NUMBER 1
 '@T6G_MB_LIB.T6G(SCH_1):PAGE48_I249@PURE_QUANTA.Q_RES(CHIPS)':
 C_PATH='@t6g_mb_lib.t6g(sch_1):page48_i249@pure_quanta.q_res(chips)';

PART_NAME
 R54 'Q_RES_0402LF-10,1%,1/16W,CHIP,TMP_QCS01002FB21':;

SECTION_NUMBER 1
 '@T6G_MB_LIB.T6G(SCH_1):PAGE50_I61@PURE_QUANTA.Q_RES(CHIPS)':
 C_PATH='@t6g_mb_lib.t6g(sch_1):page50_i61@pure_quanta.q_res(chips)';

PART_NAME
 R53 'Q_RES_0402LF-10,1%,1/16W,CHIP,TMP_QCS01002FB21':;

SECTION_NUMBER 1
 '@T6G_MB_LIB.T6G(SCH_1):PAGE50_I62@PURE_QUANTA.Q_RES(CHIPS)':
 C_PATH='@t6g_mb_lib.t6g(sch_1):page50_i62@pure_quanta.q_res(chips)';

PART_NAME
 R52 'Q_RES_0402LF-100,1%,1/16W,CHIP,TMP_QCS11002FB22':;

SECTION_NUMBER 1
 '@T6G_MB_LIB.T6G(SCH_1):PAGE50_I63@PURE_QUANTA.Q_RES(CHIPS)':
 C_PATH='@t6g_mb_lib.t6g(sch_1):page50_i63@pure_quanta.q_res(chips)';

PART_NAME
 R51 'Q_RES_0402LF-100,1%,1/16W,CHIP,TMP_QCS11002FB22':;

SECTION_NUMBER 1
 '@T6G_MB_LIB.T6G(SCH_1):PAGE50_I60@PURE_QUANTA.Q_RES(CHIPS)':
 C_PATH='@t6g_mb_lib.t6g(sch_1):page50_i60@pure_quanta.q_res(chips)';

PART_NAME
 R50 'Q_RES_0402LF-499,1%,1/16W,CHIP,CS14992FB24':;

SECTION_NUMBER 1
 '@T6G_MB_LIB.T6G(SCH_1):PAGE50_I49@PURE_QUANTA.Q_RES(CHIPS)':
 C_PATH='@t6g_mb_lib.t6g(sch_1):page50_i49@pure_quanta.q_res(chips)';

PART_NAME
 R49 'Q_RES_0402LF-499,1%,1/16W,CHIP,CS14992FB24':;

SECTION_NUMBER 1
 '@T6G_MB_LIB.T6G(SCH_1):PAGE50_I50@PURE_QUANTA.Q_RES(CHIPS)':
 C_PATH='@t6g_mb_lib.t6g(sch_1):page50_i50@pure_quanta.q_res(chips)';

PART_NAME
 R25 'Q_RES_0402LF-10,1%,1/16W,CHIP,TMP_QCS01002FB21':;

SECTION_NUMBER 1
 '@T6G_MB_LIB.T6G(SCH_1):PAGE19_I137@PURE_QUANTA.Q_RES(CHIPS)':
 C_PATH='@t6g_mb_lib.t6g(sch_1):page19_i137@pure_quanta.q_res(chips)';

PART_NAME
 R24 'Q_RES_0402LF-10,1%,1/16W,CHIP,TMP_QCS01002FB21':;

SECTION_NUMBER 1
 '@T6G_MB_LIB.T6G(SCH_1):PAGE19_I136@PURE_QUANTA.Q_RES(CHIPS)':
 C_PATH='@t6g_mb_lib.t6g(sch_1):page19_i136@pure_quanta.q_res(chips)';

PART_NAME
 R23 'Q_RES_0402LF-100,1%,1/16W,CHIP,TMP_QCS11002FB22':;

SECTION_NUMBER 1
 '@T6G_MB_LIB.T6G(SCH_1):PAGE19_I134@PURE_QUANTA.Q_RES(CHIPS)':
 C_PATH='@t6g_mb_lib.t6g(sch_1):page19_i134@pure_quanta.q_res(chips)';

PART_NAME
 R22 'Q_RES_0402LF-100,1%,1/16W,CHIP,TMP_QCS11002FB22':;

SECTION_NUMBER 1
 '@T6G_MB_LIB.T6G(SCH_1):PAGE19_I135@PURE_QUANTA.Q_RES(CHIPS)':
 C_PATH='@t6g_mb_lib.t6g(sch_1):page19_i135@pure_quanta.q_res(chips)';

PART_NAME
 R21 'Q_RES_0402LF-0,5%,1/16W,CHIP,CS00002JB38':;

SECTION_NUMBER 1
 '@T6G_MB_LIB.T6G(SCH_1):PAGE19_I138@PURE_QUANTA.Q_RES(CHIPS)':
 C_PATH='@t6g_mb_lib.t6g(sch_1):page19_i138@pure_quanta.q_res(chips)';

PART_NAME
 R20 'Q_RES_0402LF-0,5%,1/16W,CHIP,CS00002JB38':;

SECTION_NUMBER 1
 '@T6G_MB_LIB.T6G(SCH_1):PAGE19_I139@PURE_QUANTA.Q_RES(CHIPS)':
 C_PATH='@t6g_mb_lib.t6g(sch_1):page19_i139@pure_quanta.q_res(chips)';

PART_NAME
 R19 'Q_RES_0402LF-499,1%,1/16W,CHIP,CS14992FB24':;

SECTION_NUMBER 1
 '@T6G_MB_LIB.T6G(SCH_1):PAGE19_I140@PURE_QUANTA.Q_RES(CHIPS)':
 C_PATH='@t6g_mb_lib.t6g(sch_1):page19_i140@pure_quanta.q_res(chips)';

PART_NAME
 R18 'Q_RES_0402LF-499,1%,1/16W,CHIP,CS14992FB24':;

SECTION_NUMBER 1
 '@T6G_MB_LIB.T6G(SCH_1):PAGE19_I142@PURE_QUANTA.Q_RES(CHIPS)':
 C_PATH='@t6g_mb_lib.t6g(sch_1):page19_i142@pure_quanta.q_res(chips)';

PART_NAME
 R1902 'Q_RES_0402LF-10K,1%,1/16W,CHIP,TMP_QCS31002FB26':;

SECTION_NUMBER 1
 '@T6G_MB_LIB.T6G(SCH_1):PAGE192_I269@PURE_QUANTA.Q_RES(CHIPS)':
 C_PATH='@t6g_mb_lib.t6g(sch_1):page192_i269@pure_quanta.q_res(chips)';

PART_NAME
 R1901 'Q_RES_0402LF-10K,1%,1/16W,EMPTY,TMP_QCS31002FB26':;

SECTION_NUMBER 1
 '@T6G_MB_LIB.T6G(SCH_1):PAGE192_I271@PURE_QUANTA.Q_RES(CHIPS)':
 C_PATH='@t6g_mb_lib.t6g(sch_1):page192_i271@pure_quanta.q_res(chips)';

PART_NAME
 R1779 'Q_RES_0402LF-10K,1%,1/16W,CHIP,TMP_QCS31002FB26':;

SECTION_NUMBER 1
 '@T6G_MB_LIB.T6G(SCH_1):PAGE192_I243@PURE_QUANTA.Q_RES(CHIPS)':
 C_PATH='@t6g_mb_lib.t6g(sch_1):page192_i243@pure_quanta.q_res(chips)';

PART_NAME
 R1778 'Q_RES_0402LF-10K,1%,1/16W,CHIP,TMP_QCS31002FB26':;

SECTION_NUMBER 1
 '@T6G_MB_LIB.T6G(SCH_1):PAGE192_I242@PURE_QUANTA.Q_RES(CHIPS)':
 C_PATH='@t6g_mb_lib.t6g(sch_1):page192_i242@pure_quanta.q_res(chips)';

PART_NAME
 R1777 'Q_RES_0402LF-10K,1%,1/16W,EMPTY,TMP_QCS31002FB26':;

SECTION_NUMBER 1
 '@T6G_MB_LIB.T6G(SCH_1):PAGE192_I237@PURE_QUANTA.Q_RES(CHIPS)':
 C_PATH='@t6g_mb_lib.t6g(sch_1):page192_i237@pure_quanta.q_res(chips)';

PART_NAME
 R1776 'Q_RES_0402LF-10K,1%,1/16W,EMPTY,TMP_QCS31002FB26':;

SECTION_NUMBER 1
 '@T6G_MB_LIB.T6G(SCH_1):PAGE192_I236@PURE_QUANTA.Q_RES(CHIPS)':
 C_PATH='@t6g_mb_lib.t6g(sch_1):page192_i236@pure_quanta.q_res(chips)';

PART_NAME
 R1775 'Q_RES_0402LF-10K,1%,1/16W,CHIP,TMP_QCS31002FB26':;

SECTION_NUMBER 1
 '@T6G_MB_LIB.T6G(SCH_1):PAGE192_I234@PURE_QUANTA.Q_RES(CHIPS)':
 C_PATH='@t6g_mb_lib.t6g(sch_1):page192_i234@pure_quanta.q_res(chips)';

PART_NAME
 R1774 'Q_RES_0402LF-10K,1%,1/16W,CHIP,TMP_QCS31002FB26':;

SECTION_NUMBER 1
 '@T6G_MB_LIB.T6G(SCH_1):PAGE192_I233@PURE_QUANTA.Q_RES(CHIPS)':
 C_PATH='@t6g_mb_lib.t6g(sch_1):page192_i233@pure_quanta.q_res(chips)';

PART_NAME
 R1773 'Q_RES_0402LF-10K,1%,1/16W,CHIP,TMP_QCS31002FB26':;

SECTION_NUMBER 1
 '@T6G_MB_LIB.T6G(SCH_1):PAGE192_I232@PURE_QUANTA.Q_RES(CHIPS)':
 C_PATH='@t6g_mb_lib.t6g(sch_1):page192_i232@pure_quanta.q_res(chips)';

PART_NAME
 R1772 'Q_RES_0402LF-10K,1%,1/16W,CHIP,TMP_QCS31002FB26':;

SECTION_NUMBER 1
 '@T6G_MB_LIB.T6G(SCH_1):PAGE192_I231@PURE_QUANTA.Q_RES(CHIPS)':
 C_PATH='@t6g_mb_lib.t6g(sch_1):page192_i231@pure_quanta.q_res(chips)';

PART_NAME
 R1771 'Q_RES_0402LF-10K,1%,1/16W,CHIP,TMP_QCS31002FB26':;

SECTION_NUMBER 1
 '@T6G_MB_LIB.T6G(SCH_1):PAGE192_I251@PURE_QUANTA.Q_RES(CHIPS)':
 C_PATH='@t6g_mb_lib.t6g(sch_1):page192_i251@pure_quanta.q_res(chips)';

PART_NAME
 R1770 'Q_RES_0402LF-10K,1%,1/16W,CHIP,TMP_QCS31002FB26':;

SECTION_NUMBER 1
 '@T6G_MB_LIB.T6G(SCH_1):PAGE192_I250@PURE_QUANTA.Q_RES(CHIPS)':
 C_PATH='@t6g_mb_lib.t6g(sch_1):page192_i250@pure_quanta.q_res(chips)';

PART_NAME
 R1769 'Q_RES_0402LF-10K,1%,1/16W,EMPTY,TMP_QCS31002FB26':;

SECTION_NUMBER 1
 '@T6G_MB_LIB.T6G(SCH_1):PAGE192_I248@PURE_QUANTA.Q_RES(CHIPS)':
 C_PATH='@t6g_mb_lib.t6g(sch_1):page192_i248@pure_quanta.q_res(chips)';

PART_NAME
 R1768 'Q_RES_0402LF-10K,1%,1/16W,CHIP,TMP_QCS31002FB26':;

SECTION_NUMBER 1
 '@T6G_MB_LIB.T6G(SCH_1):PAGE192_I264@PURE_QUANTA.Q_RES(CHIPS)':
 C_PATH='@t6g_mb_lib.t6g(sch_1):page192_i264@pure_quanta.q_res(chips)';

PART_NAME
 R1767 'Q_RES_0402LF-1K,1%,1/16W,CHIP,TMP_QCS21002FB24':;

SECTION_NUMBER 1
 '@T6G_MB_LIB.T6G(SCH_1):PAGE192_I260@PURE_QUANTA.Q_RES(CHIPS)':
 C_PATH='@t6g_mb_lib.t6g(sch_1):page192_i260@pure_quanta.q_res(chips)';

PART_NAME
 R1766 'Q_RES_0402LF-10K,1%,1/16W,CHIP,TMP_QCS31002FB26':;

SECTION_NUMBER 1
 '@T6G_MB_LIB.T6G(SCH_1):PAGE192_I259@PURE_QUANTA.Q_RES(CHIPS)':
 C_PATH='@t6g_mb_lib.t6g(sch_1):page192_i259@pure_quanta.q_res(chips)';

PART_NAME
 R1758 'Q_RES_0402LF-10K,1%,1/16W,CHIP,TMP_QCS31002FB26':;

SECTION_NUMBER 1
 '@T6G_MB_LIB.T6G(SCH_1):PAGE192_I258@PURE_QUANTA.Q_RES(CHIPS)':
 C_PATH='@t6g_mb_lib.t6g(sch_1):page192_i258@pure_quanta.q_res(chips)';

PART_NAME
 R1262 'Q_RES_0402LF-10K,1%,1/16W,EMPTY,TMP_QCS31002FB26':;

SECTION_NUMBER 1
 '@T6G_MB_LIB.T6G(SCH_1):PAGE192_I238@PURE_QUANTA.Q_RES(CHIPS)':
 C_PATH='@t6g_mb_lib.t6g(sch_1):page192_i238@pure_quanta.q_res(chips)';

PART_NAME
 R71 'Q_RES_0402LF-10K,1%,1/16W,CHIP,TMP_QCS31002FB26':;

SECTION_NUMBER 1
 '@T6G_MB_LIB.T6G(SCH_1):PAGE192_I263@PURE_QUANTA.Q_RES(CHIPS)':
 C_PATH='@t6g_mb_lib.t6g(sch_1):page192_i263@pure_quanta.q_res(chips)';

PART_NAME
 R8 'Q_RES_0402LF-10K,1%,1/16W,CHIP,TMP_QCS31002FB26':;

SECTION_NUMBER 1
 '@T6G_MB_LIB.T6G(SCH_1):PAGE192_I262@PURE_QUANTA.Q_RES(CHIPS)':
 C_PATH='@t6g_mb_lib.t6g(sch_1):page192_i262@pure_quanta.q_res(chips)';

PART_NAME
 R3821 'Q_RES_0402LF-33,5%,1/16W,CHIP,CS03302JB29':;

SECTION_NUMBER 1
 '@T6G_MB_LIB.T6G(SCH_1):PAGE17_I357@PURE_QUANTA.Q_RES(CHIPS)':
 C_PATH='@t6g_mb_lib.t6g(sch_1):page17_i357@pure_quanta.q_res(chips)';

PART_NAME
 R3820 'Q_RES_0402LF-33,5%,1/16W,CHIP,CS03302JB29':;

SECTION_NUMBER 1
 '@T6G_MB_LIB.T6G(SCH_1):PAGE17_I356@PURE_QUANTA.Q_RES(CHIPS)':
 C_PATH='@t6g_mb_lib.t6g(sch_1):page17_i356@pure_quanta.q_res(chips)';

PART_NAME
 R556 'Q_RES_0402LF-49.9     ,1%  ,1/16W,CHIP,CS04992FB31':;

SECTION_NUMBER 1
 '@T6G_MB_LIB.T6G(SCH_1):PAGE17_I318@PURE_QUANTA.Q_RES(CHIPS)':
 C_PATH='@t6g_mb_lib.t6g(sch_1):page17_i318@pure_quanta.q_res(chips)';

PART_NAME
 R555 'Q_RES_0402LF-100,1%,1/16W,CHIP,TMP_QCS11002FB22':;

SECTION_NUMBER 1
 '@T6G_MB_LIB.T6G(SCH_1):PAGE17_I319@PURE_QUANTA.Q_RES(CHIPS)':
 C_PATH='@t6g_mb_lib.t6g(sch_1):page17_i319@pure_quanta.q_res(chips)';

PART_NAME
 R548 'Q_RES_0402LF-49.9     ,1%  ,1/16W,CHIP,CS04992FB31':;

SECTION_NUMBER 1
 '@T6G_MB_LIB.T6G(SCH_1):PAGE17_I313@PURE_QUANTA.Q_RES(CHIPS)':
 C_PATH='@t6g_mb_lib.t6g(sch_1):page17_i313@pure_quanta.q_res(chips)';

PART_NAME
 R328 'Q_RES_0402LF-100,1%,1/16W,CHIP,TMP_QCS11002FB22':;

SECTION_NUMBER 1
 '@T6G_MB_LIB.T6G(SCH_1):PAGE17_I284@PURE_QUANTA.Q_RES(CHIPS)':
 C_PATH='@t6g_mb_lib.t6g(sch_1):page17_i284@pure_quanta.q_res(chips)';

PART_NAME
 R322 'Q_RES_0402LF-33,5%,1/16W,CHIP,CS03302JB29':;

SECTION_NUMBER 1
 '@T6G_MB_LIB.T6G(SCH_1):PAGE17_I351@PURE_QUANTA.Q_RES(CHIPS)':
 C_PATH='@t6g_mb_lib.t6g(sch_1):page17_i351@pure_quanta.q_res(chips)';

PART_NAME
 R317 'Q_RES_0402LF-49.9     ,1%  ,1/16W,CHIP,CS04992FB31':;

SECTION_NUMBER 1
 '@T6G_MB_LIB.T6G(SCH_1):PAGE17_I312@PURE_QUANTA.Q_RES(CHIPS)':
 C_PATH='@t6g_mb_lib.t6g(sch_1):page17_i312@pure_quanta.q_res(chips)';

PART_NAME
 R17 'Q_RES_0402LF-200,1%,1/16W,CHIP,CS12002FB25':;

SECTION_NUMBER 1
 '@T6G_MB_LIB.T6G(SCH_1):PAGE17_I296@PURE_QUANTA.Q_RES(CHIPS)':
 C_PATH='@t6g_mb_lib.t6g(sch_1):page17_i296@pure_quanta.q_res(chips)';

PART_NAME
 R16 'Q_RES_0402LF-0,5%,1/16W,CHIP,CS00002JB38':;

SECTION_NUMBER 1
 '@T6G_MB_LIB.T6G(SCH_1):PAGE17_I295@PURE_QUANTA.Q_RES(CHIPS)':
 C_PATH='@t6g_mb_lib.t6g(sch_1):page17_i295@pure_quanta.q_res(chips)';

PART_NAME
 R15 'Q_RES_0402LF-0,5%,1/16W,CHIP,CS00002JB38':;

SECTION_NUMBER 1
 '@T6G_MB_LIB.T6G(SCH_1):PAGE17_I294@PURE_QUANTA.Q_RES(CHIPS)':
 C_PATH='@t6g_mb_lib.t6g(sch_1):page17_i294@pure_quanta.q_res(chips)';

PART_NAME
 R14 'Q_RES_0402LF-200,1%,1/16W,CHIP,CS12002FB25':;

SECTION_NUMBER 1
 '@T6G_MB_LIB.T6G(SCH_1):PAGE17_I293@PURE_QUANTA.Q_RES(CHIPS)':
 C_PATH='@t6g_mb_lib.t6g(sch_1):page17_i293@pure_quanta.q_res(chips)';

PART_NAME
 R13 'Q_RES_0402LF-0,5%,1/16W,CHIP,CS00002JB38':;

SECTION_NUMBER 1
 '@T6G_MB_LIB.T6G(SCH_1):PAGE17_I292@PURE_QUANTA.Q_RES(CHIPS)':
 C_PATH='@t6g_mb_lib.t6g(sch_1):page17_i292@pure_quanta.q_res(chips)';

PART_NAME
 R12 'Q_RES_0402LF-0,5%,1/16W,CHIP,CS00002JB38':;

SECTION_NUMBER 1
 '@T6G_MB_LIB.T6G(SCH_1):PAGE17_I291@PURE_QUANTA.Q_RES(CHIPS)':
 C_PATH='@t6g_mb_lib.t6g(sch_1):page17_i291@pure_quanta.q_res(chips)';

PART_NAME
 R11 'Q_RES_0402LF-33,5%,1/16W,CHIP,CS03302JB29':;

SECTION_NUMBER 1
 '@T6G_MB_LIB.T6G(SCH_1):PAGE17_I350@PURE_QUANTA.Q_RES(CHIPS)':
 C_PATH='@t6g_mb_lib.t6g(sch_1):page17_i350@pure_quanta.q_res(chips)';

PART_NAME
 R10 'Q_RES_0402LF-33,5%,1/16W,CHIP,CS03302JB29':;

SECTION_NUMBER 1
 '@T6G_MB_LIB.T6G(SCH_1):PAGE17_I349@PURE_QUANTA.Q_RES(CHIPS)':
 C_PATH='@t6g_mb_lib.t6g(sch_1):page17_i349@pure_quanta.q_res(chips)';

PART_NAME
 R7 'Q_RES_0402LF-33,5%,1/16W,CHIP,CS03302JB29':;

SECTION_NUMBER 1
 '@T6G_MB_LIB.T6G(SCH_1):PAGE17_I329@PURE_QUANTA.Q_RES(CHIPS)':
 C_PATH='@t6g_mb_lib.t6g(sch_1):page17_i329@pure_quanta.q_res(chips)';

PART_NAME
 R6 'Q_RES_0402LF-100,1%,1/16W,CHIP,TMP_QCS11002FB22':;

SECTION_NUMBER 1
 '@T6G_MB_LIB.T6G(SCH_1):PAGE16_I643@PURE_QUANTA.Q_RES(CHIPS)':
 C_PATH='@t6g_mb_lib.t6g(sch_1):page16_i643@pure_quanta.q_res(chips)';

PART_NAME
 R5 'Q_RES_0402LF-100,1%,1/16W,CHIP,TMP_QCS11002FB22':;

SECTION_NUMBER 1
 '@T6G_MB_LIB.T6G(SCH_1):PAGE16_I642@PURE_QUANTA.Q_RES(CHIPS)':
 C_PATH='@t6g_mb_lib.t6g(sch_1):page16_i642@pure_quanta.q_res(chips)';

PART_NAME
 R4 'Q_RES_0402LF-200,1%,1/16W,CHIP,CS12002FB25':;

SECTION_NUMBER 1
 '@T6G_MB_LIB.T6G(SCH_1):PAGE16_I641@PURE_QUANTA.Q_RES(CHIPS)':
 C_PATH='@t6g_mb_lib.t6g(sch_1):page16_i641@pure_quanta.q_res(chips)';

PART_NAME
 R3 'Q_RES_0402LF-33,5%,1/16W,CHIP,CS03302JB29':;

SECTION_NUMBER 1
 '@T6G_MB_LIB.T6G(SCH_1):PAGE16_I640@PURE_QUANTA.Q_RES(CHIPS)':
 C_PATH='@t6g_mb_lib.t6g(sch_1):page16_i640@pure_quanta.q_res(chips)';

PART_NAME
 R2 'Q_RES_0402LF-100,1%,1/16W,CHIP,TMP_QCS11002FB22':;

SECTION_NUMBER 1
 '@T6G_MB_LIB.T6G(SCH_1):PAGE16_I639@PURE_QUANTA.Q_RES(CHIPS)':
 C_PATH='@t6g_mb_lib.t6g(sch_1):page16_i639@pure_quanta.q_res(chips)';

PART_NAME
 R1 'Q_RES_0402LF-10,1%,1/16W,CHIP,TMP_QCS01002FB21':;

SECTION_NUMBER 1
 '@T6G_MB_LIB.T6G(SCH_1):PAGE16_I634@PURE_QUANTA.Q_RES(CHIPS)':
 C_PATH='@t6g_mb_lib.t6g(sch_1):page16_i634@pure_quanta.q_res(chips)';

PART_NAME
 R3721 'Q_RES_0402LF-10K,1%,1/16W,CHIP,TMP_QCS31002FB26':;

SECTION_NUMBER 1
 '@T6G_MB_LIB.T6G(SCH_1):PAGE187_I38@PURE_QUANTA.Q_RES(CHIPS)':
 C_PATH='@t6g_mb_lib.t6g(sch_1):page187_i38@pure_quanta.q_res(chips)';

PART_NAME
 R3673 'Q_RES_0402LF-33,5%,1/16W,CHIP,CS03302JB29':;

SECTION_NUMBER 1
 '@T6G_MB_LIB.T6G(SCH_1):PAGE187_I32@PURE_QUANTA.Q_RES(CHIPS)':
 C_PATH='@t6g_mb_lib.t6g(sch_1):page187_i32@pure_quanta.q_res(chips)';

PART_NAME
 R3671 'Q_RES_0402LF-33,5%,1/16W,CHIP,CS03302JB29':;

SECTION_NUMBER 1
 '@T6G_MB_LIB.T6G(SCH_1):PAGE187_I30@PURE_QUANTA.Q_RES(CHIPS)':
 C_PATH='@t6g_mb_lib.t6g(sch_1):page187_i30@pure_quanta.q_res(chips)';

PART_NAME
 R3555 'Q_RES_0402LF-33,5%,1/16W,CHIP,CS03302JB29':;

SECTION_NUMBER 1
 '@T6G_MB_LIB.T6G(SCH_1):PAGE187_I24@PURE_QUANTA.Q_RES(CHIPS)':
 C_PATH='@t6g_mb_lib.t6g(sch_1):page187_i24@pure_quanta.q_res(chips)';

PART_NAME
 R3554 'Q_RES_0402LF-33,5%,1/16W,CHIP,CS03302JB29':;

SECTION_NUMBER 1
 '@T6G_MB_LIB.T6G(SCH_1):PAGE187_I21@PURE_QUANTA.Q_RES(CHIPS)':
 C_PATH='@t6g_mb_lib.t6g(sch_1):page187_i21@pure_quanta.q_res(chips)';

PART_NAME
 R1584 'Q_RES_0402LF-4.7K,5%,1/16W,CHIP,TMP_QCS24702JB38':;

SECTION_NUMBER 1
 '@T6G_MB_LIB.T6G(SCH_1):PAGE187_I36@PURE_QUANTA.Q_RES(CHIPS)':
 C_PATH='@t6g_mb_lib.t6g(sch_1):page187_i36@pure_quanta.q_res(chips)';

PART_NAME
 R492 'Q_RES_0402LF-33,5%,1/16W,CHIP,CS03302JB29':
;

SECTION_NUMBER 1
 '@T6G_MB_LIB.T6G(SCH_1):PAGE187_I14@PURE_QUANTA.Q_RES(CHIPS)':
 C_PATH='@t6g_mb_lib.t6g(sch_1):page187_i14@pure_quanta.q_res(chips)';

PART_NAME
 R488 'Q_RES_0402LF-33,5%,1/16W,CHIP,CS03302JB29':
;

SECTION_NUMBER 1
 '@T6G_MB_LIB.T6G(SCH_1):PAGE187_I6@PURE_QUANTA.Q_RES(CHIPS)':
 C_PATH='@t6g_mb_lib.t6g(sch_1):page187_i6@pure_quanta.q_res(chips)';

PART_NAME
 Q227 'MOSFET_NCH_DUAL-2N7002KDW,SMLF,IC,BAM70020047':;

SECTION_NUMBER 1
 '@T6G_MB_LIB.T6G(SCH_1):PAGE187_I41@PURE_QUANTA.MOSFET_NCH_DUAL(CHIPS)':
 C_PATH='@t6g_mb_lib.t6g(sch_1):page187_i41@pure_quanta.mosfet_nch_dual(chips)';

SECTION_NUMBER 2
 '@T6G_MB_LIB.T6G(SCH_1):PAGE187_I40@PURE_QUANTA.MOSFET_NCH_DUAL(CHIPS)':
 C_PATH='@t6g_mb_lib.t6g(sch_1):page187_i40@pure_quanta.mosfet_nch_dual(chips)';

PART_NAME
 R3841 'Q_RES_0402LF-10K,1%,1/16W,CHIP,TMP_QCS31002FB26':;

SECTION_NUMBER 1
 '@T6G_MB_LIB.T6G(SCH_1):PAGE181_I574@PURE_QUANTA.Q_RES(CHIPS)':
 C_PATH='@t6g_mb_lib.t6g(sch_1):page181_i574@pure_quanta.q_res(chips)';

PART_NAME
 R3840 'Q_RES_0402LF-10K,1%,1/16W,CHIP,TMP_QCS31002FB26':;

SECTION_NUMBER 1
 '@T6G_MB_LIB.T6G(SCH_1):PAGE181_I569@PURE_QUANTA.Q_RES(CHIPS)':
 C_PATH='@t6g_mb_lib.t6g(sch_1):page181_i569@pure_quanta.q_res(chips)';

PART_NAME
 R3839 'Q_RES_0402LF-10K,1%,1/16W,CHIP,TMP_QCS31002FB26':;

SECTION_NUMBER 1
 '@T6G_MB_LIB.T6G(SCH_1):PAGE181_I556@PURE_QUANTA.Q_RES(CHIPS)':
 C_PATH='@t6g_mb_lib.t6g(sch_1):page181_i556@pure_quanta.q_res(chips)';

PART_NAME
 R3838 'Q_RES_0402LF-10K,1%,1/16W,CHIP,TMP_QCS31002FB26':;

SECTION_NUMBER 1
 '@T6G_MB_LIB.T6G(SCH_1):PAGE181_I546@PURE_QUANTA.Q_RES(CHIPS)':
 C_PATH='@t6g_mb_lib.t6g(sch_1):page181_i546@pure_quanta.q_res(chips)';

PART_NAME
 R3728 'Q_RES_0402LF-499,1%,1/16W,CHIP,CS14992FB24':;

SECTION_NUMBER 1
 '@T6G_MB_LIB.T6G(SCH_1):PAGE181_I566@PURE_QUANTA.Q_RES(CHIPS)':
 C_PATH='@t6g_mb_lib.t6g(sch_1):page181_i566@pure_quanta.q_res(chips)';

PART_NAME
 R3727 'Q_RES_0402LF-499,1%,1/16W,CHIP,CS14992FB24':;

SECTION_NUMBER 1
 '@T6G_MB_LIB.T6G(SCH_1):PAGE181_I562@PURE_QUANTA.Q_RES(CHIPS)':
 C_PATH='@t6g_mb_lib.t6g(sch_1):page181_i562@pure_quanta.q_res(chips)';

PART_NAME
 R3725 'Q_RES_0402LF-499,1%,1/16W,CHIP,CS14992FB24':;

SECTION_NUMBER 1
 '@T6G_MB_LIB.T6G(SCH_1):PAGE181_I552@PURE_QUANTA.Q_RES(CHIPS)':
 C_PATH='@t6g_mb_lib.t6g(sch_1):page181_i552@pure_quanta.q_res(chips)';

PART_NAME
 R3724 'Q_RES_0402LF-499,1%,1/16W,CHIP,CS14992FB24':;

SECTION_NUMBER 1
 '@T6G_MB_LIB.T6G(SCH_1):PAGE181_I542@PURE_QUANTA.Q_RES(CHIPS)':
 C_PATH='@t6g_mb_lib.t6g(sch_1):page181_i542@pure_quanta.q_res(chips)';

PART_NAME
 R3670 'Q_RES_0402LF-100K,5%,1/16W,CHIP,CS41002JB20':;

SECTION_NUMBER 1
 '@T6G_MB_LIB.T6G(SCH_1):PAGE181_I463@PURE_QUANTA.Q_RES(CHIPS)':
 C_PATH='@t6g_mb_lib.t6g(sch_1):page181_i463@pure_quanta.q_res(chips)';

PART_NAME
 R3664 'Q_RES_0402LF-100K,5%,1/16W,CHIP,CS41002JB20':;

SECTION_NUMBER 1
 '@T6G_MB_LIB.T6G(SCH_1):PAGE181_I455@PURE_QUANTA.Q_RES(CHIPS)':
 C_PATH='@t6g_mb_lib.t6g(sch_1):page181_i455@pure_quanta.q_res(chips)';

PART_NAME
 R3662 'Q_RES_0402LF-100K,5%,1/16W,CHIP,CS41002JB20':;

SECTION_NUMBER 1
 '@T6G_MB_LIB.T6G(SCH_1):PAGE181_I457@PURE_QUANTA.Q_RES(CHIPS)':
 C_PATH='@t6g_mb_lib.t6g(sch_1):page181_i457@pure_quanta.q_res(chips)';

PART_NAME
 R3661 'Q_RES_0402LF-100K,5%,1/16W,CHIP,CS41002JB20':;

SECTION_NUMBER 1
 '@T6G_MB_LIB.T6G(SCH_1):PAGE181_I458@PURE_QUANTA.Q_RES(CHIPS)':
 C_PATH='@t6g_mb_lib.t6g(sch_1):page181_i458@pure_quanta.q_res(chips)';

PART_NAME
 R3660 'Q_RES_0402LF-100K,5%,1/16W,CHIP,CS41002JB20':;

SECTION_NUMBER 1
 '@T6G_MB_LIB.T6G(SCH_1):PAGE181_I459@PURE_QUANTA.Q_RES(CHIPS)':
 C_PATH='@t6g_mb_lib.t6g(sch_1):page181_i459@pure_quanta.q_res(chips)';

PART_NAME
 R3659 'Q_RES_0402LF-100K,5%,1/16W,CHIP,CS41002JB20':;

SECTION_NUMBER 1
 '@T6G_MB_LIB.T6G(SCH_1):PAGE181_I460@PURE_QUANTA.Q_RES(CHIPS)':
 C_PATH='@t6g_mb_lib.t6g(sch_1):page181_i460@pure_quanta.q_res(chips)';

PART_NAME
 R3658 'Q_RES_0402LF-100K,5%,1/16W,CHIP,CS41002JB20':;

SECTION_NUMBER 1
 '@T6G_MB_LIB.T6G(SCH_1):PAGE181_I461@PURE_QUANTA.Q_RES(CHIPS)':
 C_PATH='@t6g_mb_lib.t6g(sch_1):page181_i461@pure_quanta.q_res(chips)';

PART_NAME
 R3657 'Q_RES_0402LF-100K,5%,1/16W,CHIP,CS41002JB20':;

SECTION_NUMBER 1
 '@T6G_MB_LIB.T6G(SCH_1):PAGE181_I462@PURE_QUANTA.Q_RES(CHIPS)':
 C_PATH='@t6g_mb_lib.t6g(sch_1):page181_i462@pure_quanta.q_res(chips)';

PART_NAME
 Q134 'MOSFET_NCH_DUAL-2N7002KDW,SMLF,IC,BAM70020047':;

SECTION_NUMBER 1
 '@T6G_MB_LIB.T6G(SCH_1):PAGE181_I577@PURE_QUANTA.MOSFET_NCH_DUAL(CHIPS)':
 C_PATH='@t6g_mb_lib.t6g(sch_1):page181_i577@pure_quanta.mosfet_nch_dual(chips)';

SECTION_NUMBER 2
 '@T6G_MB_LIB.T6G(SCH_1):PAGE181_I572@PURE_QUANTA.MOSFET_NCH_DUAL(CHIPS)':
 C_PATH='@t6g_mb_lib.t6g(sch_1):page181_i572@pure_quanta.mosfet_nch_dual(chips)';

PART_NAME
 Q133 'MOSFET_NCH_DUAL-2N7002KDW,SMLF,IC,BAM70020047':;

SECTION_NUMBER 1
 '@T6G_MB_LIB.T6G(SCH_1):PAGE181_I570@PURE_QUANTA.MOSFET_NCH_DUAL(CHIPS)':
 C_PATH='@t6g_mb_lib.t6g(sch_1):page181_i570@pure_quanta.mosfet_nch_dual(chips)';

SECTION_NUMBER 2
 '@T6G_MB_LIB.T6G(SCH_1):PAGE181_I568@PURE_QUANTA.MOSFET_NCH_DUAL(CHIPS)':
 C_PATH='@t6g_mb_lib.t6g(sch_1):page181_i568@pure_quanta.mosfet_nch_dual(chips)';

PART_NAME
 Q132 'MOSFET_NCH_DUAL-2N7002KDW,SMLF,IC,BAM70020047':;

SECTION_NUMBER 1
 '@T6G_MB_LIB.T6G(SCH_1):PAGE181_I558@PURE_QUANTA.MOSFET_NCH_DUAL(CHIPS)':
 C_PATH='@t6g_mb_lib.t6g(sch_1):page181_i558@pure_quanta.mosfet_nch_dual(chips)';

SECTION_NUMBER 2
 '@T6G_MB_LIB.T6G(SCH_1):PAGE181_I555@PURE_QUANTA.MOSFET_NCH_DUAL(CHIPS)':
 C_PATH='@t6g_mb_lib.t6g(sch_1):page181_i555@pure_quanta.mosfet_nch_dual(chips)';

PART_NAME
 Q131 'MOSFET_NCH_DUAL-2N7002KDW,SMLF,IC,BAM70020047':;

SECTION_NUMBER 1
 '@T6G_MB_LIB.T6G(SCH_1):PAGE181_I548@PURE_QUANTA.MOSFET_NCH_DUAL(CHIPS)':
 C_PATH='@t6g_mb_lib.t6g(sch_1):page181_i548@pure_quanta.mosfet_nch_dual(chips)';

SECTION_NUMBER 2
 '@T6G_MB_LIB.T6G(SCH_1):PAGE181_I543@PURE_QUANTA.MOSFET_NCH_DUAL(CHIPS)':
 C_PATH='@t6g_mb_lib.t6g(sch_1):page181_i543@pure_quanta.mosfet_nch_dual(chips)';

PART_NAME
 R1930 'Q_RES_0402LF-0,5%,1/16W,EMPTY,CS00002JB38':;

SECTION_NUMBER 1
 '@T6G_MB_LIB.T6G(SCH_1):PAGE196_I55@PURE_QUANTA.Q_RES(CHIPS)':
 C_PATH='@t6g_mb_lib.t6g(sch_1):page196_i55@pure_quanta.q_res(chips)';

PART_NAME
 R1927 'Q_RES_0402LF-0,5%,1/16W,EMPTY,CS00002JB38':;

SECTION_NUMBER 1
 '@T6G_MB_LIB.T6G(SCH_1):PAGE196_I53@PURE_QUANTA.Q_RES(CHIPS)':
 C_PATH='@t6g_mb_lib.t6g(sch_1):page196_i53@pure_quanta.q_res(chips)';

PART_NAME
 R1926 'Q_RES_0402LF-10K,1%,1/16W,CHIP,TMP_QCS31002FB26':;

SECTION_NUMBER 1
 '@T6G_MB_LIB.T6G(SCH_1):PAGE196_I72@PURE_QUANTA.Q_RES(CHIPS)':
 C_PATH='@t6g_mb_lib.t6g(sch_1):page196_i72@pure_quanta.q_res(chips)';

PART_NAME
 R1925 'Q_RES_0402LF-33,5%,1/16W,CHIP,CS03302JB29':;

SECTION_NUMBER 1
 '@T6G_MB_LIB.T6G(SCH_1):PAGE196_I66@PURE_QUANTA.Q_RES(CHIPS)':
 C_PATH='@t6g_mb_lib.t6g(sch_1):page196_i66@pure_quanta.q_res(chips)';

PART_NAME
 R1924 'Q_RES_0402LF-0,5%,1/16W,EMPTY,CS00002JB38':;

SECTION_NUMBER 1
 '@T6G_MB_LIB.T6G(SCH_1):PAGE196_I60@PURE_QUANTA.Q_RES(CHIPS)':
 C_PATH='@t6g_mb_lib.t6g(sch_1):page196_i60@pure_quanta.q_res(chips)';

PART_NAME
 R1820 'Q_RES_0402LF-10K,1%,1/16W,CHIP,TMP_QCS31002FB26':;

SECTION_NUMBER 1
 '@T6G_MB_LIB.T6G(SCH_1):PAGE196_I76@PURE_QUANTA.Q_RES(CHIPS)':
 C_PATH='@t6g_mb_lib.t6g(sch_1):page196_i76@pure_quanta.q_res(chips)';

PART_NAME
 R1266 'Q_RES_0402LF-49.9     ,1%  ,1/16W,CHIP,CS04992FB31':;

SECTION_NUMBER 1
 '@T6G_MB_LIB.T6G(SCH_1):PAGE196_I59@PURE_QUANTA.Q_RES(CHIPS)':
 C_PATH='@t6g_mb_lib.t6g(sch_1):page196_i59@pure_quanta.q_res(chips)';

PART_NAME
 R1265 'Q_RES_0402LF-10K,1%,1/16W,CHIP,TMP_QCS31002FB26':;

SECTION_NUMBER 1
 '@T6G_MB_LIB.T6G(SCH_1):PAGE196_I68@PURE_QUANTA.Q_RES(CHIPS)':
 C_PATH='@t6g_mb_lib.t6g(sch_1):page196_i68@pure_quanta.q_res(chips)';

PART_NAME
 R1249 'Q_RES_0402LF-0,5%,1/16W,CHIP,CS00002JB38':;

SECTION_NUMBER 1
 '@T6G_MB_LIB.T6G(SCH_1):PAGE196_I65@PURE_QUANTA.Q_RES(CHIPS)':
 C_PATH='@t6g_mb_lib.t6g(sch_1):page196_i65@pure_quanta.q_res(chips)';

PART_NAME
 R1247 'Q_RES_0402LF-0,5%,1/16W,CHIP,CS00002JB38':;

SECTION_NUMBER 1
 '@T6G_MB_LIB.T6G(SCH_1):PAGE196_I74@PURE_QUANTA.Q_RES(CHIPS)':
 C_PATH='@t6g_mb_lib.t6g(sch_1):page196_i74@pure_quanta.q_res(chips)';

PART_NAME
 R1246 'Q_RES_0402LF-0,5%,1/16W,EMPTY,CS00002JB38':;

SECTION_NUMBER 1
 '@T6G_MB_LIB.T6G(SCH_1):PAGE196_I73@PURE_QUANTA.Q_RES(CHIPS)':
 C_PATH='@t6g_mb_lib.t6g(sch_1):page196_i73@pure_quanta.q_res(chips)';

PART_NAME
 Q115 'MOSFET_N_123-BSS123-7-F,SMLF,IC,BAM01230014':;

SECTION_NUMBER 1
 '@T6G_MB_LIB.T6G(SCH_1):PAGE196_I63@PURE_QUANTA.MOSFET_N_123(CHIPS)':
 C_PATH='@t6g_mb_lib.t6g(sch_1):page196_i63@pure_quanta.mosfet_n_123(chips)';

PART_NAME
 Q100 'MOSFET_NCH_DUAL-2N7002KDW,SMLF,IC,BAM70020047':;

SECTION_NUMBER 1
 '@T6G_MB_LIB.T6G(SCH_1):PAGE196_I70@PURE_QUANTA.MOSFET_NCH_DUAL(CHIPS)':
 C_PATH='@t6g_mb_lib.t6g(sch_1):page196_i70@pure_quanta.mosfet_nch_dual(chips)';

SECTION_NUMBER 2
 '@T6G_MB_LIB.T6G(SCH_1):PAGE196_I57@PURE_QUANTA.MOSFET_NCH_DUAL(CHIPS)':
 C_PATH='@t6g_mb_lib.t6g(sch_1):page196_i57@pure_quanta.mosfet_nch_dual(chips)';

PART_NAME
 R3583 'Q_RES_0402LF-10K,1%,1/16W,CHIP,TMP_QCS31002FB26':;

SECTION_NUMBER 1
 '@T6G_MB_LIB.T6G(SCH_1):PAGE248_I243@PURE_QUANTA.Q_RES(CHIPS)':
 C_PATH='@t6g_mb_lib.t6g(sch_1):page248_i243@pure_quanta.q_res(chips)';

PART_NAME
 R3582 'Q_RES_0402LF-10K,1%,1/16W,CHIP,TMP_QCS31002FB26':;

SECTION_NUMBER 1
 '@T6G_MB_LIB.T6G(SCH_1):PAGE248_I232@PURE_QUANTA.Q_RES(CHIPS)':
 C_PATH='@t6g_mb_lib.t6g(sch_1):page248_i232@pure_quanta.q_res(chips)';

PART_NAME
 R3581 'Q_RES_0402LF-10K,1%,1/16W,CHIP,TMP_QCS31002FB26':;

SECTION_NUMBER 1
 '@T6G_MB_LIB.T6G(SCH_1):PAGE248_I221@PURE_QUANTA.Q_RES(CHIPS)':
 C_PATH='@t6g_mb_lib.t6g(sch_1):page248_i221@pure_quanta.q_res(chips)';

PART_NAME
 R3580 'Q_RES_0402LF-10K,1%,1/16W,CHIP,TMP_QCS31002FB26':;

SECTION_NUMBER 1
 '@T6G_MB_LIB.T6G(SCH_1):PAGE248_I239@PURE_QUANTA.Q_RES(CHIPS)':
 C_PATH='@t6g_mb_lib.t6g(sch_1):page248_i239@pure_quanta.q_res(chips)';

PART_NAME
 R3579 'Q_RES_0402LF-10K,1%,1/16W,CHIP,TMP_QCS31002FB26':;

SECTION_NUMBER 1
 '@T6G_MB_LIB.T6G(SCH_1):PAGE248_I228@PURE_QUANTA.Q_RES(CHIPS)':
 C_PATH='@t6g_mb_lib.t6g(sch_1):page248_i228@pure_quanta.q_res(chips)';

PART_NAME
 R3578 'Q_RES_0402LF-10K,1%,1/16W,CHIP,TMP_QCS31002FB26':;

SECTION_NUMBER 1
 '@T6G_MB_LIB.T6G(SCH_1):PAGE248_I217@PURE_QUANTA.Q_RES(CHIPS)':
 C_PATH='@t6g_mb_lib.t6g(sch_1):page248_i217@pure_quanta.q_res(chips)';

PART_NAME
 R3577 'Q_RES_0402LF-10K,1%,1/16W,CHIP,TMP_QCS31002FB26':;

SECTION_NUMBER 1
 '@T6G_MB_LIB.T6G(SCH_1):PAGE248_I210@PURE_QUANTA.Q_RES(CHIPS)':
 C_PATH='@t6g_mb_lib.t6g(sch_1):page248_i210@pure_quanta.q_res(chips)';

PART_NAME
 R3576 'Q_RES_0402LF-10K,1%,1/16W,CHIP,TMP_QCS31002FB26':;

SECTION_NUMBER 1
 '@T6G_MB_LIB.T6G(SCH_1):PAGE248_I193@PURE_QUANTA.Q_RES(CHIPS)':
 C_PATH='@t6g_mb_lib.t6g(sch_1):page248_i193@pure_quanta.q_res(chips)';

PART_NAME
 R3575 'Q_RES_0402LF-10K,1%,1/16W,CHIP,TMP_QCS31002FB26':;

SECTION_NUMBER 1
 '@T6G_MB_LIB.T6G(SCH_1):PAGE248_I182@PURE_QUANTA.Q_RES(CHIPS)':
 C_PATH='@t6g_mb_lib.t6g(sch_1):page248_i182@pure_quanta.q_res(chips)';

PART_NAME
 R3574 'Q_RES_0402LF-10K,1%,1/16W,CHIP,TMP_QCS31002FB26':;

SECTION_NUMBER 1
 '@T6G_MB_LIB.T6G(SCH_1):PAGE248_I206@PURE_QUANTA.Q_RES(CHIPS)':
 C_PATH='@t6g_mb_lib.t6g(sch_1):page248_i206@pure_quanta.q_res(chips)';

PART_NAME
 R3573 'Q_RES_0402LF-10K,1%,1/16W,CHIP,TMP_QCS31002FB26':;

SECTION_NUMBER 1
 '@T6G_MB_LIB.T6G(SCH_1):PAGE248_I197@PURE_QUANTA.Q_RES(CHIPS)':
 C_PATH='@t6g_mb_lib.t6g(sch_1):page248_i197@pure_quanta.q_res(chips)';

PART_NAME
 R3572 'Q_RES_0402LF-10K,1%,1/16W,CHIP,TMP_QCS31002FB26':;

SECTION_NUMBER 1
 '@T6G_MB_LIB.T6G(SCH_1):PAGE248_I186@PURE_QUANTA.Q_RES(CHIPS)':
 C_PATH='@t6g_mb_lib.t6g(sch_1):page248_i186@pure_quanta.q_res(chips)';

PART_NAME
 R3561 'Q_RES_0402LF-10K,1%,1/16W,CHIP,TMP_QCS31002FB26':;

SECTION_NUMBER 1
 '@T6G_MB_LIB.T6G(SCH_1):PAGE248_I152@PURE_QUANTA.Q_RES(CHIPS)':
 C_PATH='@t6g_mb_lib.t6g(sch_1):page248_i152@pure_quanta.q_res(chips)';

PART_NAME
 R3560 'Q_RES_0402LF-0,5%,1/16W,CHIP,CS00002JB38':;

SECTION_NUMBER 1
 '@T6G_MB_LIB.T6G(SCH_1):PAGE248_I142@PURE_QUANTA.Q_RES(CHIPS)':
 C_PATH='@t6g_mb_lib.t6g(sch_1):page248_i142@pure_quanta.q_res(chips)';

PART_NAME
 R3559 'Q_RES_0402LF-10K,1%,1/16W,CHIP,TMP_QCS31002FB26':;

SECTION_NUMBER 1
 '@T6G_MB_LIB.T6G(SCH_1):PAGE248_I138@PURE_QUANTA.Q_RES(CHIPS)':
 C_PATH='@t6g_mb_lib.t6g(sch_1):page248_i138@pure_quanta.q_res(chips)';

PART_NAME
 R3558 'Q_RES_0402LF-10K,1%,1/16W,CHIP,TMP_QCS31002FB26':;

SECTION_NUMBER 1
 '@T6G_MB_LIB.T6G(SCH_1):PAGE248_I134@PURE_QUANTA.Q_RES(CHIPS)':
 C_PATH='@t6g_mb_lib.t6g(sch_1):page248_i134@pure_quanta.q_res(chips)';

PART_NAME
 R3557 'Q_RES_0402LF-0,5%,1/16W,CHIP,CS00002JB38':;

SECTION_NUMBER 1
 '@T6G_MB_LIB.T6G(SCH_1):PAGE248_I131@PURE_QUANTA.Q_RES(CHIPS)':
 C_PATH='@t6g_mb_lib.t6g(sch_1):page248_i131@pure_quanta.q_res(chips)';

PART_NAME
 R3499 'Q_RES_0402LF-10K,1%,1/16W,CHIP,TMP_QCS31002FB26':;

SECTION_NUMBER 1
 '@T6G_MB_LIB.T6G(SCH_1):PAGE248_I149@PURE_QUANTA.Q_RES(CHIPS)':
 C_PATH='@t6g_mb_lib.t6g(sch_1):page248_i149@pure_quanta.q_res(chips)';

PART_NAME
 R3132 'Q_RES_0402LF-33,5%,1/16W,CHIP,CS03302JB29':;

SECTION_NUMBER 1
 '@T6G_MB_LIB.T6G(SCH_1):PAGE248_I95@PURE_QUANTA.Q_RES(CHIPS)':
 C_PATH='@t6g_mb_lib.t6g(sch_1):page248_i95@pure_quanta.q_res(chips)';

PART_NAME
 R635 'Q_RES_0402LF-33,5%,1/16W,CHIP,CS03302JB29':;

SECTION_NUMBER 1
 '@T6G_MB_LIB.T6G(SCH_1):PAGE248_I255@PURE_QUANTA.Q_RES(CHIPS)':
 C_PATH='@t6g_mb_lib.t6g(sch_1):page248_i255@pure_quanta.q_res(chips)';

PART_NAME
 R634 'Q_RES_0402LF-33,5%,1/16W,CHIP,CS03302JB29':;

SECTION_NUMBER 1
 '@T6G_MB_LIB.T6G(SCH_1):PAGE248_I254@PURE_QUANTA.Q_RES(CHIPS)':
 C_PATH='@t6g_mb_lib.t6g(sch_1):page248_i254@pure_quanta.q_res(chips)';

PART_NAME
 R633 'Q_RES_0402LF-33,5%,1/16W,CHIP,CS03302JB29':;

SECTION_NUMBER 1
 '@T6G_MB_LIB.T6G(SCH_1):PAGE248_I253@PURE_QUANTA.Q_RES(CHIPS)':
 C_PATH='@t6g_mb_lib.t6g(sch_1):page248_i253@pure_quanta.q_res(chips)';

PART_NAME
 R528 'Q_RES_0402LF-33,5%,1/16W,CHIP,CS03302JB29':;

SECTION_NUMBER 1
 '@T6G_MB_LIB.T6G(SCH_1):PAGE248_I249@PURE_QUANTA.Q_RES(CHIPS)':
 C_PATH='@t6g_mb_lib.t6g(sch_1):page248_i249@pure_quanta.q_res(chips)';

PART_NAME
 R527 'Q_RES_0402LF-33,5%,1/16W,CHIP,CS03302JB29':;

SECTION_NUMBER 1
 '@T6G_MB_LIB.T6G(SCH_1):PAGE248_I247@PURE_QUANTA.Q_RES(CHIPS)':
 C_PATH='@t6g_mb_lib.t6g(sch_1):page248_i247@pure_quanta.q_res(chips)';

PART_NAME
 R526 'Q_RES_0402LF-33,5%,1/16W,CHIP,CS03302JB29':;

SECTION_NUMBER 1
 '@T6G_MB_LIB.T6G(SCH_1):PAGE248_I256@PURE_QUANTA.Q_RES(CHIPS)':
 C_PATH='@t6g_mb_lib.t6g(sch_1):page248_i256@pure_quanta.q_res(chips)';

PART_NAME
 Q126 'MOSFET_NCH_DUAL-2N7002KDW,SMLF,IC,BAM70020047':;

SECTION_NUMBER 1
 '@T6G_MB_LIB.T6G(SCH_1):PAGE248_I237@PURE_QUANTA.MOSFET_NCH_DUAL(CHIPS)':
 C_PATH='@t6g_mb_lib.t6g(sch_1):page248_i237@pure_quanta.mosfet_nch_dual(chips)';

SECTION_NUMBER 2
 '@T6G_MB_LIB.T6G(SCH_1):PAGE248_I241@PURE_QUANTA.MOSFET_NCH_DUAL(CHIPS)':
 C_PATH='@t6g_mb_lib.t6g(sch_1):page248_i241@pure_quanta.mosfet_nch_dual(chips)';

PART_NAME
 Q125 'MOSFET_NCH_DUAL-2N7002KDW,SMLF,IC,BAM70020047':;

SECTION_NUMBER 1
 '@T6G_MB_LIB.T6G(SCH_1):PAGE248_I226@PURE_QUANTA.MOSFET_NCH_DUAL(CHIPS)':
 C_PATH='@t6g_mb_lib.t6g(sch_1):page248_i226@pure_quanta.mosfet_nch_dual(chips)';

SECTION_NUMBER 2
 '@T6G_MB_LIB.T6G(SCH_1):PAGE248_I230@PURE_QUANTA.MOSFET_NCH_DUAL(CHIPS)':
 C_PATH='@t6g_mb_lib.t6g(sch_1):page248_i230@pure_quanta.mosfet_nch_dual(chips)';

PART_NAME
 Q124 'MOSFET_NCH_DUAL-2N7002KDW,SMLF,IC,BAM70020047':;

SECTION_NUMBER 1
 '@T6G_MB_LIB.T6G(SCH_1):PAGE248_I215@PURE_QUANTA.MOSFET_NCH_DUAL(CHIPS)':
 C_PATH='@t6g_mb_lib.t6g(sch_1):page248_i215@pure_quanta.mosfet_nch_dual(chips)';

SECTION_NUMBER 2
 '@T6G_MB_LIB.T6G(SCH_1):PAGE248_I219@PURE_QUANTA.MOSFET_NCH_DUAL(CHIPS)':
 C_PATH='@t6g_mb_lib.t6g(sch_1):page248_i219@pure_quanta.mosfet_nch_dual(chips)';

PART_NAME
 Q123 'MOSFET_NCH_DUAL-2N7002KDW,SMLF,IC,BAM70020047':;

SECTION_NUMBER 1
 '@T6G_MB_LIB.T6G(SCH_1):PAGE248_I204@PURE_QUANTA.MOSFET_NCH_DUAL(CHIPS)':
 C_PATH='@t6g_mb_lib.t6g(sch_1):page248_i204@pure_quanta.mosfet_nch_dual(chips)';

SECTION_NUMBER 2
 '@T6G_MB_LIB.T6G(SCH_1):PAGE248_I208@PURE_QUANTA.MOSFET_NCH_DUAL(CHIPS)':
 C_PATH='@t6g_mb_lib.t6g(sch_1):page248_i208@pure_quanta.mosfet_nch_dual(chips)';

PART_NAME
 Q122 'MOSFET_NCH_DUAL-2N7002KDW,SMLF,IC,BAM70020047':;

SECTION_NUMBER 1
 '@T6G_MB_LIB.T6G(SCH_1):PAGE248_I199@PURE_QUANTA.MOSFET_NCH_DUAL(CHIPS)':
 C_PATH='@t6g_mb_lib.t6g(sch_1):page248_i199@pure_quanta.mosfet_nch_dual(chips)';

SECTION_NUMBER 2
 '@T6G_MB_LIB.T6G(SCH_1):PAGE248_I195@PURE_QUANTA.MOSFET_NCH_DUAL(CHIPS)':
 C_PATH='@t6g_mb_lib.t6g(sch_1):page248_i195@pure_quanta.mosfet_nch_dual(chips)';

PART_NAME
 Q121 'MOSFET_NCH_DUAL-2N7002KDW,SMLF,IC,BAM70020047':;

SECTION_NUMBER 1
 '@T6G_MB_LIB.T6G(SCH_1):PAGE248_I188@PURE_QUANTA.MOSFET_NCH_DUAL(CHIPS)':
 C_PATH='@t6g_mb_lib.t6g(sch_1):page248_i188@pure_quanta.mosfet_nch_dual(chips)';

SECTION_NUMBER 2
 '@T6G_MB_LIB.T6G(SCH_1):PAGE248_I184@PURE_QUANTA.MOSFET_NCH_DUAL(CHIPS)':
 C_PATH='@t6g_mb_lib.t6g(sch_1):page248_i184@pure_quanta.mosfet_nch_dual(chips)';

PART_NAME
 Q99 'MOSFET_NCH_DUAL-2N7002KDW,SMLF,IC,BAM70020047':;

SECTION_NUMBER 1
 '@T6G_MB_LIB.T6G(SCH_1):PAGE248_I145@PURE_QUANTA.MOSFET_NCH_DUAL(CHIPS)':
 C_PATH='@t6g_mb_lib.t6g(sch_1):page248_i145@pure_quanta.mosfet_nch_dual(chips)';

SECTION_NUMBER 2
 '@T6G_MB_LIB.T6G(SCH_1):PAGE248_I151@PURE_QUANTA.MOSFET_NCH_DUAL(CHIPS)':
 C_PATH='@t6g_mb_lib.t6g(sch_1):page248_i151@pure_quanta.mosfet_nch_dual(chips)';

PART_NAME
 Q98 'MOSFET_NCH_DUAL-2N7002KDW,SMLF,IC,BAM70020047':;

SECTION_NUMBER 1
 '@T6G_MB_LIB.T6G(SCH_1):PAGE248_I132@PURE_QUANTA.MOSFET_NCH_DUAL(CHIPS)':
 C_PATH='@t6g_mb_lib.t6g(sch_1):page248_i132@pure_quanta.mosfet_nch_dual(chips)';

SECTION_NUMBER 2
 '@T6G_MB_LIB.T6G(SCH_1):PAGE248_I137@PURE_QUANTA.MOSFET_NCH_DUAL(CHIPS)':
 C_PATH='@t6g_mb_lib.t6g(sch_1):page248_i137@pure_quanta.mosfet_nch_dual(chips)';

PART_NAME
 R4086 'Q_RES_0402LF-10K,5%,1/16W,CHIP,TMP_QCS31002JB28':;

SECTION_NUMBER 1
 '@T6G_MB_LIB.T6G(SCH_1):PAGE339_I39@PURE_QUANTA.Q_RES(CHIPS)':
 C_PATH='@t6g_mb_lib.t6g(sch_1):page339_i39@pure_quanta.q_res(chips)';

PART_NAME
 R3933 'Q_RES_0402LF-10K,5%,1/16W,CHIP,TMP_QCS31002JB28':;

SECTION_NUMBER 1
 '@T6G_MB_LIB.T6G(SCH_1):PAGE339_I52@PURE_QUANTA.Q_RES(CHIPS)':
 C_PATH='@t6g_mb_lib.t6g(sch_1):page339_i52@pure_quanta.q_res(chips)';

PART_NAME
 R3931 'Q_RES_0402LF-0,5%,1/16W,CHIP,CS00002JB38':;

SECTION_NUMBER 1
 '@T6G_MB_LIB.T6G(SCH_1):PAGE339_I59@PURE_QUANTA.Q_RES(CHIPS)':
 C_PATH='@t6g_mb_lib.t6g(sch_1):page339_i59@pure_quanta.q_res(chips)';

PART_NAME
 R3927 'Q_RES_0402LF-0,5%,1/16W,CHIP,CS00002JB38':;

SECTION_NUMBER 1
 '@T6G_MB_LIB.T6G(SCH_1):PAGE339_I16@PURE_QUANTA.Q_RES(CHIPS)':
 C_PATH='@t6g_mb_lib.t6g(sch_1):page339_i16@pure_quanta.q_res(chips)';

PART_NAME
 R3919 'Q_RES_0402LF-10K,5%,1/16W,CHIP,TMP_QCS31002JB28':;

SECTION_NUMBER 1
 '@T6G_MB_LIB.T6G(SCH_1):PAGE339_I18@PURE_QUANTA.Q_RES(CHIPS)':
 C_PATH='@t6g_mb_lib.t6g(sch_1):page339_i18@pure_quanta.q_res(chips)';

PART_NAME
 R3748 'Q_RES_0402LF-10K,5%,1/16W,CHIP,TMP_QCS31002JB28':;

SECTION_NUMBER 1
 '@T6G_MB_LIB.T6G(SCH_1):PAGE339_I53@PURE_QUANTA.Q_RES(CHIPS)':
 C_PATH='@t6g_mb_lib.t6g(sch_1):page339_i53@pure_quanta.q_res(chips)';

PART_NAME
 R3747 'Q_RES_0402LF-10K,5%,1/16W,CHIP,TMP_QCS31002JB28':;

SECTION_NUMBER 1
 '@T6G_MB_LIB.T6G(SCH_1):PAGE339_I31@PURE_QUANTA.Q_RES(CHIPS)':
 C_PATH='@t6g_mb_lib.t6g(sch_1):page339_i31@pure_quanta.q_res(chips)';

PART_NAME
 R3746 'Q_RES_0402LF-10K,5%,1/16W,CHIP,TMP_QCS31002JB28':;

SECTION_NUMBER 1
 '@T6G_MB_LIB.T6G(SCH_1):PAGE339_I34@PURE_QUANTA.Q_RES(CHIPS)':
 C_PATH='@t6g_mb_lib.t6g(sch_1):page339_i34@pure_quanta.q_res(chips)';

PART_NAME
 R3745 'Q_RES_0402LF-10K,5%,1/16W,CHIP,TMP_QCS31002JB28':;

SECTION_NUMBER 1
 '@T6G_MB_LIB.T6G(SCH_1):PAGE339_I11@PURE_QUANTA.Q_RES(CHIPS)':
 C_PATH='@t6g_mb_lib.t6g(sch_1):page339_i11@pure_quanta.q_res(chips)';

PART_NAME
 R3744 'Q_RES_0402LF-10K,5%,1/16W,CHIP,TMP_QCS31002JB28':;

SECTION_NUMBER 1
 '@T6G_MB_LIB.T6G(SCH_1):PAGE339_I22@PURE_QUANTA.Q_RES(CHIPS)':
 C_PATH='@t6g_mb_lib.t6g(sch_1):page339_i22@pure_quanta.q_res(chips)';

PART_NAME
 Q80 'MOSFET_NCH_DUAL-2N7002KDW,SMLF,IC,BAM70020047':;

SECTION_NUMBER 1
 '@T6G_MB_LIB.T6G(SCH_1):PAGE339_I50@PURE_QUANTA.MOSFET_NCH_DUAL(CHIPS)':
 C_PATH='@t6g_mb_lib.t6g(sch_1):page339_i50@pure_quanta.mosfet_nch_dual(chips)';

SECTION_NUMBER 2
 '@T6G_MB_LIB.T6G(SCH_1):PAGE339_I56@PURE_QUANTA.MOSFET_NCH_DUAL(CHIPS)':
 C_PATH='@t6g_mb_lib.t6g(sch_1):page339_i56@pure_quanta.mosfet_nch_dual(chips)';

PART_NAME
 Q46 'MOSFET_NCH_DUAL-2N7002KDW,SMLF,IC,BAM70020047':;

SECTION_NUMBER 1
 '@T6G_MB_LIB.T6G(SCH_1):PAGE339_I20@PURE_QUANTA.MOSFET_NCH_DUAL(CHIPS)':
 C_PATH='@t6g_mb_lib.t6g(sch_1):page339_i20@pure_quanta.mosfet_nch_dual(chips)';

SECTION_NUMBER 2
 '@T6G_MB_LIB.T6G(SCH_1):PAGE339_I24@PURE_QUANTA.MOSFET_NCH_DUAL(CHIPS)':
 C_PATH='@t6g_mb_lib.t6g(sch_1):page339_i24@pure_quanta.mosfet_nch_dual(chips)';

PART_NAME
 Q41 'MOSFET_NCH_DUAL-2N7002KDW,SMLF,IC,BAM70020047':;

SECTION_NUMBER 1
 '@T6G_MB_LIB.T6G(SCH_1):PAGE339_I29@PURE_QUANTA.MOSFET_NCH_DUAL(CHIPS)':
 C_PATH='@t6g_mb_lib.t6g(sch_1):page339_i29@pure_quanta.mosfet_nch_dual(chips)';

SECTION_NUMBER 2
 '@T6G_MB_LIB.T6G(SCH_1):PAGE339_I32@PURE_QUANTA.MOSFET_NCH_DUAL(CHIPS)':
 C_PATH='@t6g_mb_lib.t6g(sch_1):page339_i32@pure_quanta.mosfet_nch_dual(chips)';

PART_NAME
 Q40 'MOSFET_NCH_DUAL-2N7002KDW,SMLF,IC,BAM70020047':;

SECTION_NUMBER 1
 '@T6G_MB_LIB.T6G(SCH_1):PAGE339_I37@PURE_QUANTA.MOSFET_NCH_DUAL(CHIPS)':
 C_PATH='@t6g_mb_lib.t6g(sch_1):page339_i37@pure_quanta.mosfet_nch_dual(chips)';

SECTION_NUMBER 2
 '@T6G_MB_LIB.T6G(SCH_1):PAGE339_I42@PURE_QUANTA.MOSFET_NCH_DUAL(CHIPS)':
 C_PATH='@t6g_mb_lib.t6g(sch_1):page339_i42@pure_quanta.mosfet_nch_dual(chips)';

PART_NAME
 R3752 'Q_RES_0402LF-10K,5%,1/16W,CHIP,TMP_QCS31002JB28':;

SECTION_NUMBER 1
 '@T6G_MB_LIB.T6G(SCH_1):PAGE259_I17@PURE_QUANTA.Q_RES(CHIPS)':
 C_PATH='@t6g_mb_lib.t6g(sch_1):page259_i17@pure_quanta.q_res(chips)';

PART_NAME
 R1344 'Q_RES_0805LF-0,5%,1/8W,EMPTY,CS00004JA40':;

SECTION_NUMBER 1
 '@T6G_MB_LIB.T6G(SCH_1):PAGE259_I16@PURE_QUANTA.Q_RES(CHIPS)':
 C_PATH='@t6g_mb_lib.t6g(sch_1):page259_i16@pure_quanta.q_res(chips)';

PART_NAME
 R1025 'Q_RES_0805LF-0,5%,1/8W,EMPTY,CS00004JA40':;

SECTION_NUMBER 1
 '@T6G_MB_LIB.T6G(SCH_1):PAGE259_I12@PURE_QUANTA.Q_RES(CHIPS)':
 C_PATH='@t6g_mb_lib.t6g(sch_1):page259_i12@pure_quanta.q_res(chips)';

PART_NAME
 R1024 'Q_RES_0402LF-10K,5%,1/16W,CHIP,TMP_QCS31002JB28':;

SECTION_NUMBER 1
 '@T6G_MB_LIB.T6G(SCH_1):PAGE259_I9@PURE_QUANTA.Q_RES(CHIPS)':
 C_PATH='@t6g_mb_lib.t6g(sch_1):page259_i9@pure_quanta.q_res(chips)';

PART_NAME
 R1023 'Q_RES_0402LF-10K,5%,1/16W,CHIP,TMP_QCS31002JB28':;

SECTION_NUMBER 1
 '@T6G_MB_LIB.T6G(SCH_1):PAGE259_I4@PURE_QUANTA.Q_RES(CHIPS)':
 C_PATH='@t6g_mb_lib.t6g(sch_1):page259_i4@pure_quanta.q_res(chips)';

PART_NAME
 Q285 'MOSFET_PCH_GDS_ESD_PROTECTED-PJA3415AE,SMLF,IC,BAM34150008':;

SECTION_NUMBER 1
 '@T6G_MB_LIB.T6G(SCH_1):PAGE259_I11@PURE_QUANTA.MOSFET_PCH_GDS_ESD_PROTECTED(CHIPS)':
 C_PATH='@t6g_mb_lib.t6g(sch_1):page259_i11@pure_quanta.mosfet_pch_gds_esd_prote~
cted(chips)';

PART_NAME
 Q28 'MOSFET_PCH_GDS_ESD_PROTECTED-PJA3415AE,SMLF,IC,BAM34150008':;

SECTION_NUMBER 1
 '@T6G_MB_LIB.T6G(SCH_1):PAGE259_I7@PURE_QUANTA.MOSFET_PCH_GDS_ESD_PROTECTED(CHIPS)':
 C_PATH='@t6g_mb_lib.t6g(sch_1):page259_i7@pure_quanta.mosfet_pch_gds_esd_protec~
ted(chips)';

PART_NAME
 R248 'Q_RES_0402LF-0,5%,1/16W,EMPTY,CS00002JB38':;

SECTION_NUMBER 1
 '@T6G_MB_LIB.T6G(SCH_1):PAGE90_I54@PURE_QUANTA.Q_RES(CHIPS)':
 C_PATH='@t6g_mb_lib.t6g(sch_1):page90_i54@pure_quanta.q_res(chips)';

PART_NAME
 R247 'Q_RES_0402LF-0,5%,1/16W,EMPTY,CS00002JB38':;

SECTION_NUMBER 1
 '@T6G_MB_LIB.T6G(SCH_1):PAGE90_I53@PURE_QUANTA.Q_RES(CHIPS)':
 C_PATH='@t6g_mb_lib.t6g(sch_1):page90_i53@pure_quanta.q_res(chips)';

PART_NAME
 R246 'Q_RES_0402LF-0,5%,1/16W,EMPTY,CS00002JB38':;

SECTION_NUMBER 1
 '@T6G_MB_LIB.T6G(SCH_1):PAGE90_I50@PURE_QUANTA.Q_RES(CHIPS)':
 C_PATH='@t6g_mb_lib.t6g(sch_1):page90_i50@pure_quanta.q_res(chips)';

PART_NAME
 R245 'Q_RES_0402LF-0,5%,1/16W,EMPTY,CS00002JB38':;

SECTION_NUMBER 1
 '@T6G_MB_LIB.T6G(SCH_1):PAGE90_I39@PURE_QUANTA.Q_RES(CHIPS)':
 C_PATH='@t6g_mb_lib.t6g(sch_1):page90_i39@pure_quanta.q_res(chips)';

PART_NAME
 R244 'Q_RES_0402LF-100,1%,1/16W,EMPTY,TMP_QCS11002FB22':;

SECTION_NUMBER 1
 '@T6G_MB_LIB.T6G(SCH_1):PAGE90_I98@PURE_QUANTA.Q_RES(CHIPS)':
 C_PATH='@t6g_mb_lib.t6g(sch_1):page90_i98@pure_quanta.q_res(chips)';

PART_NAME
 R243 'Q_RES_0402LF-100,1%,1/16W,EMPTY,TMP_QCS11002FB22':;

SECTION_NUMBER 1
 '@T6G_MB_LIB.T6G(SCH_1):PAGE90_I96@PURE_QUANTA.Q_RES(CHIPS)':
 C_PATH='@t6g_mb_lib.t6g(sch_1):page90_i96@pure_quanta.q_res(chips)';

PART_NAME
 R242 'Q_RES_0402LF-1K,1%,1/16W,EMPTY,TMP_QCS21002FB24':;

SECTION_NUMBER 1
 '@T6G_MB_LIB.T6G(SCH_1):PAGE90_I90@PURE_QUANTA.Q_RES(CHIPS)':
 C_PATH='@t6g_mb_lib.t6g(sch_1):page90_i90@pure_quanta.q_res(chips)';

PART_NAME
 R241 'Q_RES_0402LF-1K,1%,1/16W,EMPTY,TMP_QCS21002FB24':;

SECTION_NUMBER 1
 '@T6G_MB_LIB.T6G(SCH_1):PAGE90_I88@PURE_QUANTA.Q_RES(CHIPS)':
 C_PATH='@t6g_mb_lib.t6g(sch_1):page90_i88@pure_quanta.q_res(chips)';

PART_NAME
 R240 'Q_RES_0402LF-0,5%,1/16W,CHIP,CS00002JB38':;

SECTION_NUMBER 1
 '@T6G_MB_LIB.T6G(SCH_1):PAGE90_I85@PURE_QUANTA.Q_RES(CHIPS)':
 C_PATH='@t6g_mb_lib.t6g(sch_1):page90_i85@pure_quanta.q_res(chips)';

PART_NAME
 R239 'Q_RES_0402LF-0,5%,1/16W,CHIP,CS00002JB38':;

SECTION_NUMBER 1
 '@T6G_MB_LIB.T6G(SCH_1):PAGE90_I73@PURE_QUANTA.Q_RES(CHIPS)':
 C_PATH='@t6g_mb_lib.t6g(sch_1):page90_i73@pure_quanta.q_res(chips)';

PART_NAME
 R238 'Q_RES_0402LF-0,5%,1/16W,CHIP,CS00002JB38':;

SECTION_NUMBER 1
 '@T6G_MB_LIB.T6G(SCH_1):PAGE90_I69@PURE_QUANTA.Q_RES(CHIPS)':
 C_PATH='@t6g_mb_lib.t6g(sch_1):page90_i69@pure_quanta.q_res(chips)';

PART_NAME
 R237 'Q_RES_0402LF-0,5%,1/16W,CHIP,CS00002JB38':;

SECTION_NUMBER 1
 '@T6G_MB_LIB.T6G(SCH_1):PAGE90_I61@PURE_QUANTA.Q_RES(CHIPS)':
 C_PATH='@t6g_mb_lib.t6g(sch_1):page90_i61@pure_quanta.q_res(chips)';

PART_NAME
 R236 'Q_RES_0402LF-1K,1%,1/16W,CHIP,TMP_QCS21002FB24':;

SECTION_NUMBER 1
 '@T6G_MB_LIB.T6G(SCH_1):PAGE90_I77@PURE_QUANTA.Q_RES(CHIPS)':
 C_PATH='@t6g_mb_lib.t6g(sch_1):page90_i77@pure_quanta.q_res(chips)';

PART_NAME
 R235 'Q_RES_0402LF-1K,1%,1/16W,CHIP,TMP_QCS21002FB24':;

SECTION_NUMBER 1
 '@T6G_MB_LIB.T6G(SCH_1):PAGE90_I72@PURE_QUANTA.Q_RES(CHIPS)':
 C_PATH='@t6g_mb_lib.t6g(sch_1):page90_i72@pure_quanta.q_res(chips)';

PART_NAME
 R234 'Q_RES_0402LF-1K,1%,1/16W,CHIP,TMP_QCS21002FB24':;

SECTION_NUMBER 1
 '@T6G_MB_LIB.T6G(SCH_1):PAGE90_I67@PURE_QUANTA.Q_RES(CHIPS)':
 C_PATH='@t6g_mb_lib.t6g(sch_1):page90_i67@pure_quanta.q_res(chips)';

PART_NAME
 R233 'Q_RES_0402LF-1K,1%,1/16W,CHIP,TMP_QCS21002FB24':;

SECTION_NUMBER 1
 '@T6G_MB_LIB.T6G(SCH_1):PAGE90_I60@PURE_QUANTA.Q_RES(CHIPS)':
 C_PATH='@t6g_mb_lib.t6g(sch_1):page90_i60@pure_quanta.q_res(chips)';

PART_NAME
 R232 'Q_RES_0402LF-0,5%,1/16W,EMPTY,CS00002JB38':;

SECTION_NUMBER 1
 '@T6G_MB_LIB.T6G(SCH_1):PAGE90_I82@PURE_QUANTA.Q_RES(CHIPS)':
 C_PATH='@t6g_mb_lib.t6g(sch_1):page90_i82@pure_quanta.q_res(chips)';

PART_NAME
 R231 'Q_RES_0402LF-0,5%,1/16W,EMPTY,CS00002JB38':;

SECTION_NUMBER 1
 '@T6G_MB_LIB.T6G(SCH_1):PAGE90_I81@PURE_QUANTA.Q_RES(CHIPS)':
 C_PATH='@t6g_mb_lib.t6g(sch_1):page90_i81@pure_quanta.q_res(chips)';

PART_NAME
 R230 'Q_RES_0402LF-0,5%,1/16W,EMPTY,CS00002JB38':;

SECTION_NUMBER 1
 '@T6G_MB_LIB.T6G(SCH_1):PAGE90_I79@PURE_QUANTA.Q_RES(CHIPS)':
 C_PATH='@t6g_mb_lib.t6g(sch_1):page90_i79@pure_quanta.q_res(chips)';

PART_NAME
 R229 'Q_RES_0402LF-0,5%,1/16W,EMPTY,CS00002JB38':;

SECTION_NUMBER 1
 '@T6G_MB_LIB.T6G(SCH_1):PAGE90_I64@PURE_QUANTA.Q_RES(CHIPS)':
 C_PATH='@t6g_mb_lib.t6g(sch_1):page90_i64@pure_quanta.q_res(chips)';

PART_NAME
 Q6 'MOSFET_NCH_DUAL-2N7002KDW,SMLF,IC,BAM70020047':;

SECTION_NUMBER 1
 '@T6G_MB_LIB.T6G(SCH_1):PAGE90_I78@PURE_QUANTA.MOSFET_NCH_DUAL(CHIPS)':
 C_PATH='@t6g_mb_lib.t6g(sch_1):page90_i78@pure_quanta.mosfet_nch_dual(chips)';

SECTION_NUMBER 2
 '@T6G_MB_LIB.T6G(SCH_1):PAGE90_I57@PURE_QUANTA.MOSFET_NCH_DUAL(CHIPS)':
 C_PATH='@t6g_mb_lib.t6g(sch_1):page90_i57@pure_quanta.mosfet_nch_dual(chips)';

PART_NAME
 Q5 'MOSFET_NCH_DUAL-2N7002KDW,SMLF,IC,BAM70020047':;

SECTION_NUMBER 1
 '@T6G_MB_LIB.T6G(SCH_1):PAGE90_I74@PURE_QUANTA.MOSFET_NCH_DUAL(CHIPS)':
 C_PATH='@t6g_mb_lib.t6g(sch_1):page90_i74@pure_quanta.mosfet_nch_dual(chips)';

SECTION_NUMBER 2
 '@T6G_MB_LIB.T6G(SCH_1):PAGE90_I56@PURE_QUANTA.MOSFET_NCH_DUAL(CHIPS)':
 C_PATH='@t6g_mb_lib.t6g(sch_1):page90_i56@pure_quanta.mosfet_nch_dual(chips)';

PART_NAME
 Q4 'MOSFET_NCH_DUAL-2N7002KDW,SMLF,IC,BAM70020047':;

SECTION_NUMBER 1
 '@T6G_MB_LIB.T6G(SCH_1):PAGE90_I68@PURE_QUANTA.MOSFET_NCH_DUAL(CHIPS)':
 C_PATH='@t6g_mb_lib.t6g(sch_1):page90_i68@pure_quanta.mosfet_nch_dual(chips)';

SECTION_NUMBER 2
 '@T6G_MB_LIB.T6G(SCH_1):PAGE90_I51@PURE_QUANTA.MOSFET_NCH_DUAL(CHIPS)':
 C_PATH='@t6g_mb_lib.t6g(sch_1):page90_i51@pure_quanta.mosfet_nch_dual(chips)';

PART_NAME
 Q3 'MOSFET_NCH_DUAL-2N7002KDW,SMLF,IC,BAM70020047':;

SECTION_NUMBER 1
 '@T6G_MB_LIB.T6G(SCH_1):PAGE90_I62@PURE_QUANTA.MOSFET_NCH_DUAL(CHIPS)':
 C_PATH='@t6g_mb_lib.t6g(sch_1):page90_i62@pure_quanta.mosfet_nch_dual(chips)';

SECTION_NUMBER 2
 '@T6G_MB_LIB.T6G(SCH_1):PAGE90_I41@PURE_QUANTA.MOSFET_NCH_DUAL(CHIPS)':
 C_PATH='@t6g_mb_lib.t6g(sch_1):page90_i41@pure_quanta.mosfet_nch_dual(chips)';

PART_NAME
 PU181 'MPQ8633BGLEC838Z-MPQ8633BGLE-C838-Z,SMLF,IC,AL008633005':;

SECTION_NUMBER 1
 '@T6G_MB_LIB.T6G(SCH_1):PAGE282_I54@PURE_QUANTA.MPQ8633BGLEC838Z(CHIPS)':
 C_PATH='@t6g_mb_lib.t6g(sch_1):page282_i54@pure_quanta.mpq8633bglec838z(chips)';

PART_NAME
 PR1948 'Q_RES_0402LF-75K,1%,1/16W,CHIP,CS37502FB12':;

SECTION_NUMBER 1
 '@T6G_MB_LIB.T6G(SCH_1):PAGE282_I40@PURE_QUANTA.Q_RES(CHIPS)':
 C_PATH='@t6g_mb_lib.t6g(sch_1):page282_i40@pure_quanta.q_res(chips)';

PART_NAME
 PR1945 'Q_RES_0402LF-510K,5%,1/16W,CHIP,CS45102JB16':;

SECTION_NUMBER 1
 '@T6G_MB_LIB.T6G(SCH_1):PAGE282_I41@PURE_QUANTA.Q_RES(CHIPS)':
 C_PATH='@t6g_mb_lib.t6g(sch_1):page282_i41@pure_quanta.q_res(chips)';

PART_NAME
 PR92 'Q_RES_0402LF-86.6K,1%,1/16W,CHIP,TMP_QCS38662FB16':;

SECTION_NUMBER 1
 '@T6G_MB_LIB.T6G(SCH_1):PAGE282_I66@PURE_QUANTA.Q_RES(CHIPS)':
 C_PATH='@t6g_mb_lib.t6g(sch_1):page282_i66@pure_quanta.q_res(chips)';

PART_NAME
 PR91 'Q_RES_0402LF-11.8K,1%,1/16W,CHIP,TMP_QCS31182FB18':;

SECTION_NUMBER 1
 '@T6G_MB_LIB.T6G(SCH_1):PAGE282_I63@PURE_QUANTA.Q_RES(CHIPS)':
 C_PATH='@t6g_mb_lib.t6g(sch_1):page282_i63@pure_quanta.q_res(chips)';

PART_NAME
 PR90 'Q_RES_0402LF-10K,5%,1/16W,CHIP,TMP_QCS31002JB28':;

SECTION_NUMBER 1
 '@T6G_MB_LIB.T6G(SCH_1):PAGE282_I70@PURE_QUANTA.Q_RES(CHIPS)':
 C_PATH='@t6g_mb_lib.t6g(sch_1):page282_i70@pure_quanta.q_res(chips)';

PART_NAME
 PR89 'Q_RES_0402LF-15K,1%,1/16W,CHIP,TMP_QCS31502FB24':;

SECTION_NUMBER 1
 '@T6G_MB_LIB.T6G(SCH_1):PAGE282_I53@PURE_QUANTA.Q_RES(CHIPS)':
 C_PATH='@t6g_mb_lib.t6g(sch_1):page282_i53@pure_quanta.q_res(chips)';

PART_NAME
 PL65 'Q_INDUCTOR_SMLF-3.3UH/10A,IND,CV-33A0MZ02':;

SECTION_NUMBER 1
 '@T6G_MB_LIB.T6G(SCH_1):PAGE282_I67@PURE_QUANTA.Q_INDUCTOR(CHIPS)':
 C_PATH='@t6g_mb_lib.t6g(sch_1):page282_i67@pure_quanta.q_inductor(chips)';

PART_NAME
 PL64 'Q_INDUCTOR_SMLF-BLM18SN220TN1D/8000MA,IND,CX220TN1001':;

SECTION_NUMBER 1
 '@T6G_MB_LIB.T6G(SCH_1):PAGE282_I57@PURE_QUANTA.Q_INDUCTOR(CHIPS)':
 C_PATH='@t6g_mb_lib.t6g(sch_1):page282_i57@pure_quanta.q_inductor(chips)';

PART_NAME
 PC1898 'Q_CAP_C0805-22UF,16V,20%,X6S,CH6223MEA00':;

SECTION_NUMBER 1
 '@T6G_MB_LIB.T6G(SCH_1):PAGE282_I51@PURE_QUANTA.Q_CAP(CHIPS)':
 C_PATH='@t6g_mb_lib.t6g(sch_1):page282_i51@pure_quanta.q_cap(chips)';

PART_NAME
 PC1877 'Q_CAP_0402-47PF,50V,5%,NPO,TMP_QCH04706JB01':;

SECTION_NUMBER 1
 '@T6G_MB_LIB.T6G(SCH_1):PAGE282_I65@PURE_QUANTA.Q_CAP(CHIPS)':
 C_PATH='@t6g_mb_lib.t6g(sch_1):page282_i65@pure_quanta.q_cap(chips)';

PART_NAME
 PC1870 'Q_CAP_0402-0.1UF,25V,10%,EMPTY,CH4104K1B00':
;

SECTION_NUMBER 1
 '@T6G_MB_LIB.T6G(SCH_1):PAGE282_I43@PURE_QUANTA.Q_CAP(CHIPS)':
 C_PATH='@t6g_mb_lib.t6g(sch_1):page282_i43@pure_quanta.q_cap(chips)';

PART_NAME
 PC1856 'Q_CAP_C0805-22UF,10V,20%,X6S,CH6222MEA00':;

SECTION_NUMBER 1
 '@T6G_MB_LIB.T6G(SCH_1):PAGE282_I73@PURE_QUANTA.Q_CAP(CHIPS)':
 C_PATH='@t6g_mb_lib.t6g(sch_1):page282_i73@pure_quanta.q_cap(chips)';

PART_NAME
 PC1855 'Q_CAP_C0805-22UF,10V,20%,X6S,CH6222MEA00':;

SECTION_NUMBER 1
 '@T6G_MB_LIB.T6G(SCH_1):PAGE282_I72@PURE_QUANTA.Q_CAP(CHIPS)':
 C_PATH='@t6g_mb_lib.t6g(sch_1):page282_i72@pure_quanta.q_cap(chips)';

PART_NAME
 PC1853 'Q_CAP_0402-0.1UF,25V,10%,X7R,CH4104K1B00':;

SECTION_NUMBER 1
 '@T6G_MB_LIB.T6G(SCH_1):PAGE282_I59@PURE_QUANTA.Q_CAP(CHIPS)':
 C_PATH='@t6g_mb_lib.t6g(sch_1):page282_i59@pure_quanta.q_cap(chips)';

PART_NAME
 PC1852 'Q_CAP_0402-0.1UF,25V,10%,X7R,CH4104K1B00':;

SECTION_NUMBER 1
 '@T6G_MB_LIB.T6G(SCH_1):PAGE282_I74@PURE_QUANTA.Q_CAP(CHIPS)':
 C_PATH='@t6g_mb_lib.t6g(sch_1):page282_i74@pure_quanta.q_cap(chips)';

PART_NAME
 PC1850 'Q_CAP_C0805-22UF,16V,20%,X6S,CH6223MEA00':;

SECTION_NUMBER 1
 '@T6G_MB_LIB.T6G(SCH_1):PAGE282_I77@PURE_QUANTA.Q_CAP(CHIPS)':
 C_PATH='@t6g_mb_lib.t6g(sch_1):page282_i77@pure_quanta.q_cap(chips)';

PART_NAME
 PC1849 'Q_CAP_C0805-22UF,16V,20%,X6S,CH6223MEA00':;

SECTION_NUMBER 1
 '@T6G_MB_LIB.T6G(SCH_1):PAGE282_I78@PURE_QUANTA.Q_CAP(CHIPS)':
 C_PATH='@t6g_mb_lib.t6g(sch_1):page282_i78@pure_quanta.q_cap(chips)';

PART_NAME
 PC1848 'Q_CAP_C0402-1UF,25V,10%,X6S,CH5104KEB02':
;

SECTION_NUMBER 1
 '@T6G_MB_LIB.T6G(SCH_1):PAGE282_I47@PURE_QUANTA.Q_CAP(CHIPS)':
 C_PATH='@t6g_mb_lib.t6g(sch_1):page282_i47@pure_quanta.q_cap(chips)';

PART_NAME
 PC1847 'Q_CAP_0402-0.22UF,16V,10%,X7R,CH4223K1B00':
;

SECTION_NUMBER 1
 '@T6G_MB_LIB.T6G(SCH_1):PAGE282_I64@PURE_QUANTA.Q_CAP(CHIPS)':
 C_PATH='@t6g_mb_lib.t6g(sch_1):page282_i64@pure_quanta.q_cap(chips)';

PART_NAME
 PC1846 'Q_CAP_0402-0.1UF,25V,10%,X7R,CH4104K1B00':
;

SECTION_NUMBER 1
 '@T6G_MB_LIB.T6G(SCH_1):PAGE282_I55@PURE_QUANTA.Q_CAP(CHIPS)':
 C_PATH='@t6g_mb_lib.t6g(sch_1):page282_i55@pure_quanta.q_cap(chips)';

PART_NAME
 PC1845 'Q_CAPP_SMLF-220UF,6.3V,20%,ALUM,CC72201MZ28':;

SECTION_NUMBER 1
 '@T6G_MB_LIB.T6G(SCH_1):PAGE282_I69@PURE_QUANTA.Q_CAPP(CHIPS)':
 C_PATH='@t6g_mb_lib.t6g(sch_1):page282_i69@pure_quanta.q_capp(chips)';

PART_NAME
 PU98 'NB695GDZ-NB695GD-Z,SMLF,IC,AL000695001':;

SECTION_NUMBER 1
 '@T6G_MB_LIB.T6G(SCH_1):PAGE287_I22@PURE_QUANTA.NB695GDZ(CHIPS)':
 C_PATH='@t6g_mb_lib.t6g(sch_1):page287_i22@pure_quanta.nb695gdz(chips)';

PART_NAME
 PR926 'Q_RES_0402LF-0,5%,1/16W,CHIP,CS00002JB38':;

SECTION_NUMBER 1
 '@T6G_MB_LIB.T6G(SCH_1):PAGE287_I28@PURE_QUANTA.Q_RES(CHIPS)':
 C_PATH='@t6g_mb_lib.t6g(sch_1):page287_i28@pure_quanta.q_res(chips)';

PART_NAME
 PR925 'Q_RES_0402LF-150K,1%,1/16W,CHIP,TMP_QCS41502FB18':;

SECTION_NUMBER 1
 '@T6G_MB_LIB.T6G(SCH_1):PAGE287_I38@PURE_QUANTA.Q_RES(CHIPS)':
 C_PATH='@t6g_mb_lib.t6g(sch_1):page287_i38@pure_quanta.q_res(chips)';

PART_NAME
 PR924 'Q_RES_0402LF-5.1,5%,1/16W,CHIP,CS-5102JB03':;

SECTION_NUMBER 1
 '@T6G_MB_LIB.T6G(SCH_1):PAGE287_I3@PURE_QUANTA.Q_RES(CHIPS)':
 C_PATH='@t6g_mb_lib.t6g(sch_1):page287_i3@pure_quanta.q_res(chips)';

PART_NAME
 PR923 'Q_RES_0402LF-10K,1%,1/16W,CHIP,TMP_QCS31002FB26':;

SECTION_NUMBER 1
 '@T6G_MB_LIB.T6G(SCH_1):PAGE287_I24@PURE_QUANTA.Q_RES(CHIPS)':
 C_PATH='@t6g_mb_lib.t6g(sch_1):page287_i24@pure_quanta.q_res(chips)';

PART_NAME
 PR399 'Q_RES_0402LF-0,5%,1/16W,EMPTY,CS00002JB38':;

SECTION_NUMBER 1
 '@T6G_MB_LIB.T6G(SCH_1):PAGE287_I10@PURE_QUANTA.Q_RES(CHIPS)':
 C_PATH='@t6g_mb_lib.t6g(sch_1):page287_i10@pure_quanta.q_res(chips)';

PART_NAME
 PR398 'Q_RES_0402LF-0,5%,1/16W,CHIP,CS00002JB38':;

SECTION_NUMBER 1
 '@T6G_MB_LIB.T6G(SCH_1):PAGE287_I11@PURE_QUANTA.Q_RES(CHIPS)':
 C_PATH='@t6g_mb_lib.t6g(sch_1):page287_i11@pure_quanta.q_res(chips)';

PART_NAME
 PR41 'Q_RES_0402LF-0,5%,1/16W,CHIP,CS00002JB38':;

SECTION_NUMBER 1
 '@T6G_MB_LIB.T6G(SCH_1):PAGE287_I39@PURE_QUANTA.Q_RES(CHIPS)':
 C_PATH='@t6g_mb_lib.t6g(sch_1):page287_i39@pure_quanta.q_res(chips)';

PART_NAME
 PL116 'Q_INDUCTOR_SMLF-1UH,IND,CV-10B0MZ13':;

SECTION_NUMBER 1
 '@T6G_MB_LIB.T6G(SCH_1):PAGE287_I27@PURE_QUANTA.Q_INDUCTOR(CHIPS)':
 C_PATH='@t6g_mb_lib.t6g(sch_1):page287_i27@pure_quanta.q_inductor(chips)';

PART_NAME
 PL115 'Q_INDUCTOR_SMLF-BLM18SN220TN1D/8000MA,IND,CX220TN1001':;

SECTION_NUMBER 1
 '@T6G_MB_LIB.T6G(SCH_1):PAGE287_I7@PURE_QUANTA.Q_INDUCTOR(CHIPS)':
 C_PATH='@t6g_mb_lib.t6g(sch_1):page287_i7@pure_quanta.q_inductor(chips)';

PART_NAME
 PC1333 'Q_CAP_0402-0.1UF,25V,10%,X7R,CH4104K1B00':;

SECTION_NUMBER 1
 '@T6G_MB_LIB.T6G(SCH_1):PAGE287_I26@PURE_QUANTA.Q_CAP(CHIPS)':
 C_PATH='@t6g_mb_lib.t6g(sch_1):page287_i26@pure_quanta.q_cap(chips)';

PART_NAME
 PC1332 'Q_CAP_0402-0.01UF,25V,10%,X7R,TMP_QCH31004KB17':;

SECTION_NUMBER 1
 '@T6G_MB_LIB.T6G(SCH_1):PAGE287_I30@PURE_QUANTA.Q_CAP(CHIPS)':
 C_PATH='@t6g_mb_lib.t6g(sch_1):page287_i30@pure_quanta.q_cap(chips)';

PART_NAME
 PC1331 'Q_CAP_0402-0.1UF,25V,10%,X7R,CH4104K1B00':;

SECTION_NUMBER 1
 '@T6G_MB_LIB.T6G(SCH_1):PAGE287_I20@PURE_QUANTA.Q_CAP(CHIPS)':
 C_PATH='@t6g_mb_lib.t6g(sch_1):page287_i20@pure_quanta.q_cap(chips)';

PART_NAME
 PC1330 'Q_CAP_C0805-10UF,16V,10%,X6S,CH6103KEA00':;

SECTION_NUMBER 1
 '@T6G_MB_LIB.T6G(SCH_1):PAGE287_I18@PURE_QUANTA.Q_CAP(CHIPS)':
 C_PATH='@t6g_mb_lib.t6g(sch_1):page287_i18@pure_quanta.q_cap(chips)';

PART_NAME
 PC1329 'Q_CAP_C0805-10UF,16V,10%,X6S,CH6103KEA00':;

SECTION_NUMBER 1
 '@T6G_MB_LIB.T6G(SCH_1):PAGE287_I17@PURE_QUANTA.Q_CAP(CHIPS)':
 C_PATH='@t6g_mb_lib.t6g(sch_1):page287_i17@pure_quanta.q_cap(chips)';

PART_NAME
 PC1328 'Q_CAP_0805-22UF,4V,20%,X6S,TMP_QCH622KMEA01':;

SECTION_NUMBER 1
 '@T6G_MB_LIB.T6G(SCH_1):PAGE287_I36@PURE_QUANTA.Q_CAP(CHIPS)':
 C_PATH='@t6g_mb_lib.t6g(sch_1):page287_i36@pure_quanta.q_cap(chips)';

PART_NAME
 PC1327 'Q_CAP_0805-22UF,4V,20%,X6S,TMP_QCH622KMEA01':;

SECTION_NUMBER 1
 '@T6G_MB_LIB.T6G(SCH_1):PAGE287_I34@PURE_QUANTA.Q_CAP(CHIPS)':
 C_PATH='@t6g_mb_lib.t6g(sch_1):page287_i34@pure_quanta.q_cap(chips)';

PART_NAME
 PC1326 'Q_CAP_0805-22UF,4V,20%,X6S,TMP_QCH622KMEA01':;

SECTION_NUMBER 1
 '@T6G_MB_LIB.T6G(SCH_1):PAGE287_I32@PURE_QUANTA.Q_CAP(CHIPS)':
 C_PATH='@t6g_mb_lib.t6g(sch_1):page287_i32@pure_quanta.q_cap(chips)';

PART_NAME
 PC1325 'Q_CAP_0805-22UF,4V,20%,X6S,TMP_QCH622KMEA01':;

SECTION_NUMBER 1
 '@T6G_MB_LIB.T6G(SCH_1):PAGE287_I31@PURE_QUANTA.Q_CAP(CHIPS)':
 C_PATH='@t6g_mb_lib.t6g(sch_1):page287_i31@pure_quanta.q_cap(chips)';

PART_NAME
 PC1324 'Q_CAP_0402-0.22UF,16V,10%,X7R,CH4223K1B00':;

SECTION_NUMBER 1
 '@T6G_MB_LIB.T6G(SCH_1):PAGE287_I23@PURE_QUANTA.Q_CAP(CHIPS)':
 C_PATH='@t6g_mb_lib.t6g(sch_1):page287_i23@pure_quanta.q_cap(chips)';

PART_NAME
 PC1323 'Q_CAP_C0402-1UF,25V,10%,X6S,CH5104KEB02':;

SECTION_NUMBER 1
 '@T6G_MB_LIB.T6G(SCH_1):PAGE287_I2@PURE_QUANTA.Q_CAP(CHIPS)':
 C_PATH='@t6g_mb_lib.t6g(sch_1):page287_i2@pure_quanta.q_cap(chips)';

PART_NAME
 R1850 'Q_RES_0402LF-1K,5%,1/16W,EMPTY,TMP_QCS21002JB34':;

SECTION_NUMBER 1
 '@T6G_MB_LIB.T6G(SCH_1):PAGE286_I17@PURE_QUANTA.Q_RES(CHIPS)':
 C_PATH='@t6g_mb_lib.t6g(sch_1):page286_i17@pure_quanta.q_res(chips)';

PART_NAME
 PU74 'NB695GDZ-NB695GD-Z,SMLF,IC,AL000695001':;

SECTION_NUMBER 1
 '@T6G_MB_LIB.T6G(SCH_1):PAGE286_I43@PURE_QUANTA.NB695GDZ(CHIPS)':
 C_PATH='@t6g_mb_lib.t6g(sch_1):page286_i43@pure_quanta.nb695gdz(chips)';

PART_NAME
 PR1651 'Q_RES_0402LF-0,5%,1/16W,CHIP,CS00002JB38':;

SECTION_NUMBER 1
 '@T6G_MB_LIB.T6G(SCH_1):PAGE286_I35@PURE_QUANTA.Q_RES(CHIPS)':
 C_PATH='@t6g_mb_lib.t6g(sch_1):page286_i35@pure_quanta.q_res(chips)';

PART_NAME
 PR1330 'Q_RES_0402LF-150K,1%,1/16W,CHIP,TMP_QCS41502FB18':;

SECTION_NUMBER 1
 '@T6G_MB_LIB.T6G(SCH_1):PAGE286_I13@PURE_QUANTA.Q_RES(CHIPS)':
 C_PATH='@t6g_mb_lib.t6g(sch_1):page286_i13@pure_quanta.q_res(chips)';

PART_NAME
 PR1329 'Q_RES_0402LF-5.1,5%,1/16W,CHIP,CS-5102JB03':;

SECTION_NUMBER 1
 '@T6G_MB_LIB.T6G(SCH_1):PAGE286_I7@PURE_QUANTA.Q_RES(CHIPS)':
 C_PATH='@t6g_mb_lib.t6g(sch_1):page286_i7@pure_quanta.q_res(chips)';

PART_NAME
 PR1302 'Q_RES_0402LF-10K,1%,1/16W,CHIP,TMP_QCS31002FB26':;

SECTION_NUMBER 1
 '@T6G_MB_LIB.T6G(SCH_1):PAGE286_I33@PURE_QUANTA.Q_RES(CHIPS)':
 C_PATH='@t6g_mb_lib.t6g(sch_1):page286_i33@pure_quanta.q_res(chips)';

PART_NAME
 PR412 'Q_RES_0402LF-0,5%,1/16W,EMPTY,CS00002JB38':;

SECTION_NUMBER 1
 '@T6G_MB_LIB.T6G(SCH_1):PAGE286_I16@PURE_QUANTA.Q_RES(CHIPS)':
 C_PATH='@t6g_mb_lib.t6g(sch_1):page286_i16@pure_quanta.q_res(chips)';

PART_NAME
 PR411 'Q_RES_0402LF-0,5%,1/16W,CHIP,CS00002JB38':;

SECTION_NUMBER 1
 '@T6G_MB_LIB.T6G(SCH_1):PAGE286_I15@PURE_QUANTA.Q_RES(CHIPS)':
 C_PATH='@t6g_mb_lib.t6g(sch_1):page286_i15@pure_quanta.q_res(chips)';

PART_NAME
 PR396 'Q_RES_0402LF-0,5%,1/16W,EMPTY,CS00002JB38':;

SECTION_NUMBER 1
 '@T6G_MB_LIB.T6G(SCH_1):PAGE286_I1@PURE_QUANTA.Q_RES(CHIPS)':
 C_PATH='@t6g_mb_lib.t6g(sch_1):page286_i1@pure_quanta.q_res(chips)';

PART_NAME
 PR395 'Q_RES_0402LF-0,5%,1/16W,CHIP,CS00002JB38':;

SECTION_NUMBER 1
 '@T6G_MB_LIB.T6G(SCH_1):PAGE286_I4@PURE_QUANTA.Q_RES(CHIPS)':
 C_PATH='@t6g_mb_lib.t6g(sch_1):page286_i4@pure_quanta.q_res(chips)';

PART_NAME
 PL170 'Q_INDUCTOR_SMLF-1UH,IND,CV-10B0MZ13':;

SECTION_NUMBER 1
 '@T6G_MB_LIB.T6G(SCH_1):PAGE286_I22@PURE_QUANTA.Q_INDUCTOR(CHIPS)':
 C_PATH='@t6g_mb_lib.t6g(sch_1):page286_i22@pure_quanta.q_inductor(chips)';

PART_NAME
 PL16 'Q_INDUCTOR_SMLF-BLM18SN220TN1D/8000MA,IND,CX220TN1001':;

SECTION_NUMBER 1
 '@T6G_MB_LIB.T6G(SCH_1):PAGE286_I28@PURE_QUANTA.Q_INDUCTOR(CHIPS)':
 C_PATH='@t6g_mb_lib.t6g(sch_1):page286_i28@pure_quanta.q_inductor(chips)';

PART_NAME
 PC2287 'Q_CAP_0402-0.01UF,25V,10%,X7R,TMP_QCH31004KB17':;

SECTION_NUMBER 1
 '@T6G_MB_LIB.T6G(SCH_1):PAGE286_I25@PURE_QUANTA.Q_CAP(CHIPS)':
 C_PATH='@t6g_mb_lib.t6g(sch_1):page286_i25@pure_quanta.q_cap(chips)';

PART_NAME
 PC1642 'Q_CAP_C0402-1UF,25V,10%,X6S,CH5104KEB02':;

SECTION_NUMBER 1
 '@T6G_MB_LIB.T6G(SCH_1):PAGE286_I6@PURE_QUANTA.Q_CAP(CHIPS)':
 C_PATH='@t6g_mb_lib.t6g(sch_1):page286_i6@pure_quanta.q_cap(chips)';

PART_NAME
 PC1241 'Q_CAP_0805-22UF,4V,20%,X6S,TMP_QCH622KMEA01':;

SECTION_NUMBER 1
 '@T6G_MB_LIB.T6G(SCH_1):PAGE286_I40@PURE_QUANTA.Q_CAP(CHIPS)':
 C_PATH='@t6g_mb_lib.t6g(sch_1):page286_i40@pure_quanta.q_cap(chips)';

PART_NAME
 PC1240 'Q_CAP_0805-22UF,4V,20%,X6S,TMP_QCH622KMEA01':;

SECTION_NUMBER 1
 '@T6G_MB_LIB.T6G(SCH_1):PAGE286_I38@PURE_QUANTA.Q_CAP(CHIPS)':
 C_PATH='@t6g_mb_lib.t6g(sch_1):page286_i38@pure_quanta.q_cap(chips)';

PART_NAME
 PC1239 'Q_CAP_0805-22UF,4V,20%,X6S,TMP_QCH622KMEA01':;

SECTION_NUMBER 1
 '@T6G_MB_LIB.T6G(SCH_1):PAGE286_I37@PURE_QUANTA.Q_CAP(CHIPS)':
 C_PATH='@t6g_mb_lib.t6g(sch_1):page286_i37@pure_quanta.q_cap(chips)';

PART_NAME
 PC1238 'Q_CAP_0805-22UF,4V,20%,X6S,TMP_QCH622KMEA01':;

SECTION_NUMBER 1
 '@T6G_MB_LIB.T6G(SCH_1):PAGE286_I36@PURE_QUANTA.Q_CAP(CHIPS)':
 C_PATH='@t6g_mb_lib.t6g(sch_1):page286_i36@pure_quanta.q_cap(chips)';

PART_NAME
 PC1237 'Q_CAP_0805-22UF,4V,20%,X6S,TMP_QCH622KMEA01':;

SECTION_NUMBER 1
 '@T6G_MB_LIB.T6G(SCH_1):PAGE286_I26@PURE_QUANTA.Q_CAP(CHIPS)':
 C_PATH='@t6g_mb_lib.t6g(sch_1):page286_i26@pure_quanta.q_cap(chips)';

PART_NAME
 PC1236 'Q_CAP_C0402-100NF,50V,10%,X7R,CH4106K1B01':;

SECTION_NUMBER 1
 '@T6G_MB_LIB.T6G(SCH_1):PAGE286_I23@PURE_QUANTA.Q_CAP(CHIPS)':
 C_PATH='@t6g_mb_lib.t6g(sch_1):page286_i23@pure_quanta.q_cap(chips)';

PART_NAME
 PC1235 'Q_CAP_0402-0.22UF,16V,10%,X7R,CH4223K1B00':;

SECTION_NUMBER 1
 '@T6G_MB_LIB.T6G(SCH_1):PAGE286_I21@PURE_QUANTA.Q_CAP(CHIPS)':
 C_PATH='@t6g_mb_lib.t6g(sch_1):page286_i21@pure_quanta.q_cap(chips)';

PART_NAME
 PC1234 'Q_CAP_C0402-100NF,50V,10%,X7R,CH4106K1B01':;

SECTION_NUMBER 1
 '@T6G_MB_LIB.T6G(SCH_1):PAGE286_I32@PURE_QUANTA.Q_CAP(CHIPS)':
 C_PATH='@t6g_mb_lib.t6g(sch_1):page286_i32@pure_quanta.q_cap(chips)';

PART_NAME
 PC1233 'Q_CAP_C0805-10UF,16V,10%,X6S,CH6103KEA00':;

SECTION_NUMBER 1
 '@T6G_MB_LIB.T6G(SCH_1):PAGE286_I45@PURE_QUANTA.Q_CAP(CHIPS)':
 C_PATH='@t6g_mb_lib.t6g(sch_1):page286_i45@pure_quanta.q_cap(chips)';

PART_NAME
 PC1232 'Q_CAP_C0805-10UF,16V,10%,X6S,CH6103KEA00':;

SECTION_NUMBER 1
 '@T6G_MB_LIB.T6G(SCH_1):PAGE286_I44@PURE_QUANTA.Q_CAP(CHIPS)':
 C_PATH='@t6g_mb_lib.t6g(sch_1):page286_i44@pure_quanta.q_cap(chips)';

PART_NAME
 PU78_P1_4 'ISL99390FRZTR5935-ISL99390FRZ-TR5935,SMLF,IC,AL099390004':;

SECTION_NUMBER 1
 '@T6G_MB_LIB.T6G(SCH_1):PAGE313_I24@PURE_QUANTA.ISL99390FRZTR5935(CHIPS)':
 C_PATH='@s6q_mb_lib.s6q(sch_1):page313_i24@pure_quanta.isl99390frztr5935(chips)~
';

PART_NAME
 PU77_P1_3 'ISL99390FRZTR5935-ISL99390FRZ-TR5935,SMLF,IC,AL099390004':;

SECTION_NUMBER 1
 '@T6G_MB_LIB.T6G(SCH_1):PAGE313_I27@PURE_QUANTA.ISL99390FRZTR5935(CHIPS)':
 C_PATH='@s6q_mb_lib.s6q(sch_1):page313_i27@pure_quanta.isl99390frztr5935(chips)~
';

PART_NAME
 PR1803 'Q_RES_0402LF-3.3,1%,1/16W,CHIP,CS-3302FB00':;

SECTION_NUMBER 1
 '@T6G_MB_LIB.T6G(SCH_1):PAGE313_I34@PURE_QUANTA.Q_RES(CHIPS)':
 C_PATH='@t6g_mb_lib.t6g(sch_1):page313_i34@pure_quanta.q_res(chips)',
 CDSVAR_REPCELL_MPS='pure_quanta|Q_res',
 VAR_0_MPS='VALUE|0|TOLERANCE|5%|WATTAGE|1/16W|PACK_TYPE|0402LF|MATERIAL|CHIP|PA~
RT_NUMBER|CS00002JB38|STANDARD|End of Design|LIFECYCLE|Comp-Approve|PART_NUMBER|~
CS00002JB38|JEDEC_TYPE|R0402|ALT_SYMBOLS|(R0402-0201)|VALUE|0|TOL|5%|WATTAGE|1/1~
6W|CLASS|DISCRETE|DESCRIPTION|RESISTOR CHIP 0 1/16W +-5%(0402)|COMPONENT_TYPE|CH~
IP0402|LEAD_LENGTH||DFM_EXCLUSION||DAY|20100618|VARIANT_DEVICE_TYPE|Q_RES-0,5%,1~
/16W,0402LF,CHIP,C';

PART_NAME
 PR1802 'Q_RES_0402LF-3.3,1%,1/16W,CHIP,CS-3302FB00':;

SECTION_NUMBER 1
 '@T6G_MB_LIB.T6G(SCH_1):PAGE313_I43@PURE_QUANTA.Q_RES(CHIPS)':
 C_PATH='@t6g_mb_lib.t6g(sch_1):page313_i43@pure_quanta.q_res(chips)',
 CDSVAR_REPCELL_MPS='pure_quanta|Q_res',
 VAR_0_MPS='VALUE|0|TOLERANCE|5%|WATTAGE|1/16W|PACK_TYPE|0402LF|MATERIAL|CHIP|PA~
RT_NUMBER|CS00002JB38|STANDARD|End of Design|LIFECYCLE|Comp-Approve|PART_NUMBER|~
CS00002JB38|JEDEC_TYPE|R0402|ALT_SYMBOLS|(R0402-0201)|VALUE|0|TOL|5%|WATTAGE|1/1~
6W|CLASS|DISCRETE|DESCRIPTION|RESISTOR CHIP 0 1/16W +-5%(0402)|COMPONENT_TYPE|CH~
IP0402|LEAD_LENGTH||DFM_EXCLUSION||DAY|20100618|VARIANT_DEVICE_TYPE|Q_RES-0,5%,1~
/16W,0402LF,CHIP,C';

PART_NAME
 PR1334 'Q_RES_0402LF-0,5%,1/16W,CHIP,CS00002JB38':;

SECTION_NUMBER 1
 '@T6G_MB_LIB.T6G(SCH_1):PAGE313_I30@PURE_QUANTA.Q_RES(CHIPS)':
 C_PATH='@t6g_mb_lib.t6g(sch_1):page313_i30@pure_quanta.q_res(chips)',
 CDSVAR_REPCELL_MPS='pure_quanta|Q_res',
 VAR_0_MPS='VALUE|0|TOLERANCE|5%|WATTAGE|1/16W|PACK_TYPE|0402LF|MATERIAL|EMPTY|P~
ART_NUMBER|CS00002JB38|STANDARD|End of Design|LIFECYCLE|Comp-Approve|PART_NUMBER~
|CS00002JB38|JEDEC_TYPE|R0402|ALT_SYMBOLS|(R0402-0201)|VALUE|0|TOL|5%|WATTAGE|1/~
16W|CLASS|IO|DESCRIPTION|RESISTOR CHIP 0 1/16W +-5%(0402)|COMPONENT_TYPE|CHIP040~
2|LEAD_LENGTH||DFM_EXCLUSION||DAY|20100618|VARIANT_DEVICE_TYPE|Q_RES-0,5%,1/16W,~
0402LF,EMPTY,';

PART_NAME
 PR1333 'Q_RES_0402LF-0,5%,1/16W,CHIP,CS00002JB38':;

SECTION_NUMBER 1
 '@T6G_MB_LIB.T6G(SCH_1):PAGE313_I47@PURE_QUANTA.Q_RES(CHIPS)':
 C_PATH='@t6g_mb_lib.t6g(sch_1):page313_i47@pure_quanta.q_res(chips)',
 CDSVAR_REPCELL_MPS='pure_quanta|Q_res',
 VAR_0_MPS='VALUE|0|TOLERANCE|5%|WATTAGE|1/16W|PACK_TYPE|0402LF|MATERIAL|EMPTY|P~
ART_NUMBER|CS00002JB38|STANDARD|End of Design|LIFECYCLE|Comp-Approve|PART_NUMBER~
|CS00002JB38|JEDEC_TYPE|R0402|ALT_SYMBOLS|(R0402-0201)|VALUE|0|TOL|5%|WATTAGE|1/~
16W|CLASS|IO|DESCRIPTION|RESISTOR CHIP 0 1/16W +-5%(0402)|COMPONENT_TYPE|CHIP040~
2|LEAD_LENGTH||DFM_EXCLUSION||DAY|20100618|VARIANT_DEVICE_TYPE|Q_RES-0,5%,1/16W,~
0402LF,EMPTY,';

PART_NAME
 PR1307 'Q_RES_0402LF-2.2,1%,1/16W,CHIP,CS-2202FB00':;

SECTION_NUMBER 1
 '@T6G_MB_LIB.T6G(SCH_1):PAGE313_I10@PURE_QUANTA.Q_RES(CHIPS)':
 C_PATH='@t6g_mb_lib.t6g(sch_1):page313_i10@pure_quanta.q_res(chips)';

PART_NAME
 PR1306 'Q_RES_0402LF-2.2,1%,1/16W,CHIP,CS-2202FB00':;

SECTION_NUMBER 1
 '@T6G_MB_LIB.T6G(SCH_1):PAGE313_I21@PURE_QUANTA.Q_RES(CHIPS)':
 C_PATH='@t6g_mb_lib.t6g(sch_1):page313_i21@pure_quanta.q_res(chips)';

PART_NAME
 PR1305 'Q_RES_0402LF-8.87K,1%,1/16W,EMPTY,CS28872FB01':;

SECTION_NUMBER 1
 '@T6G_MB_LIB.T6G(SCH_1):PAGE313_I13@PURE_QUANTA.Q_RES(CHIPS)':
 C_PATH='@t6g_mb_lib.t6g(sch_1):page313_i13@pure_quanta.q_res(chips)';

PART_NAME
 PR1304 'Q_RES_0402LF-8.87K,1%,1/16W,EMPTY,CS28872FB01':;

SECTION_NUMBER 1
 '@T6G_MB_LIB.T6G(SCH_1):PAGE313_I2@PURE_QUANTA.Q_RES(CHIPS)':
 C_PATH='@t6g_mb_lib.t6g(sch_1):page313_i2@pure_quanta.q_res(chips)';

PART_NAME
 PL113 'Q_INDUCTOR_SMLF-130NH/106A,IND,CV+13^0KZ11':;

SECTION_NUMBER 1
 '@T6G_MB_LIB.T6G(SCH_1):PAGE313_I77@PURE_QUANTA.Q_INDUCTOR(CHIPS)':
 C_PATH='@t6g_mb_lib.t6g(sch_1):page313_i77@pure_quanta.q_inductor(chips)';

PART_NAME
 PL14 'Q_INDUCTOR_SMLF-100NH/16A,IND,CV+10G0MZ04':;

SECTION_NUMBER 1
 '@T6G_MB_LIB.T6G(SCH_1):PAGE313_I69@PURE_QUANTA.Q_INDUCTOR(CHIPS)':
 C_PATH='@t6g_mb_lib.t6g(sch_1):page313_i69@pure_quanta.q_inductor(chips)';

PART_NAME
 PL12 'Q_INDUCTOR_SMLF-130NH/106A,IND,CV+13^0KZ11':;

SECTION_NUMBER 1
 '@T6G_MB_LIB.T6G(SCH_1):PAGE313_I76@PURE_QUANTA.Q_INDUCTOR(CHIPS)':
 C_PATH='@t6g_mb_lib.t6g(sch_1):page313_i76@pure_quanta.q_inductor(chips)';

PART_NAME
 PC2172 'Q_CAPP_SMLF-470UF,2.5V,20%,EMPTY,CH747LM8816':;

SECTION_NUMBER 1
 '@T6G_MB_LIB.T6G(SCH_1):PAGE313_I63@PURE_QUANTA.Q_CAPP(CHIPS)':
 C_PATH='@t6g_mb_lib.t6g(sch_1):page313_i63@pure_quanta.q_capp(chips)';

PART_NAME
 PC1370 'Q_CAP_0402-0.1UF,25V,10%,X7R,CH4104K1B00':;

SECTION_NUMBER 1
 '@T6G_MB_LIB.T6G(SCH_1):PAGE313_I23@PURE_QUANTA.Q_CAP(CHIPS)':
 C_PATH='@t6g_mb_lib.t6g(sch_1):page313_i23@pure_quanta.q_cap(chips)',
 CDSVAR_REPCELL_MPS='pure_quanta|Q_cap',
 VAR_0_MPS='VALUE|0.1UF|VOLTAGE|25V|TOLERANCE|10%|PACK_TYPE|0402|MATERIAL|EMPTY|~
PART_NUMBER|CH4104K1B00|STANDARD||LIFECYCLE||ASS_PART||PART_NUMBER|CH4104K1B00|J~
EDEC_TYPE|C0402|ALT_SYMBOLS|(C0402_OCTAGONXA,C0402-0201)|VALUE|NA|RATED_VOLTAGE|~
25V|TOL|10%|CLASS|IO|DESCRIPTION|CAP CHIP 0.1U 25V(+-10%,X7R,0402)|COMPONENT_TYP~
E|CHIP0402|LEAD_LENGTH||LPID||DATE|20160113|VARIANT_DEVICE_TYPE|Q_CAP-0.1UF,25V,~
10%,0402,EMPTY';

PART_NAME
 PC1369 'Q_CAP_0402-0.1UF,25V,10%,X7R,CH4104K1B00':;

SECTION_NUMBER 1
 '@T6G_MB_LIB.T6G(SCH_1):PAGE313_I40@PURE_QUANTA.Q_CAP(CHIPS)':
 C_PATH='@t6g_mb_lib.t6g(sch_1):page313_i40@pure_quanta.q_cap(chips)',
 CDSVAR_REPCELL_MPS='pure_quanta|Q_cap',
 VAR_0_MPS='VALUE|0.1UF|VOLTAGE|25V|TOLERANCE|10%|PACK_TYPE|0402|MATERIAL|EMPTY|~
PART_NUMBER|CH4104K1B00|STANDARD||LIFECYCLE||ASS_PART||PART_NUMBER|CH4104K1B00|J~
EDEC_TYPE|C0402|ALT_SYMBOLS|(C0402_OCTAGONXA,C0402-0201)|VALUE|NA|RATED_VOLTAGE|~
25V|TOL|10%|CLASS|IO|DESCRIPTION|CAP CHIP 0.1U 25V(+-10%,X7R,0402)|COMPONENT_TYP~
E|CHIP0402|LEAD_LENGTH||LPID||DATE|20160113|VARIANT_DEVICE_TYPE|Q_CAP-0.1UF,25V,~
10%,0402,EMPTY';

PART_NAME
 PC1245_P1_4 'Q_CAP_C0402-2.2UF,10V,10%,X6S,CH5222KEB01':;

SECTION_NUMBER 1
 '@T6G_MB_LIB.T6G(SCH_1):PAGE313_I26@PURE_QUANTA.Q_CAP(CHIPS)':
 C_PATH='@t6g_mb_lib.t6g(sch_1):page313_i26@pure_quanta.q_cap(chips)';

PART_NAME
 PC1244_P1_3 'Q_CAP_C0402-2.2UF,10V,10%,X6S,CH5222KEB01':;

SECTION_NUMBER 1
 '@T6G_MB_LIB.T6G(SCH_1):PAGE313_I42@PURE_QUANTA.Q_CAP(CHIPS)':
 C_PATH='@t6g_mb_lib.t6g(sch_1):page313_i42@pure_quanta.q_cap(chips)';

PART_NAME
 PC1210 'Q_CAPP_THLF-270UF,16V,20%,OSCON,CC72703MD33':;

SECTION_NUMBER 1
 '@T6G_MB_LIB.T6G(SCH_1):PAGE313_I73@PURE_QUANTA.Q_CAPP(CHIPS)':
 C_PATH='@t6g_mb_lib.t6g(sch_1):page313_i73@pure_quanta.q_capp(chips)';

PART_NAME
 PC1209_P1_4 'Q_CAP_0805-22UF,4V,20%,X6S,TMP_QCH622KMEA01':;

SECTION_NUMBER 1
 '@T6G_MB_LIB.T6G(SCH_1):PAGE313_I54@PURE_QUANTA.Q_CAP(CHIPS)':
 C_PATH='@t6g_mb_lib.t6g(sch_1):page313_i54@pure_quanta.q_cap(chips)';

PART_NAME
 PC1208_P1_3 'Q_CAP_0805-22UF,4V,20%,X6S,TMP_QCH622KMEA01':;

SECTION_NUMBER 1
 '@T6G_MB_LIB.T6G(SCH_1):PAGE313_I68@PURE_QUANTA.Q_CAP(CHIPS)':
 C_PATH='@t6g_mb_lib.t6g(sch_1):page313_i68@pure_quanta.q_cap(chips)';

PART_NAME
 PC1207_P1_4 'Q_CAP_0805-22UF,4V,20%,X6S,TMP_QCH622KMEA01':;

SECTION_NUMBER 1
 '@T6G_MB_LIB.T6G(SCH_1):PAGE313_I75@PURE_QUANTA.Q_CAP(CHIPS)':
 C_PATH='@t6g_mb_lib.t6g(sch_1):page313_i75@pure_quanta.q_cap(chips)';

PART_NAME
 PC1206_P1_3 'Q_CAP_0805-22UF,4V,20%,X6S,TMP_QCH622KMEA01':;

SECTION_NUMBER 1
 '@T6G_MB_LIB.T6G(SCH_1):PAGE313_I67@PURE_QUANTA.Q_CAP(CHIPS)':
 C_PATH='@t6g_mb_lib.t6g(sch_1):page313_i67@pure_quanta.q_cap(chips)';

PART_NAME
 PC1205 'Q_CAPP_SMLF-470UF,2.5V,20%,POSCAP,CH747LM8816':;

SECTION_NUMBER 1
 '@T6G_MB_LIB.T6G(SCH_1):PAGE313_I61@PURE_QUANTA.Q_CAPP(CHIPS)':
 C_PATH='@t6g_mb_lib.t6g(sch_1):page313_i61@pure_quanta.q_capp(chips)';

PART_NAME
 PC1204_P1_3 'Q_CAP_C0402-1UF,16V,10%,X6S,CH5103KEB01':;

SECTION_NUMBER 1
 '@T6G_MB_LIB.T6G(SCH_1):PAGE313_I66@PURE_QUANTA.Q_CAP(CHIPS)':
 C_PATH='@t6g_mb_lib.t6g(sch_1):page313_i66@pure_quanta.q_cap(chips)';

PART_NAME
 PC1204 'Q_CAPP_THLF-560UF,2.5V,20%,OSCON,CC7560JMD18':;

SECTION_NUMBER 1
 '@T6G_MB_LIB.T6G(SCH_1):PAGE313_I59@PURE_QUANTA.Q_CAPP(CHIPS)':
 C_PATH='@t6g_mb_lib.t6g(sch_1):page313_i59@pure_quanta.q_capp(chips)';

PART_NAME
 PC1203_P1_4 'Q_CAP_C0402-100NF,50V,10%,X7R,CH4106K1B01':;

SECTION_NUMBER 1
 '@T6G_MB_LIB.T6G(SCH_1):PAGE313_I80@PURE_QUANTA.Q_CAP(CHIPS)':
 C_PATH='@t6g_mb_lib.t6g(sch_1):page313_i80@pure_quanta.q_cap(chips)';

PART_NAME
 PC1203 'Q_CAPP_THLF-560UF,2.5V,20%,OSCON,CC7560JMD18':;

SECTION_NUMBER 1
 '@T6G_MB_LIB.T6G(SCH_1):PAGE313_I56@PURE_QUANTA.Q_CAPP(CHIPS)':
 C_PATH='@t6g_mb_lib.t6g(sch_1):page313_i56@pure_quanta.q_capp(chips)';

PART_NAME
 PC1202_P1_4 'Q_CAP_C0805-22UF,16V,20%,X6S,CH6223MEA00':;

SECTION_NUMBER 1
 '@T6G_MB_LIB.T6G(SCH_1):PAGE313_I37@PURE_QUANTA.Q_CAP(CHIPS)':
 C_PATH='@t6g_mb_lib.t6g(sch_1):page313_i37@pure_quanta.q_cap(chips)';

PART_NAME
 PC1201_P1_3 'Q_CAP_C0805-22UF,16V,20%,X6S,CH6223MEA00':;

SECTION_NUMBER 1
 '@T6G_MB_LIB.T6G(SCH_1):PAGE313_I51@PURE_QUANTA.Q_CAP(CHIPS)':
 C_PATH='@t6g_mb_lib.t6g(sch_1):page313_i51@pure_quanta.q_cap(chips)';

PART_NAME
 PC1201 'Q_CAPP_THLF-560UF,2.5V,20%,OSCON,CC7560JMD18':;

SECTION_NUMBER 1
 '@T6G_MB_LIB.T6G(SCH_1):PAGE313_I55@PURE_QUANTA.Q_CAPP(CHIPS)':
 C_PATH='@t6g_mb_lib.t6g(sch_1):page313_i55@pure_quanta.q_capp(chips)';

PART_NAME
 PC1200_P1_4 'Q_CAP_C0805-22UF,16V,20%,X6S,CH6223MEA00':;

SECTION_NUMBER 1
 '@T6G_MB_LIB.T6G(SCH_1):PAGE313_I36@PURE_QUANTA.Q_CAP(CHIPS)':
 C_PATH='@t6g_mb_lib.t6g(sch_1):page313_i36@pure_quanta.q_cap(chips)';

PART_NAME
 PC1199_P1_3 'Q_CAP_C0805-22UF,16V,20%,X6S,CH6223MEA00':;

SECTION_NUMBER 1
 '@T6G_MB_LIB.T6G(SCH_1):PAGE313_I46@PURE_QUANTA.Q_CAP(CHIPS)':
 C_PATH='@t6g_mb_lib.t6g(sch_1):page313_i46@pure_quanta.q_cap(chips)';

PART_NAME
 PC1198 'Q_CAP_C0402-100NF,50V,10%,X7R,CH4106K1B01':;

SECTION_NUMBER 1
 '@T6G_MB_LIB.T6G(SCH_1):PAGE313_I31@PURE_QUANTA.Q_CAP(CHIPS)':
 C_PATH='@t6g_mb_lib.t6g(sch_1):page313_i31@pure_quanta.q_cap(chips)';

PART_NAME
 PC1197 'Q_CAP_C0402-100NF,50V,10%,X7R,CH4106K1B01':;

SECTION_NUMBER 1
 '@T6G_MB_LIB.T6G(SCH_1):PAGE313_I48@PURE_QUANTA.Q_CAP(CHIPS)':
 C_PATH='@t6g_mb_lib.t6g(sch_1):page313_i48@pure_quanta.q_cap(chips)';

PART_NAME
 PC1196_P1_4 'Q_CAP_C0402-1UF,16V,10%,X6S,CH5103KEB01':;

SECTION_NUMBER 1
 '@T6G_MB_LIB.T6G(SCH_1):PAGE313_I35@PURE_QUANTA.Q_CAP(CHIPS)':
 C_PATH='@t6g_mb_lib.t6g(sch_1):page313_i35@pure_quanta.q_cap(chips)';

PART_NAME
 PC1195_P1_3 'Q_CAP_C0402-1UF,16V,10%,X6S,CH5103KEB01':;

SECTION_NUMBER 1
 '@T6G_MB_LIB.T6G(SCH_1):PAGE313_I45@PURE_QUANTA.Q_CAP(CHIPS)':
 C_PATH='@t6g_mb_lib.t6g(sch_1):page313_i45@pure_quanta.q_cap(chips)';

PART_NAME
 PC1194_P1_4 'Q_CAP_0402-3300PF,50V,10%,X7R,TMP_QCH2336K1B12':;

SECTION_NUMBER 1
 '@T6G_MB_LIB.T6G(SCH_1):PAGE313_I33@PURE_QUANTA.Q_CAP(CHIPS)':
 C_PATH='@t6g_mb_lib.t6g(sch_1):page313_i33@pure_quanta.q_cap(chips)';

PART_NAME
 PC1193_P1_3 'Q_CAP_0402-3300PF,50V,10%,X7R,TMP_QCH2336K1B12':;

SECTION_NUMBER 1
 '@T6G_MB_LIB.T6G(SCH_1):PAGE313_I44@PURE_QUANTA.Q_CAP(CHIPS)':
 C_PATH='@t6g_mb_lib.t6g(sch_1):page313_i44@pure_quanta.q_cap(chips)';

PART_NAME
 PC1192 'Q_CAP_C0402-2.2UF,10V,10%,X6S,CH5222KEB01':;

SECTION_NUMBER 1
 '@T6G_MB_LIB.T6G(SCH_1):PAGE313_I9@PURE_QUANTA.Q_CAP(CHIPS)':
 C_PATH='@t6g_mb_lib.t6g(sch_1):page313_i9@pure_quanta.q_cap(chips)';

PART_NAME
 PC1191 'Q_CAP_C0402-2.2UF,10V,10%,X6S,CH5222KEB01':;

SECTION_NUMBER 1
 '@T6G_MB_LIB.T6G(SCH_1):PAGE313_I20@PURE_QUANTA.Q_CAP(CHIPS)':
 C_PATH='@t6g_mb_lib.t6g(sch_1):page313_i20@pure_quanta.q_cap(chips)';

PART_NAME
 PU72_P0_4 'ISL99390FRZTR5935-ISL99390FRZ-TR5935,SMLF,IC,AL099390004':;

SECTION_NUMBER 1
 '@T6G_MB_LIB.T6G(SCH_1):PAGE295_I24@PURE_QUANTA.ISL99390FRZTR5935(CHIPS)':
 C_PATH='@s6q_mb_lib.s6q(sch_1):page295_i24@pure_quanta.isl99390frztr5935(chips)~
';

PART_NAME
 PU71_P0_3 'ISL99390FRZTR5935-ISL99390FRZ-TR5935,SMLF,IC,AL099390004':;

SECTION_NUMBER 1
 '@T6G_MB_LIB.T6G(SCH_1):PAGE295_I40@PURE_QUANTA.ISL99390FRZTR5935(CHIPS)':
 C_PATH='@s6q_mb_lib.s6q(sch_1):page295_i40@pure_quanta.isl99390frztr5935(chips)~
';

PART_NAME
 PR1783 'Q_RES_0402LF-3.3,1%,1/16W,CHIP,CS-3302FB00':;

SECTION_NUMBER 1
 '@T6G_MB_LIB.T6G(SCH_1):PAGE295_I33@PURE_QUANTA.Q_RES(CHIPS)':
 C_PATH='@t6g_mb_lib.t6g(sch_1):page295_i33@pure_quanta.q_res(chips)',
 CDSVAR_REPCELL_MPS='pure_quanta|Q_res',
 VAR_0_MPS='VALUE|0|TOLERANCE|5%|WATTAGE|1/16W|PACK_TYPE|0402LF|MATERIAL|CHIP|PA~
RT_NUMBER|CS00002JB38|STANDARD|End of Design|LIFECYCLE|Comp-Approve|PART_NUMBER|~
CS00002JB38|JEDEC_TYPE|R0402|ALT_SYMBOLS|(R0402-0201)|VALUE|0|TOL|5%|WATTAGE|1/1~
6W|CLASS|DISCRETE|DESCRIPTION|RESISTOR CHIP 0 1/16W +-5%(0402)|COMPONENT_TYPE|CH~
IP0402|LEAD_LENGTH||DFM_EXCLUSION||DAY|20100618|VARIANT_DEVICE_TYPE|Q_RES-0,5%,1~
/16W,0402LF,CHIP,C';

PART_NAME
 PR1782 'Q_RES_0402LF-3.3,1%,1/16W,CHIP,CS-3302FB00':;

SECTION_NUMBER 1
 '@T6G_MB_LIB.T6G(SCH_1):PAGE295_I45@PURE_QUANTA.Q_RES(CHIPS)':
 C_PATH='@t6g_mb_lib.t6g(sch_1):page295_i45@pure_quanta.q_res(chips)',
 CDSVAR_REPCELL_MPS='pure_quanta|Q_res',
 VAR_0_MPS='VALUE|0|TOLERANCE|5%|WATTAGE|1/16W|PACK_TYPE|0402LF|MATERIAL|CHIP|PA~
RT_NUMBER|CS00002JB38|STANDARD|End of Design|LIFECYCLE|Comp-Approve|PART_NUMBER|~
CS00002JB38|JEDEC_TYPE|R0402|ALT_SYMBOLS|(R0402-0201)|VALUE|0|TOL|5%|WATTAGE|1/1~
6W|CLASS|DISCRETE|DESCRIPTION|RESISTOR CHIP 0 1/16W +-5%(0402)|COMPONENT_TYPE|CH~
IP0402|LEAD_LENGTH||DFM_EXCLUSION||DAY|20100618|VARIANT_DEVICE_TYPE|Q_RES-0,5%,1~
/16W,0402LF,CHIP,C';

PART_NAME
 PR1325 'Q_RES_0402LF-0,5%,1/16W,CHIP,CS00002JB38':;

SECTION_NUMBER 1
 '@T6G_MB_LIB.T6G(SCH_1):PAGE295_I29@PURE_QUANTA.Q_RES(CHIPS)':
 C_PATH='@t6g_mb_lib.t6g(sch_1):page295_i29@pure_quanta.q_res(chips)',
 CDSVAR_REPCELL_MPS='pure_quanta|Q_res',
 VAR_0_MPS='VALUE|0|TOLERANCE|5%|WATTAGE|1/16W|PACK_TYPE|0402LF|MATERIAL|EMPTY|P~
ART_NUMBER|CS00002JB38|STANDARD|End of Design|LIFECYCLE|Comp-Approve|PART_NUMBER~
|CS00002JB38|JEDEC_TYPE|R0402|ALT_SYMBOLS|(R0402-0201)|VALUE|0|TOL|5%|WATTAGE|1/~
16W|CLASS|IO|DESCRIPTION|RESISTOR CHIP 0 1/16W +-5%(0402)|COMPONENT_TYPE|CHIP040~
2|LEAD_LENGTH||DFM_EXCLUSION||DAY|20100618|VARIANT_DEVICE_TYPE|Q_RES-0,5%,1/16W,~
0402LF,EMPTY,';

PART_NAME
 PR1324 'Q_RES_0402LF-0,5%,1/16W,CHIP,CS00002JB38':;

SECTION_NUMBER 1
 '@T6G_MB_LIB.T6G(SCH_1):PAGE295_I47@PURE_QUANTA.Q_RES(CHIPS)':
 C_PATH='@t6g_mb_lib.t6g(sch_1):page295_i47@pure_quanta.q_res(chips)',
 CDSVAR_REPCELL_MPS='pure_quanta|Q_res',
 VAR_0_MPS='VALUE|0|TOLERANCE|5%|WATTAGE|1/16W|PACK_TYPE|0402LF|MATERIAL|EMPTY|P~
ART_NUMBER|CS00002JB38|STANDARD|End of Design|LIFECYCLE|Comp-Approve|PART_NUMBER~
|CS00002JB38|JEDEC_TYPE|R0402|ALT_SYMBOLS|(R0402-0201)|VALUE|0|TOL|5%|WATTAGE|1/~
16W|CLASS|IO|DESCRIPTION|RESISTOR CHIP 0 1/16W +-5%(0402)|COMPONENT_TYPE|CHIP040~
2|LEAD_LENGTH||DFM_EXCLUSION||DAY|20100618|VARIANT_DEVICE_TYPE|Q_RES-0,5%,1/16W,~
0402LF,EMPTY,';

PART_NAME
 PR1300 'Q_RES_0402LF-2.2,1%,1/16W,CHIP,CS-2202FB00':;

SECTION_NUMBER 1
 '@T6G_MB_LIB.T6G(SCH_1):PAGE295_I10@PURE_QUANTA.Q_RES(CHIPS)':
 C_PATH='@t6g_mb_lib.t6g(sch_1):page295_i10@pure_quanta.q_res(chips)';

PART_NAME
 PR1299 'Q_RES_0402LF-2.2,1%,1/16W,CHIP,CS-2202FB00':;

SECTION_NUMBER 1
 '@T6G_MB_LIB.T6G(SCH_1):PAGE295_I21@PURE_QUANTA.Q_RES(CHIPS)':
 C_PATH='@t6g_mb_lib.t6g(sch_1):page295_i21@pure_quanta.q_res(chips)';

PART_NAME
 PR1298 'Q_RES_0402LF-8.87K,1%,1/16W,EMPTY,CS28872FB01':;

SECTION_NUMBER 1
 '@T6G_MB_LIB.T6G(SCH_1):PAGE295_I13@PURE_QUANTA.Q_RES(CHIPS)':
 C_PATH='@t6g_mb_lib.t6g(sch_1):page295_i13@pure_quanta.q_res(chips)';

PART_NAME
 PR1297 'Q_RES_0402LF-8.87K,1%,1/16W,EMPTY,CS28872FB01':;

SECTION_NUMBER 1
 '@T6G_MB_LIB.T6G(SCH_1):PAGE295_I2@PURE_QUANTA.Q_RES(CHIPS)':
 C_PATH='@t6g_mb_lib.t6g(sch_1):page295_i2@pure_quanta.q_res(chips)';

PART_NAME
 PL210 'Q_INDUCTOR_SMLF-130NH/106A,IND,CV+13^0KZ11':;

SECTION_NUMBER 1
 '@T6G_MB_LIB.T6G(SCH_1):PAGE295_I30@PURE_QUANTA.Q_INDUCTOR(CHIPS)':
 C_PATH='@t6g_mb_lib.t6g(sch_1):page295_i30@pure_quanta.q_inductor(chips)';

PART_NAME
 PL101 'Q_INDUCTOR_SMLF-100NH/16A,IND,CV+10G0MZ04':;

SECTION_NUMBER 1
 '@T6G_MB_LIB.T6G(SCH_1):PAGE295_I69@PURE_QUANTA.Q_INDUCTOR(CHIPS)':
 C_PATH='@t6g_mb_lib.t6g(sch_1):page295_i69@pure_quanta.q_inductor(chips)';

PART_NAME
 PL2 'Q_INDUCTOR_SMLF-130NH/106A,IND,CV+13^0KZ11':;

SECTION_NUMBER 1
 '@T6G_MB_LIB.T6G(SCH_1):PAGE295_I75@PURE_QUANTA.Q_INDUCTOR(CHIPS)':
 C_PATH='@t6g_mb_lib.t6g(sch_1):page295_i75@pure_quanta.q_inductor(chips)';

PART_NAME
 PC2170 'Q_CAPP_SMLF-470UF,2.5V,20%,EMPTY,CH747LM8816':;

SECTION_NUMBER 1
 '@T6G_MB_LIB.T6G(SCH_1):PAGE295_I63@PURE_QUANTA.Q_CAPP(CHIPS)':
 C_PATH='@t6g_mb_lib.t6g(sch_1):page295_i63@pure_quanta.q_capp(chips)';

PART_NAME
 PC1352 'Q_CAP_0402-0.1UF,25V,10%,X7R,CH4104K1B00':;

SECTION_NUMBER 1
 '@T6G_MB_LIB.T6G(SCH_1):PAGE295_I23@PURE_QUANTA.Q_CAP(CHIPS)':
 C_PATH='@t6g_mb_lib.t6g(sch_1):page295_i23@pure_quanta.q_cap(chips)',
 CDSVAR_REPCELL_MPS='pure_quanta|Q_cap',
 VAR_0_MPS='VALUE|0.1UF|VOLTAGE|25V|TOLERANCE|10%|PACK_TYPE|0402|MATERIAL|EMPTY|~
PART_NUMBER|CH4104K1B00|STANDARD||LIFECYCLE||ASS_PART||PART_NUMBER|CH4104K1B00|J~
EDEC_TYPE|C0402|ALT_SYMBOLS|(C0402_OCTAGONXA,C0402-0201)|VALUE|NA|RATED_VOLTAGE|~
25V|TOL|10%|CLASS|IO|DESCRIPTION|CAP CHIP 0.1U 25V(+-10%,X7R,0402)|COMPONENT_TYP~
E|CHIP0402|LEAD_LENGTH||LPID||DATE|20160113|VARIANT_DEVICE_TYPE|Q_CAP-0.1UF,25V,~
10%,0402,EMPTY';

PART_NAME
 PC1351 'Q_CAP_0402-0.1UF,25V,10%,X7R,CH4104K1B00':;

SECTION_NUMBER 1
 '@T6G_MB_LIB.T6G(SCH_1):PAGE295_I39@PURE_QUANTA.Q_CAP(CHIPS)':
 C_PATH='@t6g_mb_lib.t6g(sch_1):page295_i39@pure_quanta.q_cap(chips)',
 CDSVAR_REPCELL_MPS='pure_quanta|Q_cap',
 VAR_0_MPS='VALUE|0.1UF|VOLTAGE|25V|TOLERANCE|10%|PACK_TYPE|0402|MATERIAL|EMPTY|~
PART_NUMBER|CH4104K1B00|STANDARD||LIFECYCLE||ASS_PART||PART_NUMBER|CH4104K1B00|J~
EDEC_TYPE|C0402|ALT_SYMBOLS|(C0402_OCTAGONXA,C0402-0201)|VALUE|NA|RATED_VOLTAGE|~
25V|TOL|10%|CLASS|IO|DESCRIPTION|CAP CHIP 0.1U 25V(+-10%,X7R,0402)|COMPONENT_TYP~
E|CHIP0402|LEAD_LENGTH||LPID||DATE|20160113|VARIANT_DEVICE_TYPE|Q_CAP-0.1UF,25V,~
10%,0402,EMPTY';

PART_NAME
 PC1214_P0_4 'Q_CAP_C0402-2.2UF,10V,10%,X6S,CH5222KEB01':;

SECTION_NUMBER 1
 '@T6G_MB_LIB.T6G(SCH_1):PAGE295_I26@PURE_QUANTA.Q_CAP(CHIPS)':
 C_PATH='@t6g_mb_lib.t6g(sch_1):page295_i26@pure_quanta.q_cap(chips)';

PART_NAME
 PC1213_P0_3 'Q_CAP_C0402-2.2UF,10V,10%,X6S,CH5222KEB01':;

SECTION_NUMBER 1
 '@T6G_MB_LIB.T6G(SCH_1):PAGE295_I42@PURE_QUANTA.Q_CAP(CHIPS)':
 C_PATH='@t6g_mb_lib.t6g(sch_1):page295_i42@pure_quanta.q_cap(chips)';

PART_NAME
 PC1189 'Q_CAPP_THLF-270UF,16V,20%,OSCON,CC72703MD33':;

SECTION_NUMBER 1
 '@T6G_MB_LIB.T6G(SCH_1):PAGE295_I73@PURE_QUANTA.Q_CAPP(CHIPS)':
 C_PATH='@t6g_mb_lib.t6g(sch_1):page295_i73@pure_quanta.q_capp(chips)';

PART_NAME
 PC1188_P0_4 'Q_CAP_0805-22UF,4V,20%,X6S,TMP_QCH622KMEA01':;

SECTION_NUMBER 1
 '@T6G_MB_LIB.T6G(SCH_1):PAGE295_I55@PURE_QUANTA.Q_CAP(CHIPS)':
 C_PATH='@t6g_mb_lib.t6g(sch_1):page295_i55@pure_quanta.q_cap(chips)';

PART_NAME
 PC1187_P0_3 'Q_CAP_0805-22UF,4V,20%,X6S,TMP_QCH622KMEA01':;

SECTION_NUMBER 1
 '@T6G_MB_LIB.T6G(SCH_1):PAGE295_I68@PURE_QUANTA.Q_CAP(CHIPS)':
 C_PATH='@t6g_mb_lib.t6g(sch_1):page295_i68@pure_quanta.q_cap(chips)';

PART_NAME
 PC1187 'Q_CAPP_SMLF-470UF,2.5V,20%,POSCAP,CH747LM8816':;

SECTION_NUMBER 1
 '@T6G_MB_LIB.T6G(SCH_1):PAGE295_I61@PURE_QUANTA.Q_CAPP(CHIPS)':
 C_PATH='@t6g_mb_lib.t6g(sch_1):page295_i61@pure_quanta.q_capp(chips)';

PART_NAME
 PC1186_P0_4 'Q_CAP_0805-22UF,4V,20%,X6S,TMP_QCH622KMEA01':;

SECTION_NUMBER 1
 '@T6G_MB_LIB.T6G(SCH_1):PAGE295_I54@PURE_QUANTA.Q_CAP(CHIPS)':
 C_PATH='@t6g_mb_lib.t6g(sch_1):page295_i54@pure_quanta.q_cap(chips)';

PART_NAME
 PC1186 'Q_CAPP_THLF-560UF,2.5V,20%,OSCON,CC7560JMD18':;

SECTION_NUMBER 1
 '@T6G_MB_LIB.T6G(SCH_1):PAGE295_I60@PURE_QUANTA.Q_CAPP(CHIPS)':
 C_PATH='@t6g_mb_lib.t6g(sch_1):page295_i60@pure_quanta.q_capp(chips)';

PART_NAME
 PC1185_P0_3 'Q_CAP_0805-22UF,4V,20%,X6S,TMP_QCH622KMEA01':;

SECTION_NUMBER 1
 '@T6G_MB_LIB.T6G(SCH_1):PAGE295_I67@PURE_QUANTA.Q_CAP(CHIPS)':
 C_PATH='@t6g_mb_lib.t6g(sch_1):page295_i67@pure_quanta.q_cap(chips)';

PART_NAME
 PC1185 'Q_CAPP_THLF-560UF,2.5V,20%,OSCON,CC7560JMD18':;

SECTION_NUMBER 1
 '@T6G_MB_LIB.T6G(SCH_1):PAGE295_I57@PURE_QUANTA.Q_CAPP(CHIPS)':
 C_PATH='@t6g_mb_lib.t6g(sch_1):page295_i57@pure_quanta.q_capp(chips)';

PART_NAME
 PC1183_P0_4 'Q_CAP_C0402-100NF,50V,10%,X7R,CH4106K1B01':;

SECTION_NUMBER 1
 '@T6G_MB_LIB.T6G(SCH_1):PAGE295_I53@PURE_QUANTA.Q_CAP(CHIPS)':
 C_PATH='@t6g_mb_lib.t6g(sch_1):page295_i53@pure_quanta.q_cap(chips)';

PART_NAME
 PC1183_P0_3 'Q_CAP_C0402-1UF,16V,10%,X6S,CH5103KEB01':;

SECTION_NUMBER 1
 '@T6G_MB_LIB.T6G(SCH_1):PAGE295_I65@PURE_QUANTA.Q_CAP(CHIPS)':
 C_PATH='@t6g_mb_lib.t6g(sch_1):page295_i65@pure_quanta.q_cap(chips)';

PART_NAME
 PC1183 'Q_CAPP_THLF-560UF,2.5V,20%,OSCON,CC7560JMD18':;

SECTION_NUMBER 1
 '@T6G_MB_LIB.T6G(SCH_1):PAGE295_I56@PURE_QUANTA.Q_CAPP(CHIPS)':
 C_PATH='@t6g_mb_lib.t6g(sch_1):page295_i56@pure_quanta.q_capp(chips)';

PART_NAME
 PC1182_P0_4 'Q_CAP_C0805-22UF,16V,20%,X6S,CH6223MEA00':;

SECTION_NUMBER 1
 '@T6G_MB_LIB.T6G(SCH_1):PAGE295_I35@PURE_QUANTA.Q_CAP(CHIPS)':
 C_PATH='@t6g_mb_lib.t6g(sch_1):page295_i35@pure_quanta.q_cap(chips)';

PART_NAME
 PC1181_P0_3 'Q_CAP_C0805-22UF,16V,20%,X6S,CH6223MEA00':;

SECTION_NUMBER 1
 '@T6G_MB_LIB.T6G(SCH_1):PAGE295_I50@PURE_QUANTA.Q_CAP(CHIPS)':
 C_PATH='@t6g_mb_lib.t6g(sch_1):page295_i50@pure_quanta.q_cap(chips)';

PART_NAME
 PC1180_P0_4 'Q_CAP_C0805-22UF,16V,20%,X6S,CH6223MEA00':;

SECTION_NUMBER 1
 '@T6G_MB_LIB.T6G(SCH_1):PAGE295_I34@PURE_QUANTA.Q_CAP(CHIPS)':
 C_PATH='@t6g_mb_lib.t6g(sch_1):page295_i34@pure_quanta.q_cap(chips)';

PART_NAME
 PC1179_P0_3 'Q_CAP_C0805-22UF,16V,20%,X6S,CH6223MEA00':;

SECTION_NUMBER 1
 '@T6G_MB_LIB.T6G(SCH_1):PAGE295_I46@PURE_QUANTA.Q_CAP(CHIPS)':
 C_PATH='@t6g_mb_lib.t6g(sch_1):page295_i46@pure_quanta.q_cap(chips)';

PART_NAME
 PC1178 'Q_CAP_C0402-100NF,50V,10%,X7R,CH4106K1B01':;

SECTION_NUMBER 1
 '@T6G_MB_LIB.T6G(SCH_1):PAGE295_I36@PURE_QUANTA.Q_CAP(CHIPS)':
 C_PATH='@t6g_mb_lib.t6g(sch_1):page295_i36@pure_quanta.q_cap(chips)';

PART_NAME
 PC1177 'Q_CAP_C0402-100NF,50V,10%,X7R,CH4106K1B01':;

SECTION_NUMBER 1
 '@T6G_MB_LIB.T6G(SCH_1):PAGE295_I48@PURE_QUANTA.Q_CAP(CHIPS)':
 C_PATH='@t6g_mb_lib.t6g(sch_1):page295_i48@pure_quanta.q_cap(chips)';

PART_NAME
 PC1176_P0_4 'Q_CAP_C0402-1UF,16V,10%,X6S,CH5103KEB01':;

SECTION_NUMBER 1
 '@T6G_MB_LIB.T6G(SCH_1):PAGE295_I32@PURE_QUANTA.Q_CAP(CHIPS)':
 C_PATH='@t6g_mb_lib.t6g(sch_1):page295_i32@pure_quanta.q_cap(chips)';

PART_NAME
 PC1175_P0_3 'Q_CAP_C0402-1UF,16V,10%,X6S,CH5103KEB01':;

SECTION_NUMBER 1
 '@T6G_MB_LIB.T6G(SCH_1):PAGE295_I44@PURE_QUANTA.Q_CAP(CHIPS)':
 C_PATH='@t6g_mb_lib.t6g(sch_1):page295_i44@pure_quanta.q_cap(chips)';

PART_NAME
 PC1174_P0_4 'Q_CAP_0402-3300PF,50V,10%,X7R,TMP_QCH2336K1B12':;

SECTION_NUMBER 1
 '@T6G_MB_LIB.T6G(SCH_1):PAGE295_I31@PURE_QUANTA.Q_CAP(CHIPS)':
 C_PATH='@t6g_mb_lib.t6g(sch_1):page295_i31@pure_quanta.q_cap(chips)';

PART_NAME
 PC1173_P0_3 'Q_CAP_0402-3300PF,50V,10%,X7R,TMP_QCH2336K1B12':;

SECTION_NUMBER 1
 '@T6G_MB_LIB.T6G(SCH_1):PAGE295_I43@PURE_QUANTA.Q_CAP(CHIPS)':
 C_PATH='@t6g_mb_lib.t6g(sch_1):page295_i43@pure_quanta.q_cap(chips)';

PART_NAME
 PC1172 'Q_CAP_C0402-2.2UF,10V,10%,X6S,CH5222KEB01':;

SECTION_NUMBER 1
 '@T6G_MB_LIB.T6G(SCH_1):PAGE295_I9@PURE_QUANTA.Q_CAP(CHIPS)':
 C_PATH='@t6g_mb_lib.t6g(sch_1):page295_i9@pure_quanta.q_cap(chips)';

PART_NAME
 PC1171 'Q_CAP_C0402-2.2UF,10V,10%,X6S,CH5222KEB01':;

SECTION_NUMBER 1
 '@T6G_MB_LIB.T6G(SCH_1):PAGE295_I20@PURE_QUANTA.Q_CAP(CHIPS)':
 C_PATH='@t6g_mb_lib.t6g(sch_1):page295_i20@pure_quanta.q_cap(chips)';

PART_NAME
 PU36 'RAA2213404GNPHB0-RAA2213404GNP#HB0,SMLF,IC,AL221340000':;

SECTION_NUMBER 1
 '@T6G_MB_LIB.T6G(SCH_1):PAGE302_I333@PURE_QUANTA.RAA2213404GNPHB0(CHIPS)':
 C_PATH='@s6q_mb_lib.s6q(sch_1):page302_i333@pure_quanta.raa2213404gnphb0(chips)~
',
 CDSVAR_REPCELL_MPS='pure_quanta|mp86950glvtz',
 VAR_0_MPS='VAR_REPLACED|RAA2213404GNPHB0|VAR_PARTNAME|MP86950GLVTZ|VALUE|MP8695~
0GLVT-Z|PART_TYPE|SMLF|MATERIAL|IC|PART_NUMBER|AL086950A00|STANDARD||LIFECYCLE||~
PART_NUMBER|AL086950A00|JEDEC_TYPE|LGA17_5X4|DESCRIPTION|IC OTHER(27P)MP86950GLV~
T-Z(LGA)|MANUFTR|MPS|MANUF_PN|MP86950GLVT-Z|RD_CMPLS_LVL|EP(V1)|CMPLS_LVL||FROM_~
PJ|S69-CARSON|CLASS|IC|DIP_SMD||DATA|MPS_MP86950GLVT-Z.pdf|EE_CHECK_LIST||FP_ECN~
||PSL||CREATOR||STATUS||MSD|Level-3|ESD_CDM|NA|ESD_HBM|NA|ESD_MM|NA|PIN_LENGTH_S~
HORT_PIN|0 MILS|PIN_LENGTH_LONG_PIN|0 MILS|CREATEDAY|20180807|VARIANT_DEVICE_TYP~
E|MP86950GLVTZ-MP86950GLVT-Z,SML';

PART_NAME
 PR2718 'Q_RES_0402LF-8.87K,1%,1/16W,EMPTY,CS28872FB01':;

SECTION_NUMBER 1
 '@T6G_MB_LIB.T6G(SCH_1):PAGE302_I325@PURE_QUANTA.Q_RES(CHIPS)':
 C_PATH='@t6g_mb_lib.t6g(sch_1):page302_i325@pure_quanta.q_res(chips)';

PART_NAME
 PR1785 'Q_RES_0402LF-0,5%,1/16W,CHIP,CS00002JB38':;

SECTION_NUMBER 1
 '@T6G_MB_LIB.T6G(SCH_1):PAGE302_I342@PURE_QUANTA.Q_RES(CHIPS)':
 C_PATH='@t6g_mb_lib.t6g(sch_1):page302_i342@pure_quanta.q_res(chips)',
 CDSVAR_REPCELL_MPS='pure_quanta|Q_res',
 VAR_0_MPS='VALUE|0|TOLERANCE|5%|WATTAGE|1/16W|PACK_TYPE|0402LF|MATERIAL|EMPTY|P~
ART_NUMBER|CS00002JB38|STANDARD|End of Design|LIFECYCLE|Comp-Approve|PART_NUMBER~
|CS00002JB38|JEDEC_TYPE|R0402|ALT_SYMBOLS|(R0402-0201)|VALUE|0|TOL|5%|WATTAGE|1/~
16W|CLASS|IO|DESCRIPTION|RESISTOR CHIP 0 1/16W +-5%(0402)|COMPONENT_TYPE|CHIP040~
2|LEAD_LENGTH||DFM_EXCLUSION||DAY|20100618|VARIANT_DEVICE_TYPE|Q_RES-0,5%,1/16W,~
0402LF,EMPTY,';

PART_NAME
 PR1784 'Q_RES_0402LF-4.7,1%,1/16W,CHIP,CS-4702FB19':;

SECTION_NUMBER 1
 '@T6G_MB_LIB.T6G(SCH_1):PAGE302_I341@PURE_QUANTA.Q_RES(CHIPS)':
 C_PATH='@t6g_mb_lib.t6g(sch_1):page302_i341@pure_quanta.q_res(chips)',
 CDSVAR_REPCELL_MPS='pure_quanta|Q_res',
 VAR_0_MPS='VALUE|0|TOLERANCE|5%|WATTAGE|1/16W|PACK_TYPE|0402LF|MATERIAL|CHIP|PA~
RT_NUMBER|CS00002JB38|STANDARD|End of Design|LIFECYCLE|Comp-Approve|PART_NUMBER|~
CS00002JB38|JEDEC_TYPE|R0402|ALT_SYMBOLS|(R0402-0201)|VALUE|0|TOL|5%|WATTAGE|1/1~
6W|CLASS|DISCRETE|DESCRIPTION|RESISTOR CHIP 0 1/16W +-5%(0402)|COMPONENT_TYPE|CH~
IP0402|LEAD_LENGTH||DFM_EXCLUSION||DAY|20100618|VARIANT_DEVICE_TYPE|Q_RES-0,5%,1~
/16W,0402LF,CHIP,C';

PART_NAME
 PR636 'Q_RES_0402LF-0,5%,1/16W,EMPTY,CS00002JB38':;

SECTION_NUMBER 1
 '@T6G_MB_LIB.T6G(SCH_1):PAGE302_I337@PURE_QUANTA.Q_RES(CHIPS)':
 C_PATH='@t6g_mb_lib.t6g(sch_1):page302_i337@pure_quanta.q_res(chips)',
 CDSVAR_REPCELL_MPS='pure_quanta|Q_res',
 VAR_0_MPS='VALUE|0|TOLERANCE|5%|WATTAGE|1/16W|PACK_TYPE|0402LF|MATERIAL|CHIP|PA~
RT_NUMBER|CS00002JB38|STANDARD|End of Design|LIFECYCLE|Comp-Approve|PART_NUMBER|~
CS00002JB38|JEDEC_TYPE|R0402|ALT_SYMBOLS|(R0402-0201)|VALUE|0|TOL|5%|WATTAGE|1/1~
6W|CLASS|DISCRETE|DESCRIPTION|RESISTOR CHIP 0 1/16W +-5%(0402)|COMPONENT_TYPE|CH~
IP0402|LEAD_LENGTH||DFM_EXCLUSION||DAY|20100618|VARIANT_DEVICE_TYPE|Q_RES-0,5%,1~
/16W,0402LF,CHIP,C';

PART_NAME
 PR635 'Q_RES_0402LF-0,5%,1/16W,CHIP,CS00002JB38':;

SECTION_NUMBER 1
 '@T6G_MB_LIB.T6G(SCH_1):PAGE302_I335@PURE_QUANTA.Q_RES(CHIPS)':
 C_PATH='@t6g_mb_lib.t6g(sch_1):page302_i335@pure_quanta.q_res(chips)',
 CDSVAR_REPCELL_MPS='pure_quanta|Q_res',
 VAR_0_MPS='VALUE|0|TOLERANCE|5%|WATTAGE|1/16W|PACK_TYPE|0402LF|MATERIAL|EMPTY|P~
ART_NUMBER|CS00002JB38|STANDARD|End of Design|LIFECYCLE|Comp-Approve|PART_NUMBER~
|CS00002JB38|JEDEC_TYPE|R0402|ALT_SYMBOLS|(R0402-0201)|VALUE|0|TOL|5%|WATTAGE|1/~
16W|CLASS|IO|DESCRIPTION|RESISTOR CHIP 0 1/16W +-5%(0402)|COMPONENT_TYPE|CHIP040~
2|LEAD_LENGTH||DFM_EXCLUSION||DAY|20100618|VARIANT_DEVICE_TYPE|Q_RES-0,5%,1/16W,~
0402LF,EMPTY,';

PART_NAME
 PR380 'Q_RES_0402LF-2.2,1%,1/16W,CHIP,CS-2202FB00':;

SECTION_NUMBER 1
 '@T6G_MB_LIB.T6G(SCH_1):PAGE302_I336@PURE_QUANTA.Q_RES(CHIPS)':
 C_PATH='@t6g_mb_lib.t6g(sch_1):page302_i336@pure_quanta.q_res(chips)';

PART_NAME
 PL35 'Q_INDUCTOR_SMLF-120NH/94A,IND,CV+12^0KZ16':;

SECTION_NUMBER 1
 '@T6G_MB_LIB.T6G(SCH_1):PAGE302_I345@PURE_QUANTA.Q_INDUCTOR(CHIPS)':
 C_PATH='@t6g_mb_lib.t6g(sch_1):page302_i345@pure_quanta.q_inductor(chips)';

PART_NAME
 PC1910 'Q_CAPP_SMLF-330UF,2V,35%,SPCAP,CH733RY8807':;

SECTION_NUMBER 1
 '@T6G_MB_LIB.T6G(SCH_1):PAGE302_I348@PURE_QUANTA.Q_CAPP(CHIPS)':
 C_PATH='@t6g_mb_lib.t6g(sch_1):page302_i348@pure_quanta.q_capp(chips)';

PART_NAME
 PC1645 'Q_CAPP_THLF-560UF,2.5V,20%,OSCON,CC7560JMD18':;

SECTION_NUMBER 1
 '@T6G_MB_LIB.T6G(SCH_1):PAGE302_I350@PURE_QUANTA.Q_CAPP(CHIPS)':
 C_PATH='@t6g_mb_lib.t6g(sch_1):page302_i350@pure_quanta.q_capp(chips)';

PART_NAME
 PC1644 'Q_CAPP_THLF-560UF,2.5V,20%,OSCON,CC7560JMD18':;

SECTION_NUMBER 1
 '@T6G_MB_LIB.T6G(SCH_1):PAGE302_I349@PURE_QUANTA.Q_CAPP(CHIPS)':
 C_PATH='@t6g_mb_lib.t6g(sch_1):page302_i349@pure_quanta.q_capp(chips)';

PART_NAME
 PC1354 'Q_CAP_0402-0.1UF,25V,10%,X7R,CH4104K1B00':;

SECTION_NUMBER 1
 '@T6G_MB_LIB.T6G(SCH_1):PAGE302_I330@PURE_QUANTA.Q_CAP(CHIPS)':
 C_PATH='@t6g_mb_lib.t6g(sch_1):page302_i330@pure_quanta.q_cap(chips)',
 CDSVAR_REPCELL_MPS='pure_quanta|Q_cap',
 VAR_0_MPS='VALUE|0.1UF|VOLTAGE|25V|TOLERANCE|10%|PACK_TYPE|0402|MATERIAL|EMPTY|~
PART_NUMBER|CH4104K1B00|STANDARD||LIFECYCLE||ASS_PART||PART_NUMBER|CH4104K1B00|J~
EDEC_TYPE|C0402|ALT_SYMBOLS|(C0402_OCTAGONXA,C0402-0201)|VALUE|NA|RATED_VOLTAGE|~
25V|TOL|10%|CLASS|IO|DESCRIPTION|CAP CHIP 0.1U 25V(+-10%,X7R,0402)|COMPONENT_TYP~
E|CHIP0402|LEAD_LENGTH||LPID||DATE|20160113|VARIANT_DEVICE_TYPE|Q_CAP-0.1UF,25V,~
10%,0402,EMPTY';

PART_NAME
 PC642 'Q_CAP_0805-22UF,4V,20%,X6S,TMP_QCH622KMEA01':;

SECTION_NUMBER 1
 '@T6G_MB_LIB.T6G(SCH_1):PAGE302_I353@PURE_QUANTA.Q_CAP(CHIPS)':
 C_PATH='@t6g_mb_lib.t6g(sch_1):page302_i353@pure_quanta.q_cap(chips)';

PART_NAME
 PC641 'Q_CAP_0805-22UF,4V,20%,X6S,TMP_QCH622KMEA01':;

SECTION_NUMBER 1
 '@T6G_MB_LIB.T6G(SCH_1):PAGE302_I352@PURE_QUANTA.Q_CAP(CHIPS)':
 C_PATH='@t6g_mb_lib.t6g(sch_1):page302_i352@pure_quanta.q_cap(chips)';

PART_NAME
 PC639 'Q_CAP_C0402-100NF,50V,10%,X7R,CH4106K1B01':;

SECTION_NUMBER 1
 '@T6G_MB_LIB.T6G(SCH_1):PAGE302_I346@PURE_QUANTA.Q_CAP(CHIPS)':
 C_PATH='@t6g_mb_lib.t6g(sch_1):page302_i346@pure_quanta.q_cap(chips)';

PART_NAME
 PC638 'Q_CAP_C0805-22UF,16V,20%,X6S,CH6223MEA00':;

SECTION_NUMBER 1
 '@T6G_MB_LIB.T6G(SCH_1):PAGE302_I359@PURE_QUANTA.Q_CAP(CHIPS)':
 C_PATH='@t6g_mb_lib.t6g(sch_1):page302_i359@pure_quanta.q_cap(chips)';

PART_NAME
 PC637 'Q_CAP_C0805-22UF,16V,20%,X6S,CH6223MEA00':;

SECTION_NUMBER 1
 '@T6G_MB_LIB.T6G(SCH_1):PAGE302_I358@PURE_QUANTA.Q_CAP(CHIPS)':
 C_PATH='@t6g_mb_lib.t6g(sch_1):page302_i358@pure_quanta.q_cap(chips)';

PART_NAME
 PC636 'Q_CAP_C0402-100NF,50V,10%,X7R,CH4106K1B01':;

SECTION_NUMBER 1
 '@T6G_MB_LIB.T6G(SCH_1):PAGE302_I344@PURE_QUANTA.Q_CAP(CHIPS)':
 C_PATH='@t6g_mb_lib.t6g(sch_1):page302_i344@pure_quanta.q_cap(chips)';

PART_NAME
 PC635 'Q_CAP_C0402-1UF,16V,10%,X6S,CH5103KEB01':;

SECTION_NUMBER 1
 '@T6G_MB_LIB.T6G(SCH_1):PAGE302_I357@PURE_QUANTA.Q_CAP(CHIPS)':
 C_PATH='@t6g_mb_lib.t6g(sch_1):page302_i357@pure_quanta.q_cap(chips)';

PART_NAME
 PC634 'Q_CAP_0402-3300PF,50V,10%,X7R,TMP_QCH2336K1B12':;

SECTION_NUMBER 1
 '@T6G_MB_LIB.T6G(SCH_1):PAGE302_I340@PURE_QUANTA.Q_CAP(CHIPS)':
 C_PATH='@t6g_mb_lib.t6g(sch_1):page302_i340@pure_quanta.q_cap(chips)';

PART_NAME
 PC633 'Q_CAP_C0402-2.2UF,10V,10%,X6S,CH5222KEB01':;

SECTION_NUMBER 1
 '@T6G_MB_LIB.T6G(SCH_1):PAGE302_I332@PURE_QUANTA.Q_CAP(CHIPS)':
 C_PATH='@t6g_mb_lib.t6g(sch_1):page302_i332@pure_quanta.q_cap(chips)';

PART_NAME
 PU70_P0_2 'ISL99390FRZTR5935-ISL99390FRZ-TR5935,SMLF,IC,AL099390004':;

SECTION_NUMBER 1
 '@T6G_MB_LIB.T6G(SCH_1):PAGE294_I30@PURE_QUANTA.ISL99390FRZTR5935(CHIPS)':
 C_PATH='@s6q_mb_lib.s6q(sch_1):page294_i30@pure_quanta.isl99390frztr5935(chips)~
';

PART_NAME
 PU69_P0_1 'ISL99390FRZTR5935-ISL99390FRZ-TR5935,SMLF,IC,AL099390004':;

SECTION_NUMBER 1
 '@T6G_MB_LIB.T6G(SCH_1):PAGE294_I35@PURE_QUANTA.ISL99390FRZTR5935(CHIPS)':
 C_PATH='@s6q_mb_lib.s6q(sch_1):page294_i35@pure_quanta.isl99390frztr5935(chips)~
';

PART_NAME
 PR1781 'Q_RES_0402LF-3.3,1%,1/16W,CHIP,CS-3302FB00':;

SECTION_NUMBER 1
 '@T6G_MB_LIB.T6G(SCH_1):PAGE294_I40@PURE_QUANTA.Q_RES(CHIPS)':
 C_PATH='@t6g_mb_lib.t6g(sch_1):page294_i40@pure_quanta.q_res(chips)',
 CDSVAR_REPCELL_MPS='pure_quanta|Q_res',
 VAR_0_MPS='VALUE|0|TOLERANCE|5%|WATTAGE|1/16W|PACK_TYPE|0402LF|MATERIAL|CHIP|PA~
RT_NUMBER|CS00002JB38|STANDARD|End of Design|LIFECYCLE|Comp-Approve|PART_NUMBER|~
CS00002JB38|JEDEC_TYPE|R0402|ALT_SYMBOLS|(R0402-0201)|VALUE|0|TOL|5%|WATTAGE|1/1~
6W|CLASS|DISCRETE|DESCRIPTION|RESISTOR CHIP 0 1/16W +-5%(0402)|COMPONENT_TYPE|CH~
IP0402|LEAD_LENGTH||DFM_EXCLUSION||DAY|20100618|VARIANT_DEVICE_TYPE|Q_RES-0,5%,1~
/16W,0402LF,CHIP,C';

PART_NAME
 PR1780 'Q_RES_0402LF-3.3,1%,1/16W,CHIP,CS-3302FB00':;

SECTION_NUMBER 1
 '@T6G_MB_LIB.T6G(SCH_1):PAGE294_I51@PURE_QUANTA.Q_RES(CHIPS)':
 C_PATH='@t6g_mb_lib.t6g(sch_1):page294_i51@pure_quanta.q_res(chips)',
 CDSVAR_REPCELL_MPS='pure_quanta|Q_res',
 VAR_0_MPS='VALUE|0|TOLERANCE|5%|WATTAGE|1/16W|PACK_TYPE|0402LF|MATERIAL|CHIP|PA~
RT_NUMBER|CS00002JB38|STANDARD|End of Design|LIFECYCLE|Comp-Approve|PART_NUMBER|~
CS00002JB38|JEDEC_TYPE|R0402|ALT_SYMBOLS|(R0402-0201)|VALUE|0|TOL|5%|WATTAGE|1/1~
6W|CLASS|DISCRETE|DESCRIPTION|RESISTOR CHIP 0 1/16W +-5%(0402)|COMPONENT_TYPE|CH~
IP0402|LEAD_LENGTH||DFM_EXCLUSION||DAY|20100618|VARIANT_DEVICE_TYPE|Q_RES-0,5%,1~
/16W,0402LF,CHIP,C';

PART_NAME
 PR1323 'Q_RES_0402LF-0,5%,1/16W,CHIP,CS00002JB38':;

SECTION_NUMBER 1
 '@T6G_MB_LIB.T6G(SCH_1):PAGE294_I36@PURE_QUANTA.Q_RES(CHIPS)':
 C_PATH='@t6g_mb_lib.t6g(sch_1):page294_i36@pure_quanta.q_res(chips)',
 CDSVAR_REPCELL_MPS='pure_quanta|Q_res',
 VAR_0_MPS='VALUE|0|TOLERANCE|5%|WATTAGE|1/16W|PACK_TYPE|0402LF|MATERIAL|EMPTY|P~
ART_NUMBER|CS00002JB38|STANDARD|End of Design|LIFECYCLE|Comp-Approve|PART_NUMBER~
|CS00002JB38|JEDEC_TYPE|R0402|ALT_SYMBOLS|(R0402-0201)|VALUE|0|TOL|5%|WATTAGE|1/~
16W|CLASS|IO|DESCRIPTION|RESISTOR CHIP 0 1/16W +-5%(0402)|COMPONENT_TYPE|CHIP040~
2|LEAD_LENGTH||DFM_EXCLUSION||DAY|20100618|VARIANT_DEVICE_TYPE|Q_RES-0,5%,1/16W,~
0402LF,EMPTY,';

PART_NAME
 PR1322 'Q_RES_0402LF-0,5%,1/16W,CHIP,CS00002JB38':;

SECTION_NUMBER 1
 '@T6G_MB_LIB.T6G(SCH_1):PAGE294_I53@PURE_QUANTA.Q_RES(CHIPS)':
 C_PATH='@t6g_mb_lib.t6g(sch_1):page294_i53@pure_quanta.q_res(chips)',
 CDSVAR_REPCELL_MPS='pure_quanta|Q_res',
 VAR_0_MPS='VALUE|0|TOLERANCE|5%|WATTAGE|1/16W|PACK_TYPE|0402LF|MATERIAL|EMPTY|P~
ART_NUMBER|CS00002JB38|STANDARD|End of Design|LIFECYCLE|Comp-Approve|PART_NUMBER~
|CS00002JB38|JEDEC_TYPE|R0402|ALT_SYMBOLS|(R0402-0201)|VALUE|0|TOL|5%|WATTAGE|1/~
16W|CLASS|IO|DESCRIPTION|RESISTOR CHIP 0 1/16W +-5%(0402)|COMPONENT_TYPE|CHIP040~
2|LEAD_LENGTH||DFM_EXCLUSION||DAY|20100618|VARIANT_DEVICE_TYPE|Q_RES-0,5%,1/16W,~
0402LF,EMPTY,';

PART_NAME
 PR633 'Q_RES_0402LF-0,5%,1/16W,EMPTY,CS00002JB38':;

SECTION_NUMBER 1
 '@T6G_MB_LIB.T6G(SCH_1):PAGE294_I14@PURE_QUANTA.Q_RES(CHIPS)':
 C_PATH='@t6g_mb_lib.t6g(sch_1):page294_i14@pure_quanta.q_res(chips)',
 CDSVAR_REPCELL_MPS='pure_quanta|Q_res',
 VAR_0_MPS='VALUE|0|TOLERANCE|5%|WATTAGE|1/16W|PACK_TYPE|0402LF|MATERIAL|CHIP|PA~
RT_NUMBER|CS00002JB38|STANDARD|End of Design|LIFECYCLE|Comp-Approve|PART_NUMBER|~
CS00002JB38|JEDEC_TYPE|R0402|ALT_SYMBOLS|(R0402-0201)|VALUE|0|TOL|5%|WATTAGE|1/1~
6W|CLASS|DISCRETE|DESCRIPTION|RESISTOR CHIP 0 1/16W +-5%(0402)|COMPONENT_TYPE|CH~
IP0402|LEAD_LENGTH||DFM_EXCLUSION||DAY|20100618|VARIANT_DEVICE_TYPE|Q_RES-0,5%,1~
/16W,0402LF,CHIP,C';

PART_NAME
 PR632 'Q_RES_0402LF-0,5%,1/16W,EMPTY,CS00002JB38':;

SECTION_NUMBER 1
 '@T6G_MB_LIB.T6G(SCH_1):PAGE294_I26@PURE_QUANTA.Q_RES(CHIPS)':
 C_PATH='@t6g_mb_lib.t6g(sch_1):page294_i26@pure_quanta.q_res(chips)',
 CDSVAR_REPCELL_MPS='pure_quanta|Q_res',
 VAR_0_MPS='VALUE|0|TOLERANCE|5%|WATTAGE|1/16W|PACK_TYPE|0402LF|MATERIAL|CHIP|PA~
RT_NUMBER|CS00002JB38|STANDARD|End of Design|LIFECYCLE|Comp-Approve|PART_NUMBER|~
CS00002JB38|JEDEC_TYPE|R0402|ALT_SYMBOLS|(R0402-0201)|VALUE|0|TOL|5%|WATTAGE|1/1~
6W|CLASS|DISCRETE|DESCRIPTION|RESISTOR CHIP 0 1/16W +-5%(0402)|COMPONENT_TYPE|CH~
IP0402|LEAD_LENGTH||DFM_EXCLUSION||DAY|20100618|VARIANT_DEVICE_TYPE|Q_RES-0,5%,1~
/16W,0402LF,CHIP,C';

PART_NAME
 PR447 'Q_RES_0402LF-0,5%,1/16W,CHIP,CS00002JB38':;

SECTION_NUMBER 1
 '@T6G_MB_LIB.T6G(SCH_1):PAGE294_I11@PURE_QUANTA.Q_RES(CHIPS)':
 C_PATH='@t6g_mb_lib.t6g(sch_1):page294_i11@pure_quanta.q_res(chips)',
 CDSVAR_REPCELL_MPS='pure_quanta|Q_res',
 VAR_0_MPS='VALUE|0|TOLERANCE|5%|WATTAGE|1/16W|PACK_TYPE|0402LF|MATERIAL|EMPTY|P~
ART_NUMBER|CS00002JB38|STANDARD|End of Design|LIFECYCLE|Comp-Approve|PART_NUMBER~
|CS00002JB38|JEDEC_TYPE|R0402|ALT_SYMBOLS|(R0402-0201)|VALUE|0|TOL|5%|WATTAGE|1/~
16W|CLASS|IO|DESCRIPTION|RESISTOR CHIP 0 1/16W +-5%(0402)|COMPONENT_TYPE|CHIP040~
2|LEAD_LENGTH||DFM_EXCLUSION||DAY|20100618|VARIANT_DEVICE_TYPE|Q_RES-0,5%,1/16W,~
0402LF,EMPTY,';

PART_NAME
 PR444 'Q_RES_0402LF-0,5%,1/16W,CHIP,CS00002JB38':;

SECTION_NUMBER 1
 '@T6G_MB_LIB.T6G(SCH_1):PAGE294_I24@PURE_QUANTA.Q_RES(CHIPS)':
 C_PATH='@t6g_mb_lib.t6g(sch_1):page294_i24@pure_quanta.q_res(chips)',
 CDSVAR_REPCELL_MPS='pure_quanta|Q_res',
 VAR_0_MPS='VALUE|0|TOLERANCE|5%|WATTAGE|1/16W|PACK_TYPE|0402LF|MATERIAL|EMPTY|P~
ART_NUMBER|CS00002JB38|STANDARD|End of Design|LIFECYCLE|Comp-Approve|PART_NUMBER~
|CS00002JB38|JEDEC_TYPE|R0402|ALT_SYMBOLS|(R0402-0201)|VALUE|0|TOL|5%|WATTAGE|1/~
16W|CLASS|IO|DESCRIPTION|RESISTOR CHIP 0 1/16W +-5%(0402)|COMPONENT_TYPE|CHIP040~
2|LEAD_LENGTH||DFM_EXCLUSION||DAY|20100618|VARIANT_DEVICE_TYPE|Q_RES-0,5%,1/16W,~
0402LF,EMPTY,';

PART_NAME
 PR356 'Q_RES_0402LF-2.2,1%,1/16W,CHIP,CS-2202FB00':;

SECTION_NUMBER 1
 '@T6G_MB_LIB.T6G(SCH_1):PAGE294_I10@PURE_QUANTA.Q_RES(CHIPS)':
 C_PATH='@t6g_mb_lib.t6g(sch_1):page294_i10@pure_quanta.q_res(chips)';

PART_NAME
 PR355 'Q_RES_0402LF-2.2,1%,1/16W,CHIP,CS-2202FB00':;

SECTION_NUMBER 1
 '@T6G_MB_LIB.T6G(SCH_1):PAGE294_I25@PURE_QUANTA.Q_RES(CHIPS)':
 C_PATH='@t6g_mb_lib.t6g(sch_1):page294_i25@pure_quanta.q_res(chips)';

PART_NAME
 PR354 'Q_RES_0402LF-8.87K,1%,1/16W,EMPTY,CS28872FB01':;

SECTION_NUMBER 1
 '@T6G_MB_LIB.T6G(SCH_1):PAGE294_I17@PURE_QUANTA.Q_RES(CHIPS)':
 C_PATH='@t6g_mb_lib.t6g(sch_1):page294_i17@pure_quanta.q_res(chips)';

PART_NAME
 PR353 'Q_RES_0402LF-8.87K,1%,1/16W,EMPTY,CS28872FB01':;

SECTION_NUMBER 1
 '@T6G_MB_LIB.T6G(SCH_1):PAGE294_I2@PURE_QUANTA.Q_RES(CHIPS)':
 C_PATH='@t6g_mb_lib.t6g(sch_1):page294_i2@pure_quanta.q_res(chips)';

PART_NAME
 PL44 'Q_INDUCTOR_SMLF-100NH/16A,IND,CV+10G0MZ04':;

SECTION_NUMBER 1
 '@T6G_MB_LIB.T6G(SCH_1):PAGE294_I74@PURE_QUANTA.Q_INDUCTOR(CHIPS)':
 C_PATH='@t6g_mb_lib.t6g(sch_1):page294_i74@pure_quanta.q_inductor(chips)';

PART_NAME
 PL34 'Q_INDUCTOR_SMLF-130NH/106A,IND,CV+13^0KZ11':;

SECTION_NUMBER 1
 '@T6G_MB_LIB.T6G(SCH_1):PAGE294_I82@PURE_QUANTA.Q_INDUCTOR(CHIPS)':
 C_PATH='@t6g_mb_lib.t6g(sch_1):page294_i82@pure_quanta.q_inductor(chips)';

PART_NAME
 PL33 'Q_INDUCTOR_SMLF-130NH/106A,IND,CV+13^0KZ11':;

SECTION_NUMBER 1
 '@T6G_MB_LIB.T6G(SCH_1):PAGE294_I81@PURE_QUANTA.Q_INDUCTOR(CHIPS)':
 C_PATH='@t6g_mb_lib.t6g(sch_1):page294_i81@pure_quanta.q_inductor(chips)';

PART_NAME
 PC2645 'Q_CAPP_SMLF-470UF,2.5V,20%,EMPTY,CH747LM8816':;

SECTION_NUMBER 1
 '@T6G_MB_LIB.T6G(SCH_1):PAGE294_I68@PURE_QUANTA.Q_CAPP(CHIPS)':
 C_PATH='@t6g_mb_lib.t6g(sch_1):page294_i68@pure_quanta.q_capp(chips)';

PART_NAME
 PC1350 'Q_CAP_0402-0.1UF,25V,10%,X7R,CH4104K1B00':;

SECTION_NUMBER 1
 '@T6G_MB_LIB.T6G(SCH_1):PAGE294_I29@PURE_QUANTA.Q_CAP(CHIPS)':
 C_PATH='@t6g_mb_lib.t6g(sch_1):page294_i29@pure_quanta.q_cap(chips)',
 CDSVAR_REPCELL_MPS='pure_quanta|Q_cap',
 VAR_0_MPS='VALUE|0.1UF|VOLTAGE|25V|TOLERANCE|10%|PACK_TYPE|0402|MATERIAL|EMPTY|~
PART_NUMBER|CH4104K1B00|STANDARD||LIFECYCLE||ASS_PART||PART_NUMBER|CH4104K1B00|J~
EDEC_TYPE|C0402|ALT_SYMBOLS|(C0402_OCTAGONXA,C0402-0201)|VALUE|NA|RATED_VOLTAGE|~
25V|TOL|10%|CLASS|IO|DESCRIPTION|CAP CHIP 0.1U 25V(+-10%,X7R,0402)|COMPONENT_TYP~
E|CHIP0402|LEAD_LENGTH||LPID||DATE|20160113|VARIANT_DEVICE_TYPE|Q_CAP-0.1UF,25V,~
10%,0402,EMPTY';

PART_NAME
 PC1349 'Q_CAP_0402-0.1UF,25V,10%,X7R,CH4104K1B00':;

SECTION_NUMBER 1
 '@T6G_MB_LIB.T6G(SCH_1):PAGE294_I46@PURE_QUANTA.Q_CAP(CHIPS)':
 C_PATH='@t6g_mb_lib.t6g(sch_1):page294_i46@pure_quanta.q_cap(chips)',
 CDSVAR_REPCELL_MPS='pure_quanta|Q_cap',
 VAR_0_MPS='VALUE|0.1UF|VOLTAGE|25V|TOLERANCE|10%|PACK_TYPE|0402|MATERIAL|EMPTY|~
PART_NUMBER|CH4104K1B00|STANDARD||LIFECYCLE||ASS_PART||PART_NUMBER|CH4104K1B00|J~
EDEC_TYPE|C0402|ALT_SYMBOLS|(C0402_OCTAGONXA,C0402-0201)|VALUE|NA|RATED_VOLTAGE|~
25V|TOL|10%|CLASS|IO|DESCRIPTION|CAP CHIP 0.1U 25V(+-10%,X7R,0402)|COMPONENT_TYP~
E|CHIP0402|LEAD_LENGTH||LPID||DATE|20160113|VARIANT_DEVICE_TYPE|Q_CAP-0.1UF,25V,~
10%,0402,EMPTY';

PART_NAME
 PC1212_P0_2 'Q_CAP_C0402-2.2UF,10V,10%,X6S,CH5222KEB01':;

SECTION_NUMBER 1
 '@T6G_MB_LIB.T6G(SCH_1):PAGE294_I33@PURE_QUANTA.Q_CAP(CHIPS)':
 C_PATH='@t6g_mb_lib.t6g(sch_1):page294_i33@pure_quanta.q_cap(chips)';

PART_NAME
 PC1211_P0_1 'Q_CAP_C0402-2.2UF,10V,10%,X6S,CH5222KEB01':;

SECTION_NUMBER 1
 '@T6G_MB_LIB.T6G(SCH_1):PAGE294_I48@PURE_QUANTA.Q_CAP(CHIPS)':
 C_PATH='@t6g_mb_lib.t6g(sch_1):page294_i48@pure_quanta.q_cap(chips)';

PART_NAME
 PC623 'Q_CAPP_SMLF-470UF,2.5V,20%,POSCAP,CH747LM8816':;

SECTION_NUMBER 1
 '@T6G_MB_LIB.T6G(SCH_1):PAGE294_I66@PURE_QUANTA.Q_CAPP(CHIPS)':
 C_PATH='@t6g_mb_lib.t6g(sch_1):page294_i66@pure_quanta.q_capp(chips)';

PART_NAME
 PC622 'Q_CAPP_THLF-270UF,16V,20%,OSCON,CC72703MD33':;

SECTION_NUMBER 1
 '@T6G_MB_LIB.T6G(SCH_1):PAGE294_I77@PURE_QUANTA.Q_CAPP(CHIPS)':
 C_PATH='@t6g_mb_lib.t6g(sch_1):page294_i77@pure_quanta.q_capp(chips)';

PART_NAME
 PC621 'Q_CAPP_THLF-560UF,2.5V,20%,OSCON,CC7560JMD18':;

SECTION_NUMBER 1
 '@T6G_MB_LIB.T6G(SCH_1):PAGE294_I65@PURE_QUANTA.Q_CAPP(CHIPS)':
 C_PATH='@t6g_mb_lib.t6g(sch_1):page294_i65@pure_quanta.q_capp(chips)';

PART_NAME
 PC620 'Q_CAPP_THLF-560UF,2.5V,20%,OSCON,CC7560JMD18':;

SECTION_NUMBER 1
 '@T6G_MB_LIB.T6G(SCH_1):PAGE294_I63@PURE_QUANTA.Q_CAPP(CHIPS)':
 C_PATH='@t6g_mb_lib.t6g(sch_1):page294_i63@pure_quanta.q_capp(chips)';

PART_NAME
 PC619 'Q_CAPP_THLF-560UF,2.5V,20%,OSCON,CC7560JMD18':;

SECTION_NUMBER 1
 '@T6G_MB_LIB.T6G(SCH_1):PAGE294_I62@PURE_QUANTA.Q_CAPP(CHIPS)':
 C_PATH='@t6g_mb_lib.t6g(sch_1):page294_i62@pure_quanta.q_capp(chips)';

PART_NAME
 PC618_P0_2 'Q_CAP_0805-22UF,4V,20%,X6S,TMP_QCH622KMEA01':;

SECTION_NUMBER 1
 '@T6G_MB_LIB.T6G(SCH_1):PAGE294_I61@PURE_QUANTA.Q_CAP(CHIPS)':
 C_PATH='@t6g_mb_lib.t6g(sch_1):page294_i61@pure_quanta.q_cap(chips)';

PART_NAME
 PC617_P0_1 'Q_CAP_0805-22UF,4V,20%,X6S,TMP_QCH622KMEA01':;

SECTION_NUMBER 1
 '@T6G_MB_LIB.T6G(SCH_1):PAGE294_I73@PURE_QUANTA.Q_CAP(CHIPS)':
 C_PATH='@t6g_mb_lib.t6g(sch_1):page294_i73@pure_quanta.q_cap(chips)';

PART_NAME
 PC616_P0_2 'Q_CAP_0805-22UF,4V,20%,X6S,TMP_QCH622KMEA01':;

SECTION_NUMBER 1
 '@T6G_MB_LIB.T6G(SCH_1):PAGE294_I60@PURE_QUANTA.Q_CAP(CHIPS)':
 C_PATH='@t6g_mb_lib.t6g(sch_1):page294_i60@pure_quanta.q_cap(chips)';

PART_NAME
 PC615_P0_1 'Q_CAP_0805-22UF,4V,20%,X6S,TMP_QCH622KMEA01':;

SECTION_NUMBER 1
 '@T6G_MB_LIB.T6G(SCH_1):PAGE294_I72@PURE_QUANTA.Q_CAP(CHIPS)':
 C_PATH='@t6g_mb_lib.t6g(sch_1):page294_i72@pure_quanta.q_cap(chips)';

PART_NAME
 PC613_P0_2 'Q_CAP_C0402-1UF,16V,10%,X6S,CH5103KEB01':;

SECTION_NUMBER 1
 '@T6G_MB_LIB.T6G(SCH_1):PAGE294_I59@PURE_QUANTA.Q_CAP(CHIPS)':
 C_PATH='@t6g_mb_lib.t6g(sch_1):page294_i59@pure_quanta.q_cap(chips)';

PART_NAME
 PC612_P0_1 'Q_CAP_C0402-100NF,50V,10%,X7R,CH4106K1B01':;

SECTION_NUMBER 1
 '@T6G_MB_LIB.T6G(SCH_1):PAGE294_I70@PURE_QUANTA.Q_CAP(CHIPS)':
 C_PATH='@t6g_mb_lib.t6g(sch_1):page294_i70@pure_quanta.q_cap(chips)';

PART_NAME
 PC611_P0_2 'Q_CAP_C0805-22UF,16V,20%,X6S,CH6223MEA00':;

SECTION_NUMBER 1
 '@T6G_MB_LIB.T6G(SCH_1):PAGE294_I42@PURE_QUANTA.Q_CAP(CHIPS)':
 C_PATH='@t6g_mb_lib.t6g(sch_1):page294_i42@pure_quanta.q_cap(chips)';

PART_NAME
 PC610_P0_1 'Q_CAP_C0805-22UF,16V,20%,X6S,CH6223MEA00':;

SECTION_NUMBER 1
 '@T6G_MB_LIB.T6G(SCH_1):PAGE294_I56@PURE_QUANTA.Q_CAP(CHIPS)':
 C_PATH='@t6g_mb_lib.t6g(sch_1):page294_i56@pure_quanta.q_cap(chips)';

PART_NAME
 PC609_P0_2 'Q_CAP_C0805-22UF,16V,20%,X6S,CH6223MEA00':;

SECTION_NUMBER 1
 '@T6G_MB_LIB.T6G(SCH_1):PAGE294_I41@PURE_QUANTA.Q_CAP(CHIPS)':
 C_PATH='@t6g_mb_lib.t6g(sch_1):page294_i41@pure_quanta.q_cap(chips)';

PART_NAME
 PC608_P0_1 'Q_CAP_C0805-22UF,16V,20%,X6S,CH6223MEA00':;

SECTION_NUMBER 1
 '@T6G_MB_LIB.T6G(SCH_1):PAGE294_I52@PURE_QUANTA.Q_CAP(CHIPS)':
 C_PATH='@t6g_mb_lib.t6g(sch_1):page294_i52@pure_quanta.q_cap(chips)';

PART_NAME
 PC607 'Q_CAP_C0402-100NF,50V,10%,X7R,CH4106K1B01':;

SECTION_NUMBER 1
 '@T6G_MB_LIB.T6G(SCH_1):PAGE294_I43@PURE_QUANTA.Q_CAP(CHIPS)':
 C_PATH='@t6g_mb_lib.t6g(sch_1):page294_i43@pure_quanta.q_cap(chips)';

PART_NAME
 PC606 'Q_CAP_C0402-100NF,50V,10%,X7R,CH4106K1B01':;

SECTION_NUMBER 1
 '@T6G_MB_LIB.T6G(SCH_1):PAGE294_I54@PURE_QUANTA.Q_CAP(CHIPS)':
 C_PATH='@t6g_mb_lib.t6g(sch_1):page294_i54@pure_quanta.q_cap(chips)';

PART_NAME
 PC605_P0_2 'Q_CAP_C0402-1UF,16V,10%,X6S,CH5103KEB01':;

SECTION_NUMBER 1
 '@T6G_MB_LIB.T6G(SCH_1):PAGE294_I39@PURE_QUANTA.Q_CAP(CHIPS)':
 C_PATH='@t6g_mb_lib.t6g(sch_1):page294_i39@pure_quanta.q_cap(chips)';

PART_NAME
 PC604_P0_1 'Q_CAP_C0402-1UF,16V,10%,X6S,CH5103KEB01':;

SECTION_NUMBER 1
 '@T6G_MB_LIB.T6G(SCH_1):PAGE294_I50@PURE_QUANTA.Q_CAP(CHIPS)':
 C_PATH='@t6g_mb_lib.t6g(sch_1):page294_i50@pure_quanta.q_cap(chips)';

PART_NAME
 PC603_P0_2 'Q_CAP_0402-3300PF,50V,10%,X7R,TMP_QCH2336K1B12':;

SECTION_NUMBER 1
 '@T6G_MB_LIB.T6G(SCH_1):PAGE294_I38@PURE_QUANTA.Q_CAP(CHIPS)':
 C_PATH='@t6g_mb_lib.t6g(sch_1):page294_i38@pure_quanta.q_cap(chips)';

PART_NAME
 PC602_P0_1 'Q_CAP_0402-3300PF,50V,10%,X7R,TMP_QCH2336K1B12':;

SECTION_NUMBER 1
 '@T6G_MB_LIB.T6G(SCH_1):PAGE294_I49@PURE_QUANTA.Q_CAP(CHIPS)':
 C_PATH='@t6g_mb_lib.t6g(sch_1):page294_i49@pure_quanta.q_cap(chips)';

PART_NAME
 PC601 'Q_CAP_C0402-2.2UF,10V,10%,X6S,CH5222KEB01':;

SECTION_NUMBER 1
 '@T6G_MB_LIB.T6G(SCH_1):PAGE294_I8@PURE_QUANTA.Q_CAP(CHIPS)':
 C_PATH='@t6g_mb_lib.t6g(sch_1):page294_i8@pure_quanta.q_cap(chips)';

PART_NAME
 PC600 'Q_CAP_C0402-2.2UF,10V,10%,X6S,CH5222KEB01':;

SECTION_NUMBER 1
 '@T6G_MB_LIB.T6G(SCH_1):PAGE294_I23@PURE_QUANTA.Q_CAP(CHIPS)':
 C_PATH='@t6g_mb_lib.t6g(sch_1):page294_i23@pure_quanta.q_cap(chips)';

PART_NAME
 PU28_P1_3 'ISL99390FRZTR5935-ISL99390FRZ-TR5935,SMLF,IC,AL099390004':;

SECTION_NUMBER 1
 '@T6G_MB_LIB.T6G(SCH_1):PAGE309_I18@PURE_QUANTA.ISL99390FRZTR5935(CHIPS)':
 C_PATH='@s6q_mb_lib.s6q(sch_1):page309_i18@pure_quanta.isl99390frztr5935(chips)~
';

PART_NAME
 PU27_P1_4 'ISL99390FRZTR5935-ISL99390FRZ-TR5935,SMLF,IC,AL099390004':;

SECTION_NUMBER 1
 '@T6G_MB_LIB.T6G(SCH_1):PAGE309_I9@PURE_QUANTA.ISL99390FRZTR5935(CHIPS)':
 C_PATH='@t6g_mb_lib.t6g(sch_1):page309_i9@pure_quanta.isl99390frztr5935(chips)';

PART_NAME
 PR1789 'Q_RES_0402LF-3.3,1%,1/16W,CHIP,CS-3302FB00':;

SECTION_NUMBER 1
 '@T6G_MB_LIB.T6G(SCH_1):PAGE309_I47@PURE_QUANTA.Q_RES(CHIPS)':
 C_PATH='@t6g_mb_lib.t6g(sch_1):page309_i47@pure_quanta.q_res(chips)',
 CDSVAR_REPCELL_MPS='pure_quanta|Q_res',
 VAR_0_MPS='VALUE|0|TOLERANCE|5%|WATTAGE|1/16W|PACK_TYPE|0402LF|MATERIAL|CHIP|PA~
RT_NUMBER|CS00002JB38|STANDARD|End of Design|LIFECYCLE|Comp-Approve|PART_NUMBER|~
CS00002JB38|JEDEC_TYPE|R0402|ALT_SYMBOLS|(R0402-0201)|VALUE|0|TOL|5%|WATTAGE|1/1~
6W|CLASS|DISCRETE|DESCRIPTION|RESISTOR CHIP 0 1/16W +-5%(0402)|COMPONENT_TYPE|CH~
IP0402|LEAD_LENGTH||DFM_EXCLUSION||DAY|20100618|VARIANT_DEVICE_TYPE|Q_RES-0,5%,1~
/16W,0402LF,CHIP,C';

PART_NAME
 PR1788 'Q_RES_0402LF-3.3,1%,1/16W,CHIP,CS-3302FB00':;

SECTION_NUMBER 1
 '@T6G_MB_LIB.T6G(SCH_1):PAGE309_I34@PURE_QUANTA.Q_RES(CHIPS)':
 C_PATH='@t6g_mb_lib.t6g(sch_1):page309_i34@pure_quanta.q_res(chips)',
 CDSVAR_REPCELL_MPS='pure_quanta|Q_res',
 VAR_0_MPS='VALUE|0|TOLERANCE|5%|WATTAGE|1/16W|PACK_TYPE|0402LF|MATERIAL|CHIP|PA~
RT_NUMBER|CS00002JB38|STANDARD|End of Design|LIFECYCLE|Comp-Approve|PART_NUMBER|~
CS00002JB38|JEDEC_TYPE|R0402|ALT_SYMBOLS|(R0402-0201)|VALUE|0|TOL|5%|WATTAGE|1/1~
6W|CLASS|DISCRETE|DESCRIPTION|RESISTOR CHIP 0 1/16W +-5%(0402)|COMPONENT_TYPE|CH~
IP0402|LEAD_LENGTH||DFM_EXCLUSION||DAY|20100618|VARIANT_DEVICE_TYPE|Q_RES-0,5%,1~
/16W,0402LF,CHIP,C';

PART_NAME
 PR302 'Q_RES_0402LF-0,5%,1/16W,CHIP,CS00002JB38':;

SECTION_NUMBER 1
 '@T6G_MB_LIB.T6G(SCH_1):PAGE309_I80@PURE_QUANTA.Q_RES(CHIPS)':
 C_PATH='@t6g_mb_lib.t6g(sch_1):page309_i80@pure_quanta.q_res(chips)';

PART_NAME
 PR301 'Q_RES_0402LF-0,5%,1/16W,CHIP,CS00002JB38':;

SECTION_NUMBER 1
 '@T6G_MB_LIB.T6G(SCH_1):PAGE309_I92@PURE_QUANTA.Q_RES(CHIPS)':
 C_PATH='@t6g_mb_lib.t6g(sch_1):page309_i92@pure_quanta.q_res(chips)';

PART_NAME
 PR300 'Q_RES_0402LF-2.2,1%,1/16W,CHIP,CS-2202FB00':;

SECTION_NUMBER 1
 '@T6G_MB_LIB.T6G(SCH_1):PAGE309_I27@PURE_QUANTA.Q_RES(CHIPS)':
 C_PATH='@t6g_mb_lib.t6g(sch_1):page309_i27@pure_quanta.q_res(chips)';

PART_NAME
 PR299 'Q_RES_0402LF-2.2,1%,1/16W,CHIP,CS-2202FB00':;

SECTION_NUMBER 1
 '@T6G_MB_LIB.T6G(SCH_1):PAGE309_I12@PURE_QUANTA.Q_RES(CHIPS)':
 C_PATH='@t6g_mb_lib.t6g(sch_1):page309_i12@pure_quanta.q_res(chips)';

PART_NAME
 PR298 'Q_RES_0402LF-8.87K,1%,1/16W,EMPTY,CS28872FB01':;

SECTION_NUMBER 1
 '@T6G_MB_LIB.T6G(SCH_1):PAGE309_I20@PURE_QUANTA.Q_RES(CHIPS)':
 C_PATH='@t6g_mb_lib.t6g(sch_1):page309_i20@pure_quanta.q_res(chips)';

PART_NAME
 PR297 'Q_RES_0402LF-8.87K,1%,1/16W,EMPTY,CS28872FB01':;

SECTION_NUMBER 1
 '@T6G_MB_LIB.T6G(SCH_1):PAGE309_I2@PURE_QUANTA.Q_RES(CHIPS)':
 C_PATH='@t6g_mb_lib.t6g(sch_1):page309_i2@pure_quanta.q_res(chips)';

PART_NAME
 PL29 'Q_INDUCTOR4P_14-150NH,SMLF,IND,CV+15^0TZ01':;

SECTION_NUMBER 1
 '@T6G_MB_LIB.T6G(SCH_1):PAGE309_I74@PURE_QUANTA.Q_INDUCTOR4P_14(CHIPS)':
 C_PATH='@t6g_mb_lib.t6g(sch_1):page309_i74@pure_quanta.q_inductor4p_14(chips)';

PART_NAME
 PL28 'Q_INDUCTOR4P_14-150NH,SMLF,IND,CV+15^0TZ01':;

SECTION_NUMBER 1
 '@T6G_MB_LIB.T6G(SCH_1):PAGE309_I90@PURE_QUANTA.Q_INDUCTOR4P_14(CHIPS)':
 C_PATH='@t6g_mb_lib.t6g(sch_1):page309_i90@pure_quanta.q_inductor4p_14(chips)';

PART_NAME
 PC1359 'Q_CAP_0402-0.1UF,25V,10%,X7R,CH4104K1B00':;

SECTION_NUMBER 1
 '@T6G_MB_LIB.T6G(SCH_1):PAGE309_I23@PURE_QUANTA.Q_CAP(CHIPS)':
 C_PATH='@t6g_mb_lib.t6g(sch_1):page309_i23@pure_quanta.q_cap(chips)',
 CDSVAR_REPCELL_MPS='pure_quanta|Q_cap',
 VAR_0_MPS='VALUE|0.1UF|VOLTAGE|25V|TOLERANCE|10%|PACK_TYPE|0402|MATERIAL|EMPTY|~
PART_NUMBER|CH4104K1B00|STANDARD||LIFECYCLE||ASS_PART||PART_NUMBER|CH4104K1B00|J~
EDEC_TYPE|C0402|ALT_SYMBOLS|(C0402_OCTAGONXA,C0402-0201)|VALUE|NA|RATED_VOLTAGE|~
25V|TOL|10%|CLASS|IO|DESCRIPTION|CAP CHIP 0.1U 25V(+-10%,X7R,0402)|COMPONENT_TYP~
E|CHIP0402|LEAD_LENGTH||LPID||DATE|20160113|VARIANT_DEVICE_TYPE|Q_CAP-0.1UF,25V,~
10%,0402,EMPTY';

PART_NAME
 PC1358 'Q_CAP_0402-0.1UF,25V,10%,X7R,CH4104K1B00':;

SECTION_NUMBER 1
 '@T6G_MB_LIB.T6G(SCH_1):PAGE309_I8@PURE_QUANTA.Q_CAP(CHIPS)':
 C_PATH='@t6g_mb_lib.t6g(sch_1):page309_i8@pure_quanta.q_cap(chips)',
 CDSVAR_REPCELL_MPS='pure_quanta|Q_cap',
 VAR_0_MPS='VALUE|0.1UF|VOLTAGE|25V|TOLERANCE|10%|PACK_TYPE|0402|MATERIAL|EMPTY|~
PART_NUMBER|CH4104K1B00|STANDARD||LIFECYCLE||ASS_PART||PART_NUMBER|CH4104K1B00|J~
EDEC_TYPE|C0402|ALT_SYMBOLS|(C0402_OCTAGONXA,C0402-0201)|VALUE|NA|RATED_VOLTAGE|~
25V|TOL|10%|CLASS|IO|DESCRIPTION|CAP CHIP 0.1U 25V(+-10%,X7R,0402)|COMPONENT_TYP~
E|CHIP0402|LEAD_LENGTH||LPID||DATE|20160113|VARIANT_DEVICE_TYPE|Q_CAP-0.1UF,25V,~
10%,0402,EMPTY';

PART_NAME
 PC544_P1_3 'Q_CAP_0805-22UF,4V,20%,X6S,TMP_QCH622KMEA01':;

SECTION_NUMBER 1
 '@T6G_MB_LIB.T6G(SCH_1):PAGE309_I77@PURE_QUANTA.Q_CAP(CHIPS)':
 C_PATH='@t6g_mb_lib.t6g(sch_1):page309_i77@pure_quanta.q_cap(chips)';

PART_NAME
 PC543_P1_4 'Q_CAP_0805-22UF,4V,20%,X6S,TMP_QCH622KMEA01':;

SECTION_NUMBER 1
 '@T6G_MB_LIB.T6G(SCH_1):PAGE309_I94@PURE_QUANTA.Q_CAP(CHIPS)':
 C_PATH='@t6g_mb_lib.t6g(sch_1):page309_i94@pure_quanta.q_cap(chips)';

PART_NAME
 PC542_P1_3 'Q_CAP_0805-22UF,4V,20%,X6S,TMP_QCH622KMEA01':;

SECTION_NUMBER 1
 '@T6G_MB_LIB.T6G(SCH_1):PAGE309_I79@PURE_QUANTA.Q_CAP(CHIPS)':
 C_PATH='@t6g_mb_lib.t6g(sch_1):page309_i79@pure_quanta.q_cap(chips)';

PART_NAME
 PC541_P1_4 'Q_CAP_0805-22UF,4V,20%,X6S,TMP_QCH622KMEA01':;

SECTION_NUMBER 1
 '@T6G_MB_LIB.T6G(SCH_1):PAGE309_I96@PURE_QUANTA.Q_CAP(CHIPS)':
 C_PATH='@t6g_mb_lib.t6g(sch_1):page309_i96@pure_quanta.q_cap(chips)';

PART_NAME
 PC538_P1_3 'Q_CAP_C0805-22UF,16V,20%,X6S,CH6223MEA00':;

SECTION_NUMBER 1
 '@T6G_MB_LIB.T6G(SCH_1):PAGE309_I54@PURE_QUANTA.Q_CAP(CHIPS)':
 C_PATH='@t6g_mb_lib.t6g(sch_1):page309_i54@pure_quanta.q_cap(chips)';

PART_NAME
 PC537_P1_4 'Q_CAP_C0805-22UF,16V,20%,X6S,CH6223MEA00':;

SECTION_NUMBER 1
 '@T6G_MB_LIB.T6G(SCH_1):PAGE309_I43@PURE_QUANTA.Q_CAP(CHIPS)':
 C_PATH='@t6g_mb_lib.t6g(sch_1):page309_i43@pure_quanta.q_cap(chips)';

PART_NAME
 PC536_P1_3 'Q_CAP_C0805-22UF,16V,20%,X6S,CH6223MEA00':;

SECTION_NUMBER 1
 '@T6G_MB_LIB.T6G(SCH_1):PAGE309_I53@PURE_QUANTA.Q_CAP(CHIPS)':
 C_PATH='@t6g_mb_lib.t6g(sch_1):page309_i53@pure_quanta.q_cap(chips)';

PART_NAME
 PC535_P1_4 'Q_CAP_C0805-22UF,16V,20%,X6S,CH6223MEA00':;

SECTION_NUMBER 1
 '@T6G_MB_LIB.T6G(SCH_1):PAGE309_I42@PURE_QUANTA.Q_CAP(CHIPS)':
 C_PATH='@t6g_mb_lib.t6g(sch_1):page309_i42@pure_quanta.q_cap(chips)';

PART_NAME
 PC534_P1_3 'Q_CAP_C0805-22UF,16V,20%,X6S,CH6223MEA00':;

SECTION_NUMBER 1
 '@T6G_MB_LIB.T6G(SCH_1):PAGE309_I49@PURE_QUANTA.Q_CAP(CHIPS)':
 C_PATH='@t6g_mb_lib.t6g(sch_1):page309_i49@pure_quanta.q_cap(chips)';

PART_NAME
 PC533_P1_4 'Q_CAP_C0805-22UF,16V,20%,X6S,CH6223MEA00':;

SECTION_NUMBER 1
 '@T6G_MB_LIB.T6G(SCH_1):PAGE309_I36@PURE_QUANTA.Q_CAP(CHIPS)':
 C_PATH='@t6g_mb_lib.t6g(sch_1):page309_i36@pure_quanta.q_cap(chips)';

PART_NAME
 PC532 'Q_CAP_C0402-100NF,50V,10%,X7R,CH4106K1B01':;

SECTION_NUMBER 1
 '@T6G_MB_LIB.T6G(SCH_1):PAGE309_I52@PURE_QUANTA.Q_CAP(CHIPS)':
 C_PATH='@t6g_mb_lib.t6g(sch_1):page309_i52@pure_quanta.q_cap(chips)';

PART_NAME
 PC531 'Q_CAP_C0402-100NF,50V,10%,X7R,CH4106K1B01':;

SECTION_NUMBER 1
 '@T6G_MB_LIB.T6G(SCH_1):PAGE309_I41@PURE_QUANTA.Q_CAP(CHIPS)':
 C_PATH='@t6g_mb_lib.t6g(sch_1):page309_i41@pure_quanta.q_cap(chips)';

PART_NAME
 PC530_P1_3 'Q_CAP_C0402-1UF,16V,10%,X6S,CH5103KEB01':;

SECTION_NUMBER 1
 '@T6G_MB_LIB.T6G(SCH_1):PAGE309_I48@PURE_QUANTA.Q_CAP(CHIPS)':
 C_PATH='@t6g_mb_lib.t6g(sch_1):page309_i48@pure_quanta.q_cap(chips)';

PART_NAME
 PC529_P1_4 'Q_CAP_C0402-1UF,16V,10%,X6S,CH5103KEB01':;

SECTION_NUMBER 1
 '@T6G_MB_LIB.T6G(SCH_1):PAGE309_I35@PURE_QUANTA.Q_CAP(CHIPS)':
 C_PATH='@t6g_mb_lib.t6g(sch_1):page309_i35@pure_quanta.q_cap(chips)';

PART_NAME
 PC528_P1_3 'Q_CAP_0402-3300PF,50V,10%,X7R,TMP_QCH2336K1B12':;

SECTION_NUMBER 1
 '@T6G_MB_LIB.T6G(SCH_1):PAGE309_I46@PURE_QUANTA.Q_CAP(CHIPS)':
 C_PATH='@t6g_mb_lib.t6g(sch_1):page309_i46@pure_quanta.q_cap(chips)';

PART_NAME
 PC527_P1_4 'Q_CAP_0402-3300PF,50V,10%,X7R,TMP_QCH2336K1B12':;

SECTION_NUMBER 1
 '@T6G_MB_LIB.T6G(SCH_1):PAGE309_I32@PURE_QUANTA.Q_CAP(CHIPS)':
 C_PATH='@t6g_mb_lib.t6g(sch_1):page309_i32@pure_quanta.q_cap(chips)';

PART_NAME
 PC526_P1_3 'Q_CAP_C0402-2.2UF,10V,10%,X6S,CH5222KEB01':;

SECTION_NUMBER 1
 '@T6G_MB_LIB.T6G(SCH_1):PAGE309_I30@PURE_QUANTA.Q_CAP(CHIPS)':
 C_PATH='@t6g_mb_lib.t6g(sch_1):page309_i30@pure_quanta.q_cap(chips)';

PART_NAME
 PC525_P1_4 'Q_CAP_C0402-2.2UF,10V,10%,X6S,CH5222KEB01':;

SECTION_NUMBER 1
 '@T6G_MB_LIB.T6G(SCH_1):PAGE309_I16@PURE_QUANTA.Q_CAP(CHIPS)':
 C_PATH='@t6g_mb_lib.t6g(sch_1):page309_i16@pure_quanta.q_cap(chips)';

PART_NAME
 PC524 'Q_CAP_C0402-2.2UF,10V,10%,X6S,CH5222KEB01':;

SECTION_NUMBER 1
 '@T6G_MB_LIB.T6G(SCH_1):PAGE309_I26@PURE_QUANTA.Q_CAP(CHIPS)':
 C_PATH='@t6g_mb_lib.t6g(sch_1):page309_i26@pure_quanta.q_cap(chips)';

PART_NAME
 PC523 'Q_CAP_C0402-2.2UF,10V,10%,X6S,CH5222KEB01':;

SECTION_NUMBER 1
 '@T6G_MB_LIB.T6G(SCH_1):PAGE309_I11@PURE_QUANTA.Q_CAP(CHIPS)':
 C_PATH='@t6g_mb_lib.t6g(sch_1):page309_i11@pure_quanta.q_cap(chips)';

PART_NAME
 PU26_P1_5 'ISL99390FRZTR5935-ISL99390FRZ-TR5935,SMLF,IC,AL099390004':;

SECTION_NUMBER 1
 '@T6G_MB_LIB.T6G(SCH_1):PAGE310_I32@PURE_QUANTA.ISL99390FRZTR5935(CHIPS)':
 C_PATH='@s6q_mb_lib.s6q(sch_1):page310_i32@pure_quanta.isl99390frztr5935(chips)~
';

PART_NAME
 PU25_P1_6 'ISL99390FRZTR5935-ISL99390FRZ-TR5935,SMLF,IC,AL099390004':;

SECTION_NUMBER 1
 '@T6G_MB_LIB.T6G(SCH_1):PAGE310_I23@PURE_QUANTA.ISL99390FRZTR5935(CHIPS)':
 C_PATH='@s6q_mb_lib.s6q(sch_1):page310_i23@pure_quanta.isl99390frztr5935(chips)~
';

PART_NAME
 PR1791 'Q_RES_0402LF-3.3,1%,1/16W,CHIP,CS-3302FB00':;

SECTION_NUMBER 1
 '@T6G_MB_LIB.T6G(SCH_1):PAGE310_I47@PURE_QUANTA.Q_RES(CHIPS)':
 C_PATH='@t6g_mb_lib.t6g(sch_1):page310_i47@pure_quanta.q_res(chips)',
 CDSVAR_REPCELL_MPS='pure_quanta|Q_res',
 VAR_0_MPS='VALUE|0|TOLERANCE|5%|WATTAGE|1/16W|PACK_TYPE|0402LF|MATERIAL|CHIP|PA~
RT_NUMBER|CS00002JB38|STANDARD|End of Design|LIFECYCLE|Comp-Approve|PART_NUMBER|~
CS00002JB38|JEDEC_TYPE|R0402|ALT_SYMBOLS|(R0402-0201)|VALUE|0|TOL|5%|WATTAGE|1/1~
6W|CLASS|DISCRETE|DESCRIPTION|RESISTOR CHIP 0 1/16W +-5%(0402)|COMPONENT_TYPE|CH~
IP0402|LEAD_LENGTH||DFM_EXCLUSION||DAY|20100618|VARIANT_DEVICE_TYPE|Q_RES-0,5%,1~
/16W,0402LF,CHIP,C';

PART_NAME
 PR1790 'Q_RES_0402LF-3.3,1%,1/16W,CHIP,CS-3302FB00':;

SECTION_NUMBER 1
 '@T6G_MB_LIB.T6G(SCH_1):PAGE310_I36@PURE_QUANTA.Q_RES(CHIPS)':
 C_PATH='@t6g_mb_lib.t6g(sch_1):page310_i36@pure_quanta.q_res(chips)',
 CDSVAR_REPCELL_MPS='pure_quanta|Q_res',
 VAR_0_MPS='VALUE|0|TOLERANCE|5%|WATTAGE|1/16W|PACK_TYPE|0402LF|MATERIAL|CHIP|PA~
RT_NUMBER|CS00002JB38|STANDARD|End of Design|LIFECYCLE|Comp-Approve|PART_NUMBER|~
CS00002JB38|JEDEC_TYPE|R0402|ALT_SYMBOLS|(R0402-0201)|VALUE|0|TOL|5%|WATTAGE|1/1~
6W|CLASS|DISCRETE|DESCRIPTION|RESISTOR CHIP 0 1/16W +-5%(0402)|COMPONENT_TYPE|CH~
IP0402|LEAD_LENGTH||DFM_EXCLUSION||DAY|20100618|VARIANT_DEVICE_TYPE|Q_RES-0,5%,1~
/16W,0402LF,CHIP,C';

PART_NAME
 PR296 'Q_RES_0402LF-0,5%,1/16W,CHIP,CS00002JB38':;

SECTION_NUMBER 1
 '@T6G_MB_LIB.T6G(SCH_1):PAGE310_I80@PURE_QUANTA.Q_RES(CHIPS)':
 C_PATH='@t6g_mb_lib.t6g(sch_1):page310_i80@pure_quanta.q_res(chips)';

PART_NAME
 PR295 'Q_RES_0402LF-0,5%,1/16W,CHIP,CS00002JB38':;

SECTION_NUMBER 1
 '@T6G_MB_LIB.T6G(SCH_1):PAGE310_I96@PURE_QUANTA.Q_RES(CHIPS)':
 C_PATH='@t6g_mb_lib.t6g(sch_1):page310_i96@pure_quanta.q_res(chips)';

PART_NAME
 PR294 'Q_RES_0402LF-2.2,1%,1/16W,CHIP,CS-2202FB00':;

SECTION_NUMBER 1
 '@T6G_MB_LIB.T6G(SCH_1):PAGE310_I21@PURE_QUANTA.Q_RES(CHIPS)':
 C_PATH='@t6g_mb_lib.t6g(sch_1):page310_i21@pure_quanta.q_res(chips)';

PART_NAME
 PR293 'Q_RES_0402LF-2.2,1%,1/16W,CHIP,CS-2202FB00':;

SECTION_NUMBER 1
 '@T6G_MB_LIB.T6G(SCH_1):PAGE310_I10@PURE_QUANTA.Q_RES(CHIPS)':
 C_PATH='@t6g_mb_lib.t6g(sch_1):page310_i10@pure_quanta.q_res(chips)';

PART_NAME
 PR292 'Q_RES_0402LF-8.87K,1%,1/16W,EMPTY,CS28872FB01':;

SECTION_NUMBER 1
 '@T6G_MB_LIB.T6G(SCH_1):PAGE310_I13@PURE_QUANTA.Q_RES(CHIPS)':
 C_PATH='@t6g_mb_lib.t6g(sch_1):page310_i13@pure_quanta.q_res(chips)';

PART_NAME
 PR291 'Q_RES_0402LF-8.87K,1%,1/16W,EMPTY,CS28872FB01':;

SECTION_NUMBER 1
 '@T6G_MB_LIB.T6G(SCH_1):PAGE310_I2@PURE_QUANTA.Q_RES(CHIPS)':
 C_PATH='@t6g_mb_lib.t6g(sch_1):page310_i2@pure_quanta.q_res(chips)';

PART_NAME
 PL27 'Q_INDUCTOR4P_14-150NH,SMLF,IND,CV+15^0TZ01':;

SECTION_NUMBER 1
 '@T6G_MB_LIB.T6G(SCH_1):PAGE310_I73@PURE_QUANTA.Q_INDUCTOR4P_14(CHIPS)':
 C_PATH='@t6g_mb_lib.t6g(sch_1):page310_i73@pure_quanta.q_inductor4p_14(chips)';

PART_NAME
 PL26 'Q_INDUCTOR4P_14-150NH,SMLF,IND,CV+15^0TZ01':;

SECTION_NUMBER 1
 '@T6G_MB_LIB.T6G(SCH_1):PAGE310_I90@PURE_QUANTA.Q_INDUCTOR4P_14(CHIPS)':
 C_PATH='@t6g_mb_lib.t6g(sch_1):page310_i90@pure_quanta.q_inductor4p_14(chips)';

PART_NAME
 PC1361 'Q_CAP_0402-0.1UF,25V,10%,X7R,CH4104K1B00':;

SECTION_NUMBER 1
 '@T6G_MB_LIB.T6G(SCH_1):PAGE310_I31@PURE_QUANTA.Q_CAP(CHIPS)':
 C_PATH='@t6g_mb_lib.t6g(sch_1):page310_i31@pure_quanta.q_cap(chips)',
 CDSVAR_REPCELL_MPS='pure_quanta|Q_cap',
 VAR_0_MPS='VALUE|0.1UF|VOLTAGE|25V|TOLERANCE|10%|PACK_TYPE|0402|MATERIAL|EMPTY|~
PART_NUMBER|CH4104K1B00|STANDARD||LIFECYCLE||ASS_PART||PART_NUMBER|CH4104K1B00|J~
EDEC_TYPE|C0402|ALT_SYMBOLS|(C0402_OCTAGONXA,C0402-0201)|VALUE|NA|RATED_VOLTAGE|~
25V|TOL|10%|CLASS|IO|DESCRIPTION|CAP CHIP 0.1U 25V(+-10%,X7R,0402)|COMPONENT_TYP~
E|CHIP0402|LEAD_LENGTH||LPID||DATE|20160113|VARIANT_DEVICE_TYPE|Q_CAP-0.1UF,25V,~
10%,0402,EMPTY';

PART_NAME
 PC1360 'Q_CAP_0402-0.1UF,25V,10%,X7R,CH4104K1B00':;

SECTION_NUMBER 1
 '@T6G_MB_LIB.T6G(SCH_1):PAGE310_I28@PURE_QUANTA.Q_CAP(CHIPS)':
 C_PATH='@t6g_mb_lib.t6g(sch_1):page310_i28@pure_quanta.q_cap(chips)',
 CDSVAR_REPCELL_MPS='pure_quanta|Q_cap',
 VAR_0_MPS='VALUE|0.1UF|VOLTAGE|25V|TOLERANCE|10%|PACK_TYPE|0402|MATERIAL|EMPTY|~
PART_NUMBER|CH4104K1B00|STANDARD||LIFECYCLE||ASS_PART||PART_NUMBER|CH4104K1B00|J~
EDEC_TYPE|C0402|ALT_SYMBOLS|(C0402_OCTAGONXA,C0402-0201)|VALUE|NA|RATED_VOLTAGE|~
25V|TOL|10%|CLASS|IO|DESCRIPTION|CAP CHIP 0.1U 25V(+-10%,X7R,0402)|COMPONENT_TYP~
E|CHIP0402|LEAD_LENGTH||LPID||DATE|20160113|VARIANT_DEVICE_TYPE|Q_CAP-0.1UF,25V,~
10%,0402,EMPTY';

PART_NAME
 PC522_P1_5 'Q_CAP_0805-22UF,4V,20%,X6S,TMP_QCH622KMEA01':;

SECTION_NUMBER 1
 '@T6G_MB_LIB.T6G(SCH_1):PAGE310_I78@PURE_QUANTA.Q_CAP(CHIPS)':
 C_PATH='@t6g_mb_lib.t6g(sch_1):page310_i78@pure_quanta.q_cap(chips)';

PART_NAME
 PC521_P1_6 'Q_CAP_0805-22UF,4V,20%,X6S,TMP_QCH622KMEA01':;

SECTION_NUMBER 1
 '@T6G_MB_LIB.T6G(SCH_1):PAGE310_I94@PURE_QUANTA.Q_CAP(CHIPS)':
 C_PATH='@t6g_mb_lib.t6g(sch_1):page310_i94@pure_quanta.q_cap(chips)';

PART_NAME
 PC520_P1_5 'Q_CAP_0805-22UF,4V,20%,X6S,TMP_QCH622KMEA01':;

SECTION_NUMBER 1
 '@T6G_MB_LIB.T6G(SCH_1):PAGE310_I79@PURE_QUANTA.Q_CAP(CHIPS)':
 C_PATH='@t6g_mb_lib.t6g(sch_1):page310_i79@pure_quanta.q_cap(chips)';

PART_NAME
 PC519_P1_6 'Q_CAP_0805-22UF,4V,20%,X6S,TMP_QCH622KMEA01':;

SECTION_NUMBER 1
 '@T6G_MB_LIB.T6G(SCH_1):PAGE310_I95@PURE_QUANTA.Q_CAP(CHIPS)':
 C_PATH='@t6g_mb_lib.t6g(sch_1):page310_i95@pure_quanta.q_cap(chips)';

PART_NAME
 PC516_P1_5 'Q_CAP_C0805-22UF,16V,20%,X6S,CH6223MEA00':;

SECTION_NUMBER 1
 '@T6G_MB_LIB.T6G(SCH_1):PAGE310_I56@PURE_QUANTA.Q_CAP(CHIPS)':
 C_PATH='@t6g_mb_lib.t6g(sch_1):page310_i56@pure_quanta.q_cap(chips)';

PART_NAME
 PC515_P1_6 'Q_CAP_C0805-22UF,16V,20%,X6S,CH6223MEA00':;

SECTION_NUMBER 1
 '@T6G_MB_LIB.T6G(SCH_1):PAGE310_I45@PURE_QUANTA.Q_CAP(CHIPS)':
 C_PATH='@t6g_mb_lib.t6g(sch_1):page310_i45@pure_quanta.q_cap(chips)';

PART_NAME
 PC514_P1_5 'Q_CAP_C0805-22UF,16V,20%,X6S,CH6223MEA00':;

SECTION_NUMBER 1
 '@T6G_MB_LIB.T6G(SCH_1):PAGE310_I54@PURE_QUANTA.Q_CAP(CHIPS)':
 C_PATH='@t6g_mb_lib.t6g(sch_1):page310_i54@pure_quanta.q_cap(chips)';

PART_NAME
 PC513_P1_6 'Q_CAP_C0805-22UF,16V,20%,X6S,CH6223MEA00':;

SECTION_NUMBER 1
 '@T6G_MB_LIB.T6G(SCH_1):PAGE310_I44@PURE_QUANTA.Q_CAP(CHIPS)':
 C_PATH='@t6g_mb_lib.t6g(sch_1):page310_i44@pure_quanta.q_cap(chips)';

PART_NAME
 PC512_P1_5 'Q_CAP_C0805-22UF,16V,20%,X6S,CH6223MEA00':;

SECTION_NUMBER 1
 '@T6G_MB_LIB.T6G(SCH_1):PAGE310_I50@PURE_QUANTA.Q_CAP(CHIPS)':
 C_PATH='@t6g_mb_lib.t6g(sch_1):page310_i50@pure_quanta.q_cap(chips)';

PART_NAME
 PC511_P1_6 'Q_CAP_C0805-22UF,16V,20%,X6S,CH6223MEA00':;

SECTION_NUMBER 1
 '@T6G_MB_LIB.T6G(SCH_1):PAGE310_I39@PURE_QUANTA.Q_CAP(CHIPS)':
 C_PATH='@t6g_mb_lib.t6g(sch_1):page310_i39@pure_quanta.q_cap(chips)';

PART_NAME
 PC510 'Q_CAP_C0402-100NF,50V,10%,X7R,CH4106K1B01':;

SECTION_NUMBER 1
 '@T6G_MB_LIB.T6G(SCH_1):PAGE310_I53@PURE_QUANTA.Q_CAP(CHIPS)':
 C_PATH='@t6g_mb_lib.t6g(sch_1):page310_i53@pure_quanta.q_cap(chips)';

PART_NAME
 PC509 'Q_CAP_C0402-100NF,50V,10%,X7R,CH4106K1B01':;

SECTION_NUMBER 1
 '@T6G_MB_LIB.T6G(SCH_1):PAGE310_I41@PURE_QUANTA.Q_CAP(CHIPS)':
 C_PATH='@t6g_mb_lib.t6g(sch_1):page310_i41@pure_quanta.q_cap(chips)';

PART_NAME
 PC508_P1_5 'Q_CAP_C0402-1UF,16V,10%,X6S,CH5103KEB01':;

SECTION_NUMBER 1
 '@T6G_MB_LIB.T6G(SCH_1):PAGE310_I49@PURE_QUANTA.Q_CAP(CHIPS)':
 C_PATH='@t6g_mb_lib.t6g(sch_1):page310_i49@pure_quanta.q_cap(chips)';

PART_NAME
 PC507_P1_6 'Q_CAP_C0402-1UF,16V,10%,X6S,CH5103KEB01':;

SECTION_NUMBER 1
 '@T6G_MB_LIB.T6G(SCH_1):PAGE310_I38@PURE_QUANTA.Q_CAP(CHIPS)':
 C_PATH='@t6g_mb_lib.t6g(sch_1):page310_i38@pure_quanta.q_cap(chips)';

PART_NAME
 PC506_P1_5 'Q_CAP_0402-3300PF,50V,10%,X7R,TMP_QCH2336K1B12':;

SECTION_NUMBER 1
 '@T6G_MB_LIB.T6G(SCH_1):PAGE310_I48@PURE_QUANTA.Q_CAP(CHIPS)':
 C_PATH='@t6g_mb_lib.t6g(sch_1):page310_i48@pure_quanta.q_cap(chips)';

PART_NAME
 PC505_P1_6 'Q_CAP_0402-3300PF,50V,10%,X7R,TMP_QCH2336K1B12':;

SECTION_NUMBER 1
 '@T6G_MB_LIB.T6G(SCH_1):PAGE310_I37@PURE_QUANTA.Q_CAP(CHIPS)':
 C_PATH='@t6g_mb_lib.t6g(sch_1):page310_i37@pure_quanta.q_cap(chips)';

PART_NAME
 PC504_P1_5 'Q_CAP_C0402-2.2UF,10V,10%,X6S,CH5222KEB01':;

SECTION_NUMBER 1
 '@T6G_MB_LIB.T6G(SCH_1):PAGE310_I34@PURE_QUANTA.Q_CAP(CHIPS)':
 C_PATH='@t6g_mb_lib.t6g(sch_1):page310_i34@pure_quanta.q_cap(chips)';

PART_NAME
 PC503_P1_6 'Q_CAP_C0402-2.2UF,10V,10%,X6S,CH5222KEB01':;

SECTION_NUMBER 1
 '@T6G_MB_LIB.T6G(SCH_1):PAGE310_I29@PURE_QUANTA.Q_CAP(CHIPS)':
 C_PATH='@t6g_mb_lib.t6g(sch_1):page310_i29@pure_quanta.q_cap(chips)';

PART_NAME
 PC502 'Q_CAP_C0402-2.2UF,10V,10%,X6S,CH5222KEB01':;

SECTION_NUMBER 1
 '@T6G_MB_LIB.T6G(SCH_1):PAGE310_I20@PURE_QUANTA.Q_CAP(CHIPS)':
 C_PATH='@t6g_mb_lib.t6g(sch_1):page310_i20@pure_quanta.q_cap(chips)';

PART_NAME
 PC501 'Q_CAP_C0402-2.2UF,10V,10%,X6S,CH5222KEB01':;

SECTION_NUMBER 1
 '@T6G_MB_LIB.T6G(SCH_1):PAGE310_I8@PURE_QUANTA.Q_CAP(CHIPS)':
 C_PATH='@t6g_mb_lib.t6g(sch_1):page310_i8@pure_quanta.q_cap(chips)';

PART_NAME
 PU24_P1_7 'ISL99390FRZTR5935-ISL99390FRZ-TR5935,SMLF,IC,AL099390004':;

SECTION_NUMBER 1
 '@T6G_MB_LIB.T6G(SCH_1):PAGE311_I37@PURE_QUANTA.ISL99390FRZTR5935(CHIPS)':
 C_PATH='@s6q_mb_lib.s6q(sch_1):page311_i37@pure_quanta.isl99390frztr5935(chips)~
';

PART_NAME
 PU23_P1_8 'ISL99390FRZTR5935-ISL99390FRZ-TR5935,SMLF,IC,AL099390004':;

SECTION_NUMBER 1
 '@T6G_MB_LIB.T6G(SCH_1):PAGE311_I9@PURE_QUANTA.ISL99390FRZTR5935(CHIPS)':
 C_PATH='@t6g_mb_lib.t6g(sch_1):page311_i9@pure_quanta.isl99390frztr5935(chips)';

PART_NAME
 PR1793 'Q_RES_0402LF-3.3,1%,1/16W,CHIP,CS-3302FB00':;

SECTION_NUMBER 1
 '@T6G_MB_LIB.T6G(SCH_1):PAGE311_I47@PURE_QUANTA.Q_RES(CHIPS)':
 C_PATH='@t6g_mb_lib.t6g(sch_1):page311_i47@pure_quanta.q_res(chips)',
 CDSVAR_REPCELL_MPS='pure_quanta|Q_res',
 VAR_0_MPS='VALUE|0|TOLERANCE|5%|WATTAGE|1/16W|PACK_TYPE|0402LF|MATERIAL|CHIP|PA~
RT_NUMBER|CS00002JB38|STANDARD|End of Design|LIFECYCLE|Comp-Approve|PART_NUMBER|~
CS00002JB38|JEDEC_TYPE|R0402|ALT_SYMBOLS|(R0402-0201)|VALUE|0|TOL|5%|WATTAGE|1/1~
6W|CLASS|DISCRETE|DESCRIPTION|RESISTOR CHIP 0 1/16W +-5%(0402)|COMPONENT_TYPE|CH~
IP0402|LEAD_LENGTH||DFM_EXCLUSION||DAY|20100618|VARIANT_DEVICE_TYPE|Q_RES-0,5%,1~
/16W,0402LF,CHIP,C';

PART_NAME
 PR1792 'Q_RES_0402LF-3.3,1%,1/16W,CHIP,CS-3302FB00':;

SECTION_NUMBER 1
 '@T6G_MB_LIB.T6G(SCH_1):PAGE311_I39@PURE_QUANTA.Q_RES(CHIPS)':
 C_PATH='@t6g_mb_lib.t6g(sch_1):page311_i39@pure_quanta.q_res(chips)',
 CDSVAR_REPCELL_MPS='pure_quanta|Q_res',
 VAR_0_MPS='VALUE|0|TOLERANCE|5%|WATTAGE|1/16W|PACK_TYPE|0402LF|MATERIAL|CHIP|PA~
RT_NUMBER|CS00002JB38|STANDARD|End of Design|LIFECYCLE|Comp-Approve|PART_NUMBER|~
CS00002JB38|JEDEC_TYPE|R0402|ALT_SYMBOLS|(R0402-0201)|VALUE|0|TOL|5%|WATTAGE|1/1~
6W|CLASS|DISCRETE|DESCRIPTION|RESISTOR CHIP 0 1/16W +-5%(0402)|COMPONENT_TYPE|CH~
IP0402|LEAD_LENGTH||DFM_EXCLUSION||DAY|20100618|VARIANT_DEVICE_TYPE|Q_RES-0,5%,1~
/16W,0402LF,CHIP,C';

PART_NAME
 PR290 'Q_RES_0402LF-0,5%,1/16W,CHIP,CS00002JB38':;

SECTION_NUMBER 1
 '@T6G_MB_LIB.T6G(SCH_1):PAGE311_I79@PURE_QUANTA.Q_RES(CHIPS)':
 C_PATH='@t6g_mb_lib.t6g(sch_1):page311_i79@pure_quanta.q_res(chips)';

PART_NAME
 PR289 'Q_RES_0402LF-0,5%,1/16W,CHIP,CS00002JB38':;

SECTION_NUMBER 1
 '@T6G_MB_LIB.T6G(SCH_1):PAGE311_I98@PURE_QUANTA.Q_RES(CHIPS)':
 C_PATH='@t6g_mb_lib.t6g(sch_1):page311_i98@pure_quanta.q_res(chips)';

PART_NAME
 PR288 'Q_RES_0402LF-2.2,1%,1/16W,CHIP,CS-2202FB00':;

SECTION_NUMBER 1
 '@T6G_MB_LIB.T6G(SCH_1):PAGE311_I34@PURE_QUANTA.Q_RES(CHIPS)':
 C_PATH='@t6g_mb_lib.t6g(sch_1):page311_i34@pure_quanta.q_res(chips)';

PART_NAME
 PR287 'Q_RES_0402LF-2.2,1%,1/16W,CHIP,CS-2202FB00':;

SECTION_NUMBER 1
 '@T6G_MB_LIB.T6G(SCH_1):PAGE311_I26@PURE_QUANTA.Q_RES(CHIPS)':
 C_PATH='@t6g_mb_lib.t6g(sch_1):page311_i26@pure_quanta.q_res(chips)';

PART_NAME
 PR286 'Q_RES_0402LF-8.87K,1%,1/16W,EMPTY,CS28872FB01':;

SECTION_NUMBER 1
 '@T6G_MB_LIB.T6G(SCH_1):PAGE311_I18@PURE_QUANTA.Q_RES(CHIPS)':
 C_PATH='@t6g_mb_lib.t6g(sch_1):page311_i18@pure_quanta.q_res(chips)';

PART_NAME
 PR285 'Q_RES_0402LF-8.87K,1%,1/16W,EMPTY,CS28872FB01':;

SECTION_NUMBER 1
 '@T6G_MB_LIB.T6G(SCH_1):PAGE311_I2@PURE_QUANTA.Q_RES(CHIPS)':
 C_PATH='@t6g_mb_lib.t6g(sch_1):page311_i2@pure_quanta.q_res(chips)';

PART_NAME
 PL106 'Q_INDUCTOR_SMLF-120NH/76A,IND,CV+12^0TZ06':;

SECTION_NUMBER 1
 '@T6G_MB_LIB.T6G(SCH_1):PAGE311_I107@PURE_QUANTA.Q_INDUCTOR(CHIPS)':
 C_PATH='@t6g_mb_lib.t6g(sch_1):page311_i107@pure_quanta.q_inductor(chips)';

PART_NAME
 PL25 'Q_INDUCTOR4P_14-150NH,SMLF,IND,CV+15^0TZ01':;

SECTION_NUMBER 1
 '@T6G_MB_LIB.T6G(SCH_1):PAGE311_I76@PURE_QUANTA.Q_INDUCTOR4P_14(CHIPS)':
 C_PATH='@t6g_mb_lib.t6g(sch_1):page311_i76@pure_quanta.q_inductor4p_14(chips)';

PART_NAME
 PL24 'Q_INDUCTOR4P_14-150NH,SMLF,IND,CV+15^0TZ01':;

SECTION_NUMBER 1
 '@T6G_MB_LIB.T6G(SCH_1):PAGE311_I95@PURE_QUANTA.Q_INDUCTOR4P_14(CHIPS)':
 C_PATH='@t6g_mb_lib.t6g(sch_1):page311_i95@pure_quanta.q_inductor4p_14(chips)';

PART_NAME
 PC1363 'Q_CAP_0402-0.1UF,25V,10%,X7R,CH4104K1B00':;

SECTION_NUMBER 1
 '@T6G_MB_LIB.T6G(SCH_1):PAGE311_I31@PURE_QUANTA.Q_CAP(CHIPS)':
 C_PATH='@t6g_mb_lib.t6g(sch_1):page311_i31@pure_quanta.q_cap(chips)',
 CDSVAR_REPCELL_MPS='pure_quanta|Q_cap',
 VAR_0_MPS='VALUE|0.1UF|VOLTAGE|25V|TOLERANCE|10%|PACK_TYPE|0402|MATERIAL|EMPTY|~
PART_NUMBER|CH4104K1B00|STANDARD||LIFECYCLE||ASS_PART||PART_NUMBER|CH4104K1B00|J~
EDEC_TYPE|C0402|ALT_SYMBOLS|(C0402_OCTAGONXA,C0402-0201)|VALUE|NA|RATED_VOLTAGE|~
25V|TOL|10%|CLASS|IO|DESCRIPTION|CAP CHIP 0.1U 25V(+-10%,X7R,0402)|COMPONENT_TYP~
E|CHIP0402|LEAD_LENGTH||LPID||DATE|20160113|VARIANT_DEVICE_TYPE|Q_CAP-0.1UF,25V,~
10%,0402,EMPTY';

PART_NAME
 PC1362 'Q_CAP_0402-0.1UF,25V,10%,X7R,CH4104K1B00':;

SECTION_NUMBER 1
 '@T6G_MB_LIB.T6G(SCH_1):PAGE311_I8@PURE_QUANTA.Q_CAP(CHIPS)':
 C_PATH='@t6g_mb_lib.t6g(sch_1):page311_i8@pure_quanta.q_cap(chips)',
 CDSVAR_REPCELL_MPS='pure_quanta|Q_cap',
 VAR_0_MPS='VALUE|0.1UF|VOLTAGE|25V|TOLERANCE|10%|PACK_TYPE|0402|MATERIAL|EMPTY|~
PART_NUMBER|CH4104K1B00|STANDARD||LIFECYCLE||ASS_PART||PART_NUMBER|CH4104K1B00|J~
EDEC_TYPE|C0402|ALT_SYMBOLS|(C0402_OCTAGONXA,C0402-0201)|VALUE|NA|RATED_VOLTAGE|~
25V|TOL|10%|CLASS|IO|DESCRIPTION|CAP CHIP 0.1U 25V(+-10%,X7R,0402)|COMPONENT_TYP~
E|CHIP0402|LEAD_LENGTH||LPID||DATE|20160113|VARIANT_DEVICE_TYPE|Q_CAP-0.1UF,25V,~
10%,0402,EMPTY';

PART_NAME
 PC500_P1_7 'Q_CAP_0805-22UF,4V,20%,X6S,TMP_QCH622KMEA01':;

SECTION_NUMBER 1
 '@T6G_MB_LIB.T6G(SCH_1):PAGE311_I81@PURE_QUANTA.Q_CAP(CHIPS)':
 C_PATH='@t6g_mb_lib.t6g(sch_1):page311_i81@pure_quanta.q_cap(chips)';

PART_NAME
 PC499_P1_8 'Q_CAP_0805-22UF,4V,20%,X6S,TMP_QCH622KMEA01':;

SECTION_NUMBER 1
 '@T6G_MB_LIB.T6G(SCH_1):PAGE311_I101@PURE_QUANTA.Q_CAP(CHIPS)':
 C_PATH='@t6g_mb_lib.t6g(sch_1):page311_i101@pure_quanta.q_cap(chips)';

PART_NAME
 PC498_P1_7 'Q_CAP_0805-22UF,4V,20%,X6S,TMP_QCH622KMEA01':;

SECTION_NUMBER 1
 '@T6G_MB_LIB.T6G(SCH_1):PAGE311_I83@PURE_QUANTA.Q_CAP(CHIPS)':
 C_PATH='@t6g_mb_lib.t6g(sch_1):page311_i83@pure_quanta.q_cap(chips)';

PART_NAME
 PC497_P1_8 'Q_CAP_0805-22UF,4V,20%,X6S,TMP_QCH622KMEA01':;

SECTION_NUMBER 1
 '@T6G_MB_LIB.T6G(SCH_1):PAGE311_I102@PURE_QUANTA.Q_CAP(CHIPS)':
 C_PATH='@t6g_mb_lib.t6g(sch_1):page311_i102@pure_quanta.q_cap(chips)';

PART_NAME
 PC496_P1_7 'Q_CAP_C0402-1UF,16V,10%,X6S,CH5103KEB01':;

SECTION_NUMBER 1
 '@T6G_MB_LIB.T6G(SCH_1):PAGE311_I84@PURE_QUANTA.Q_CAP(CHIPS)':
 C_PATH='@t6g_mb_lib.t6g(sch_1):page311_i84@pure_quanta.q_cap(chips)';

PART_NAME
 PC495_P1_8 'Q_CAP_C0402-1UF,16V,10%,X6S,CH5103KEB01':;

SECTION_NUMBER 1
 '@T6G_MB_LIB.T6G(SCH_1):PAGE311_I103@PURE_QUANTA.Q_CAP(CHIPS)':
 C_PATH='@t6g_mb_lib.t6g(sch_1):page311_i103@pure_quanta.q_cap(chips)';

PART_NAME
 PC494_P1_7 'Q_CAP_C0805-22UF,16V,20%,X6S,CH6223MEA00':;

SECTION_NUMBER 1
 '@T6G_MB_LIB.T6G(SCH_1):PAGE311_I54@PURE_QUANTA.Q_CAP(CHIPS)':
 C_PATH='@t6g_mb_lib.t6g(sch_1):page311_i54@pure_quanta.q_cap(chips)';

PART_NAME
 PC493_P1_8 'Q_CAP_C0805-22UF,16V,20%,X6S,CH6223MEA00':;

SECTION_NUMBER 1
 '@T6G_MB_LIB.T6G(SCH_1):PAGE311_I44@PURE_QUANTA.Q_CAP(CHIPS)':
 C_PATH='@t6g_mb_lib.t6g(sch_1):page311_i44@pure_quanta.q_cap(chips)';

PART_NAME
 PC492_P1_7 'Q_CAP_C0805-22UF,16V,20%,X6S,CH6223MEA00':;

SECTION_NUMBER 1
 '@T6G_MB_LIB.T6G(SCH_1):PAGE311_I53@PURE_QUANTA.Q_CAP(CHIPS)':
 C_PATH='@t6g_mb_lib.t6g(sch_1):page311_i53@pure_quanta.q_cap(chips)';

PART_NAME
 PC491_P1_8 'Q_CAP_C0805-22UF,16V,20%,X6S,CH6223MEA00':;

SECTION_NUMBER 1
 '@T6G_MB_LIB.T6G(SCH_1):PAGE311_I43@PURE_QUANTA.Q_CAP(CHIPS)':
 C_PATH='@t6g_mb_lib.t6g(sch_1):page311_i43@pure_quanta.q_cap(chips)';

PART_NAME
 PC490_P1_7 'Q_CAP_C0805-22UF,16V,20%,X6S,CH6223MEA00':;

SECTION_NUMBER 1
 '@T6G_MB_LIB.T6G(SCH_1):PAGE311_I52@PURE_QUANTA.Q_CAP(CHIPS)':
 C_PATH='@t6g_mb_lib.t6g(sch_1):page311_i52@pure_quanta.q_cap(chips)';

PART_NAME
 PC489_P1_8 'Q_CAP_C0805-22UF,16V,20%,X6S,CH6223MEA00':;

SECTION_NUMBER 1
 '@T6G_MB_LIB.T6G(SCH_1):PAGE311_I42@PURE_QUANTA.Q_CAP(CHIPS)':
 C_PATH='@t6g_mb_lib.t6g(sch_1):page311_i42@pure_quanta.q_cap(chips)';

PART_NAME
 PC488 'Q_CAP_C0402-100NF,50V,10%,X7R,CH4106K1B01':;

SECTION_NUMBER 1
 '@T6G_MB_LIB.T6G(SCH_1):PAGE311_I49@PURE_QUANTA.Q_CAP(CHIPS)':
 C_PATH='@t6g_mb_lib.t6g(sch_1):page311_i49@pure_quanta.q_cap(chips)';

PART_NAME
 PC487 'Q_CAP_C0402-100NF,50V,10%,X7R,CH4106K1B01':;

SECTION_NUMBER 1
 '@T6G_MB_LIB.T6G(SCH_1):PAGE311_I41@PURE_QUANTA.Q_CAP(CHIPS)':
 C_PATH='@t6g_mb_lib.t6g(sch_1):page311_i41@pure_quanta.q_cap(chips)';

PART_NAME
 PC486_P1_7 'Q_CAP_C0402-1UF,16V,10%,X6S,CH5103KEB01':;

SECTION_NUMBER 1
 '@T6G_MB_LIB.T6G(SCH_1):PAGE311_I48@PURE_QUANTA.Q_CAP(CHIPS)':
 C_PATH='@t6g_mb_lib.t6g(sch_1):page311_i48@pure_quanta.q_cap(chips)';

PART_NAME
 PC485_P1_8 'Q_CAP_C0402-1UF,16V,10%,X6S,CH5103KEB01':;

SECTION_NUMBER 1
 '@T6G_MB_LIB.T6G(SCH_1):PAGE311_I40@PURE_QUANTA.Q_CAP(CHIPS)':
 C_PATH='@t6g_mb_lib.t6g(sch_1):page311_i40@pure_quanta.q_cap(chips)';

PART_NAME
 PC484_P1_7 'Q_CAP_0402-3300PF,50V,10%,X7R,TMP_QCH2336K1B12':;

SECTION_NUMBER 1
 '@T6G_MB_LIB.T6G(SCH_1):PAGE311_I46@PURE_QUANTA.Q_CAP(CHIPS)':
 C_PATH='@t6g_mb_lib.t6g(sch_1):page311_i46@pure_quanta.q_cap(chips)';

PART_NAME
 PC483_P1_8 'Q_CAP_0402-3300PF,50V,10%,X7R,TMP_QCH2336K1B12':;

SECTION_NUMBER 1
 '@T6G_MB_LIB.T6G(SCH_1):PAGE311_I38@PURE_QUANTA.Q_CAP(CHIPS)':
 C_PATH='@t6g_mb_lib.t6g(sch_1):page311_i38@pure_quanta.q_cap(chips)';

PART_NAME
 PC482_P1_7 'Q_CAP_C0402-2.2UF,10V,10%,X6S,CH5222KEB01':;

SECTION_NUMBER 1
 '@T6G_MB_LIB.T6G(SCH_1):PAGE311_I36@PURE_QUANTA.Q_CAP(CHIPS)':
 C_PATH='@t6g_mb_lib.t6g(sch_1):page311_i36@pure_quanta.q_cap(chips)';

PART_NAME
 PC481_P1_8 'Q_CAP_C0402-2.2UF,10V,10%,X6S,CH5222KEB01':;

SECTION_NUMBER 1
 '@T6G_MB_LIB.T6G(SCH_1):PAGE311_I28@PURE_QUANTA.Q_CAP(CHIPS)':
 C_PATH='@t6g_mb_lib.t6g(sch_1):page311_i28@pure_quanta.q_cap(chips)';

PART_NAME
 PC480 'Q_CAP_C0402-2.2UF,10V,10%,X6S,CH5222KEB01':;

SECTION_NUMBER 1
 '@T6G_MB_LIB.T6G(SCH_1):PAGE311_I32@PURE_QUANTA.Q_CAP(CHIPS)':
 C_PATH='@t6g_mb_lib.t6g(sch_1):page311_i32@pure_quanta.q_cap(chips)';

PART_NAME
 PC479 'Q_CAP_C0402-2.2UF,10V,10%,X6S,CH5222KEB01':;

SECTION_NUMBER 1
 '@T6G_MB_LIB.T6G(SCH_1):PAGE311_I25@PURE_QUANTA.Q_CAP(CHIPS)':
 C_PATH='@t6g_mb_lib.t6g(sch_1):page311_i25@pure_quanta.q_cap(chips)';

PART_NAME
 R2354 'Q_RES_0402LF-100,1%,1/16W,EMPTY,TMP_QCS11002FB22':;

SECTION_NUMBER 1
 '@T6G_MB_LIB.T6G(SCH_1):PAGE315_I38@PURE_QUANTA.Q_RES(CHIPS)':
 C_PATH='@t6g_mb_lib.t6g(sch_1):page315_i38@pure_quanta.q_res(chips)';

PART_NAME
 R2345 'Q_RES_0402LF-49.9     ,1%  ,1/16W,EMPTY,CS04992FB31':;

SECTION_NUMBER 1
 '@T6G_MB_LIB.T6G(SCH_1):PAGE315_I39@PURE_QUANTA.Q_RES(CHIPS)':
 C_PATH='@t6g_mb_lib.t6g(sch_1):page315_i39@pure_quanta.q_res(chips)';

PART_NAME
 PU22 'ISL69260IRAZT-ISL69260IRAZ-T,SMLF,IC,AL069260000':;

SECTION_NUMBER 1
 '@T6G_MB_LIB.T6G(SCH_1):PAGE315_I61@PURE_QUANTA.ISL69260IRAZT(CHIPS)':
 C_PATH='@t6g_mb_lib.t6g(sch_1):page315_i61@pure_quanta.isl69260irazt(chips)';

PART_NAME
 PR667 'Q_RES_0402LF-10K,1%,1/16W,EMPTY,CS31002FB08':;

SECTION_NUMBER 1
 '@T6G_MB_LIB.T6G(SCH_1):PAGE315_I93@PURE_QUANTA.Q_RES(CHIPS)':
 C_PATH='@t6g_mb_lib.t6g(sch_1):page315_i93@pure_quanta.q_res(chips)',
 CDSVAR_REPCELL_MPS='pure_quanta|Q_res',
 VAR_0_MPS='VALUE|10K|TOLERANCE|1%|WATTAGE|1/16W|PACK_TYPE|0402LF|MATERIAL|CHIP|~
PART_NUMBER|CS31002FB08|STANDARD|End of Design|LIFECYCLE|Comp-Approve|PART_NUMBE~
R|CS31002FB08|JEDEC_TYPE|R0402|ALT_SYMBOLS|(R0402-0201)|VALUE|10K|TOL|1%|WATTAGE~
|1/16W|CLASS|DISCRETE|DESCRIPTION|RES CHIP 10K 1/16W +-1%(0402)EF|COMPONENT_TYPE~
|CHIPR0402|LEAD_LENGTH||DFM_EXCLUSION||DAY|20180208|VARIANT_DEVICE_TYPE|Q_RES-10~
K,1%,1/16W,0402LF,CHIP';

PART_NAME
 PR665 'Q_RES_0402LF-10K,1%,1/16W,EMPTY,CS31002FB08':;

SECTION_NUMBER 1
 '@T6G_MB_LIB.T6G(SCH_1):PAGE315_I70@PURE_QUANTA.Q_RES(CHIPS)':
 C_PATH='@t6g_mb_lib.t6g(sch_1):page315_i70@pure_quanta.q_res(chips)',
 CDSVAR_REPCELL_MPS='pure_quanta|Q_res',
 VAR_0_MPS='VALUE|10K|TOLERANCE|1%|WATTAGE|1/16W|PACK_TYPE|0402LF|MATERIAL|CHIP|~
PART_NUMBER|CS31002FB08|STANDARD|End of Design|LIFECYCLE|Comp-Approve|PART_NUMBE~
R|CS31002FB08|JEDEC_TYPE|R0402|ALT_SYMBOLS|(R0402-0201)|VALUE|10K|TOL|1%|WATTAGE~
|1/16W|CLASS|DISCRETE|DESCRIPTION|RES CHIP 10K 1/16W +-1%(0402)EF|COMPONENT_TYPE~
|CHIPR0402|LEAD_LENGTH||DFM_EXCLUSION||DAY|20180208|VARIANT_DEVICE_TYPE|Q_RES-10~
K,1%,1/16W,0402LF,CHIP';

PART_NAME
 PR571 'Q_RES_0402LF-1K,1%,1/16W,CHIP,TMP_QCS21002FB24':;

SECTION_NUMBER 1
 '@T6G_MB_LIB.T6G(SCH_1):PAGE315_I25@PURE_QUANTA.Q_RES(CHIPS)':
 C_PATH='@t6g_mb_lib.t6g(sch_1):page315_i25@pure_quanta.q_res(chips)';

PART_NAME
 PR570 'Q_RES_0402LF-1K,1%,1/16W,CHIP,TMP_QCS21002FB24':;

SECTION_NUMBER 1
 '@T6G_MB_LIB.T6G(SCH_1):PAGE315_I26@PURE_QUANTA.Q_RES(CHIPS)':
 C_PATH='@t6g_mb_lib.t6g(sch_1):page315_i26@pure_quanta.q_res(chips)';

PART_NAME
 PR569 'Q_RES_0402LF-100,1%,1/16W,CHIP,TMP_QCS11002FB22':;

SECTION_NUMBER 1
 '@T6G_MB_LIB.T6G(SCH_1):PAGE315_I21@PURE_QUANTA.Q_RES(CHIPS)':
 C_PATH='@t6g_mb_lib.t6g(sch_1):page315_i21@pure_quanta.q_res(chips)';

PART_NAME
 PR568 'Q_RES_0402LF-100,1%,1/16W,CHIP,TMP_QCS11002FB22':;

SECTION_NUMBER 1
 '@T6G_MB_LIB.T6G(SCH_1):PAGE315_I98@PURE_QUANTA.Q_RES(CHIPS)':
 C_PATH='@t6g_mb_lib.t6g(sch_1):page315_i98@pure_quanta.q_res(chips)';

PART_NAME
 PR567 'Q_RES_0402LF-100,1%,1/16W,CHIP,TMP_QCS11002FB22':;

SECTION_NUMBER 1
 '@T6G_MB_LIB.T6G(SCH_1):PAGE315_I19@PURE_QUANTA.Q_RES(CHIPS)':
 C_PATH='@t6g_mb_lib.t6g(sch_1):page315_i19@pure_quanta.q_res(chips)';

PART_NAME
 PR566 'Q_RES_0402LF-100,1%,1/16W,CHIP,TMP_QCS11002FB22':;

SECTION_NUMBER 1
 '@T6G_MB_LIB.T6G(SCH_1):PAGE315_I22@PURE_QUANTA.Q_RES(CHIPS)':
 C_PATH='@t6g_mb_lib.t6g(sch_1):page315_i22@pure_quanta.q_res(chips)';

PART_NAME
 PR284 'Q_RES_0402LF-1K,1%,1/16W,CHIP,TMP_QCS21002FB24':;

SECTION_NUMBER 1
 '@T6G_MB_LIB.T6G(SCH_1):PAGE315_I92@PURE_QUANTA.Q_RES(CHIPS)':
 C_PATH='@t6g_mb_lib.t6g(sch_1):page315_i92@pure_quanta.q_res(chips)';

PART_NAME
 PR283 'Q_RES_0402LF-1,1%,1/16W,CHIP,CS-1002FB23':;

SECTION_NUMBER 1
 '@T6G_MB_LIB.T6G(SCH_1):PAGE315_I89@PURE_QUANTA.Q_RES(CHIPS)':
 C_PATH='@t6g_mb_lib.t6g(sch_1):page315_i89@pure_quanta.q_res(chips)';

PART_NAME
 PR276 'Q_RES_0402LF-1K,1%,1/16W,EMPTY,TMP_QCS21002FB24':;

SECTION_NUMBER 1
 '@T6G_MB_LIB.T6G(SCH_1):PAGE315_I56@PURE_QUANTA.Q_RES(CHIPS)':
 C_PATH='@t6g_mb_lib.t6g(sch_1):page315_i56@pure_quanta.q_res(chips)',
 CDSVAR_REPCELL_MPS='pure_quanta|Q_res',
 VAR_0_MPS='VALUE|1K|TOLERANCE|1%|WATTAGE|1/16W|PACK_TYPE|0402LF|MATERIAL|CHIP|P~
ART_NUMBER|TMP_QCS21002FB24|STANDARD|End of Design|LIFECYCLE|Comp-Approve|PART_N~
UMBER|CS21002FB24|JEDEC_TYPE|R0402|ALT_SYMBOLS|(R0402-0201)|VALUE|1K|TOL|1%|WATT~
AGE|1/16W|CLASS|DISCRETE|DESCRIPTION|RES CHIP 1K 1/16W +-1% (0402)|COMPONENT_TYP~
E|CHIP0402|LEAD_LENGTH||DFM_EXCLUSION||DAY||VARIANT_DEVICE_TYPE|Q_RES-1K,1%,1/16~
W,0402LF,CHIP,';

PART_NAME
 PR275 'Q_RES_0402LF-0,5%,1/16W,CHIP,CS00002JB38':;

SECTION_NUMBER 1
 '@T6G_MB_LIB.T6G(SCH_1):PAGE315_I13@PURE_QUANTA.Q_RES(CHIPS)':
 C_PATH='@t6g_mb_lib.t6g(sch_1):page315_i13@pure_quanta.q_res(chips)',
 VAR_0_MPS='';

PART_NAME
 PR274 'Q_RES_0402LF-0,5%,1/16W,CHIP,CS00002JB38':;

SECTION_NUMBER 1
 '@T6G_MB_LIB.T6G(SCH_1):PAGE315_I29@PURE_QUANTA.Q_RES(CHIPS)':
 C_PATH='@t6g_mb_lib.t6g(sch_1):page315_i29@pure_quanta.q_res(chips)';

PART_NAME
 PR273 'Q_RES_0402LF-0,5%,1/16W,CHIP,CS00002JB38':;

SECTION_NUMBER 1
 '@T6G_MB_LIB.T6G(SCH_1):PAGE315_I42@PURE_QUANTA.Q_RES(CHIPS)':
 C_PATH='@t6g_mb_lib.t6g(sch_1):page315_i42@pure_quanta.q_res(chips)';

PART_NAME
 PR272 'Q_RES_0402LF-0,5%,1/16W,CHIP,CS00002JB38':;

SECTION_NUMBER 1
 '@T6G_MB_LIB.T6G(SCH_1):PAGE315_I18@PURE_QUANTA.Q_RES(CHIPS)':
 C_PATH='@t6g_mb_lib.t6g(sch_1):page315_i18@pure_quanta.q_res(chips)';

PART_NAME
 PR271 'Q_RES_0402LF-0,5%,1/16W,CHIP,CS00002JB38':;

SECTION_NUMBER 1
 '@T6G_MB_LIB.T6G(SCH_1):PAGE315_I16@PURE_QUANTA.Q_RES(CHIPS)':
 C_PATH='@t6g_mb_lib.t6g(sch_1):page315_i16@pure_quanta.q_res(chips)';

PART_NAME
 PR270 'Q_RES_0402LF-1K,1%,1/16W,CHIP,TMP_QCS21002FB24':;

SECTION_NUMBER 1
 '@T6G_MB_LIB.T6G(SCH_1):PAGE315_I17@PURE_QUANTA.Q_RES(CHIPS)':
 C_PATH='@t6g_mb_lib.t6g(sch_1):page315_i17@pure_quanta.q_res(chips)';

PART_NAME
 PR269 'Q_RES_0402LF-0,5%,1/16W,CHIP,CS00002JB38':;

SECTION_NUMBER 1
 '@T6G_MB_LIB.T6G(SCH_1):PAGE315_I41@PURE_QUANTA.Q_RES(CHIPS)':
 C_PATH='@t6g_mb_lib.t6g(sch_1):page315_i41@pure_quanta.q_res(chips)';

PART_NAME
 PR268 'Q_RES_0402LF-0,5%,1/16W,CHIP,CS00002JB38':;

SECTION_NUMBER 1
 '@T6G_MB_LIB.T6G(SCH_1):PAGE315_I43@PURE_QUANTA.Q_RES(CHIPS)':
 C_PATH='@t6g_mb_lib.t6g(sch_1):page315_i43@pure_quanta.q_res(chips)';

PART_NAME
 PR267 'Q_RES_0402LF-0,5%,1/16W,CHIP,CS00002JB38':;

SECTION_NUMBER 1
 '@T6G_MB_LIB.T6G(SCH_1):PAGE315_I44@PURE_QUANTA.Q_RES(CHIPS)':
 C_PATH='@t6g_mb_lib.t6g(sch_1):page315_i44@pure_quanta.q_res(chips)';

PART_NAME
 PR266 'Q_RES_0402LF-0,5%,1/16W,CHIP,CS00002JB38':;

SECTION_NUMBER 1
 '@T6G_MB_LIB.T6G(SCH_1):PAGE315_I46@PURE_QUANTA.Q_RES(CHIPS)':
 C_PATH='@t6g_mb_lib.t6g(sch_1):page315_i46@pure_quanta.q_res(chips)';

PART_NAME
 PR265 'Q_RES_0402LF-150,1%,1/16W,CHIP,TMP_QCS11502FB21':;

SECTION_NUMBER 1
 '@T6G_MB_LIB.T6G(SCH_1):PAGE315_I45@PURE_QUANTA.Q_RES(CHIPS)':
 C_PATH='@t6g_mb_lib.t6g(sch_1):page315_i45@pure_quanta.q_res(chips)';

PART_NAME
 PR264 'Q_RES_0402LF-0,5%,1/16W,CHIP,CS00002JB38':;

SECTION_NUMBER 1
 '@T6G_MB_LIB.T6G(SCH_1):PAGE315_I51@PURE_QUANTA.Q_RES(CHIPS)':
 C_PATH='@t6g_mb_lib.t6g(sch_1):page315_i51@pure_quanta.q_res(chips)';

PART_NAME
 PR263 'Q_RES_0402LF-0,5%,1/16W,CHIP,CS00002JB38':;

SECTION_NUMBER 1
 '@T6G_MB_LIB.T6G(SCH_1):PAGE315_I50@PURE_QUANTA.Q_RES(CHIPS)':
 C_PATH='@t6g_mb_lib.t6g(sch_1):page315_i50@pure_quanta.q_res(chips)';

PART_NAME
 PR262 'Q_RES_0402LF-1K,1%,1/16W,CHIP,TMP_QCS21002FB24':;

SECTION_NUMBER 1
 '@T6G_MB_LIB.T6G(SCH_1):PAGE315_I52@PURE_QUANTA.Q_RES(CHIPS)':
 C_PATH='@t6g_mb_lib.t6g(sch_1):page315_i52@pure_quanta.q_res(chips)';

PART_NAME
 PR261 'Q_RES_0402LF-0,5%,1/16W,CHIP,CS00002JB38':;

SECTION_NUMBER 1
 '@T6G_MB_LIB.T6G(SCH_1):PAGE315_I11@PURE_QUANTA.Q_RES(CHIPS)':
 C_PATH='@t6g_mb_lib.t6g(sch_1):page315_i11@pure_quanta.q_res(chips)',
 CDSVAR_REPCELL_MPS='pure_quanta|Q_res',
 VAR_0_MPS='VALUE|15K|TOLERANCE|1%|WATTAGE|1/16W|PACK_TYPE|0402LF|MATERIAL|CHIP|~
PART_NUMBER|TMP_QCS31502FB24|STANDARD|End of Design|LIFECYCLE|Comp-Approve|PART_~
NUMBER|CS31502FB24|JEDEC_TYPE|R0402|ALT_SYMBOLS|(R0402-0201)|VALUE|15K|TOL|1%|WA~
TTAGE|1/16W |CLASS|DISCRETE|DESCRIPTION|RES CHIP 15K 1/16W +-1% (0402)|COMPONENT~
_TYPE|CHIP0402|LEAD_LENGTH||DFM_EXCLUSION||DAY||VARIANT_DEVICE_TYPE|Q_RES-15K,1%~
,1/16W,0402LF,CHIP';

PART_NAME
 PR260 'Q_RES_0402LF-0,5%,1/16W,EMPTY,CS00002JB38':;

SECTION_NUMBER 1
 '@T6G_MB_LIB.T6G(SCH_1):PAGE315_I12@PURE_QUANTA.Q_RES(CHIPS)':
 C_PATH='@t6g_mb_lib.t6g(sch_1):page315_i12@pure_quanta.q_res(chips)',
 VAR_0_MPS='';

PART_NAME
 PR259 'Q_RES_0402LF -9.53K,1%,1/16W ,CHIP,TMP_QCS29532FB10':;

SECTION_NUMBER 1
 '@T6G_MB_LIB.T6G(SCH_1):PAGE315_I6@PURE_QUANTA.Q_RES(CHIPS)':
 C_PATH='@t6g_mb_lib.t6g(sch_1):page315_i6@pure_quanta.q_res(chips)',
 CDSVAR_REPCELL_MPS='pure_quanta|Q_res',
 VAR_0_MPS='VALUE|110|TOLERANCE|1%|WATTAGE|1/16W|PACK_TYPE|0402LF|MATERIAL|CHIP|~
PART_NUMBER|TMP_QCS11102FB18|STANDARD|End of Design|LIFECYCLE|Comp-Approve|PART_~
NUMBER|CS11102FB18|JEDEC_TYPE|R0402|ALT_SYMBOLS|(R0402-0201)|VALUE|110|TOL|1%|WA~
TTAGE|1/16W|CLASS|DISCRETE|DESCRIPTION|110ohm 0402|COMPONENT_TYPE|CHIP0402|LEAD_~
LENGTH||DFM_EXCLUSION||DAY||VARIANT_DEVICE_TYPE|Q_RES-110,1%,1/16W,0402LF,CHIP';

PART_NAME
 PR258 'Q_RES_0402LF-28K,1%,1/16W,EMPTY,CS32802FB05':;

SECTION_NUMBER 1
 '@T6G_MB_LIB.T6G(SCH_1):PAGE315_I10@PURE_QUANTA.Q_RES(CHIPS)':
 C_PATH='@t6g_mb_lib.t6g(sch_1):page315_i10@pure_quanta.q_res(chips)',
 CDSVAR_REPCELL_MPS='pure_quanta|Q_res',
 VAR_0_MPS='VALUE|3.32K|TOLERANCE|1%|WATTAGE|1/16W|PACK_TYPE|0402LF|MATERIAL|CHI~
P|PART_NUMBER|CS23322FB20|STANDARD|End of Design|LIFECYCLE|Comp-Approve|PART_NUM~
BER|CS23322FB20|JEDEC_TYPE|R0402|ALT_SYMBOLS|(R0402-0201)|VALUE|3.32K|TOL|1%|WAT~
TAGE|1/16W|CLASS|DISCRETE|DESCRIPTION|RES CHIP 3.32K 1/16W +-1% (0402)|COMPONENT~
_TYPE|CHIP0402|LEAD_LENGTH||DFM_EXCLUSION||DAY|20140826|VARIANT_DEVICE_TYPE|Q_RE~
S-3.32K,1%,1/16W,0402LF,CH';

PART_NAME
 PJ51 'Q_SHORT_SM-EMPTY,SHORT6':;

SECTION_NUMBER 1
 '@T6G_MB_LIB.T6G(SCH_1):PAGE315_I20@PURE_QUANTA.Q_SHORT(CHIPS)':
 C_PATH='@t6g_mb_lib.t6g(sch_1):page315_i20@pure_quanta.q_short(chips)';

PART_NAME
 PJ50 'Q_SHORT_SM-EMPTY,SHORT6':;

SECTION_NUMBER 1
 '@T6G_MB_LIB.T6G(SCH_1):PAGE315_I33@PURE_QUANTA.Q_SHORT(CHIPS)':
 C_PATH='@t6g_mb_lib.t6g(sch_1):page315_i33@pure_quanta.q_short(chips)';

PART_NAME
 PC1292 'Q_CAP_0402-470PF,50V,10%,X7R,TMP_QCH14706KB18':;

SECTION_NUMBER 1
 '@T6G_MB_LIB.T6G(SCH_1):PAGE315_I68@PURE_QUANTA.Q_CAP(CHIPS)':
 C_PATH='@t6g_mb_lib.t6g(sch_1):page315_i68@pure_quanta.q_cap(chips)',
 CDSVAR_REPCELL_MPS='pure_quanta|Q_cap',
 VAR_0_MPS='VALUE|0.01UF|VOLTAGE|25V|TOLERANCE|10%|PACK_TYPE|0402|MATERIAL|X7R|P~
ART_NUMBER|TMP_QCH31004KB17|STANDARD|End of Design|LIFECYCLE|Comp-Approve|ASS_PA~
RT||PART_NUMBER|CH31004KB17|JEDEC_TYPE|C0402|ALT_SYMBOLS|(C0402-0201)|VALUE|0.01~
UF|RATED_VOLTAGE|25V|TOL|10%|CLASS|DISCRETE|DESCRIPTION|CAP CHIP 0.01U 25V(+-10%~
,X7R,0402)|COMPONENT_TYPE|CHIP0402|LEAD_LENGTH||LPID||DATE|20100528|VARIANT_DEVI~
CE_TYPE|Q_CAP-0.01UF,25V,10%,0402,X7R,';

PART_NAME
 PC1193 'Q_CAP_C0402-1UF,16V,10%,X6S,CH5103KEB01':;

SECTION_NUMBER 1
 '@T6G_MB_LIB.T6G(SCH_1):PAGE315_I81@PURE_QUANTA.Q_CAP(CHIPS)':
 C_PATH='@t6g_mb_lib.t6g(sch_1):page315_i81@pure_quanta.q_cap(chips)';

PART_NAME
 PC478 'Q_CAP_C0402-1UF,16V,10%,X6S,CH5103KEB01':;

SECTION_NUMBER 1
 '@T6G_MB_LIB.T6G(SCH_1):PAGE315_I83@PURE_QUANTA.Q_CAP(CHIPS)':
 C_PATH='@t6g_mb_lib.t6g(sch_1):page315_i83@pure_quanta.q_cap(chips)';

PART_NAME
 PC477 'Q_CAP_0402-4.7UF,6.3V,20%,X6S,CH5471MEB01':;

SECTION_NUMBER 1
 '@T6G_MB_LIB.T6G(SCH_1):PAGE315_I80@PURE_QUANTA.Q_CAP(CHIPS)':
 C_PATH='@t6g_mb_lib.t6g(sch_1):page315_i80@pure_quanta.q_cap(chips)',
 CDSVAR_REPCELL_MPS='pure_quanta|Q_cap',
 VAR_0_MPS='VALUE|4.7UF|VOLTAGE|6.3V|TOLERANCE|20%|PACK_TYPE|0402|MATERIAL|EMPTY~
|PART_NUMBER|CH5471MEB01|STANDARD||LIFECYCLE||ASS_PART||PART_NUMBER|CH5471MEB01|~
JEDEC_TYPE|C0402|ALT_SYMBOLS|(C0402_OCTAGON,C0402_OCTAGONXA,C0402-0201)|VALUE|NA~
|RATED_VOLTAGE|6.3V|TOL|20%|CLASS|IO|DESCRIPTION|CAP CHIP 4.7UF 6.3V(+-20%,X6S,0~
402)|COMPONENT_TYPE|CHIP0402|LEAD_LENGTH||LPID||DATE|20151211|VARIANT_DEVICE_TYP~
E|Q_CAP-4.7UF,6.3V,20%,0402,EMPT';

PART_NAME
 PC476 'Q_CAP_C0402-100NF,50V,10%,EMPTY,CH4106K1B01':;

SECTION_NUMBER 1
 '@T6G_MB_LIB.T6G(SCH_1):PAGE315_I82@PURE_QUANTA.Q_CAP(CHIPS)':
 C_PATH='@t6g_mb_lib.t6g(sch_1):page315_i82@pure_quanta.q_cap(chips)';

PART_NAME
 PC475 'Q_CAP_0402-470PF,50V,10%,X7R,TMP_QCH14706KB18':;

SECTION_NUMBER 1
 '@T6G_MB_LIB.T6G(SCH_1):PAGE315_I67@PURE_QUANTA.Q_CAP(CHIPS)':
 C_PATH='@t6g_mb_lib.t6g(sch_1):page315_i67@pure_quanta.q_cap(chips)',
 CDSVAR_REPCELL_MPS='pure_quanta|Q_cap',
 VAR_0_MPS='VALUE|0.01UF|VOLTAGE|25V|TOLERANCE|10%|PACK_TYPE|0402|MATERIAL|X7R|P~
ART_NUMBER|TMP_QCH31004KB17|STANDARD|End of Design|LIFECYCLE|Comp-Approve|ASS_PA~
RT||PART_NUMBER|CH31004KB17|JEDEC_TYPE|C0402|ALT_SYMBOLS|(C0402-0201)|VALUE|0.01~
UF|RATED_VOLTAGE|25V|TOL|10%|CLASS|DISCRETE|DESCRIPTION|CAP CHIP 0.01U 25V(+-10%~
,X7R,0402)|COMPONENT_TYPE|CHIP0402|LEAD_LENGTH||LPID||DATE|20100528|VARIANT_DEVI~
CE_TYPE|Q_CAP-0.01UF,25V,10%,0402,X7R,';

PART_NAME
 PC474 'Q_CAP_0402-0.1UF,25V,10%,X7R,CH4104K1B00':;

SECTION_NUMBER 1
 '@T6G_MB_LIB.T6G(SCH_1):PAGE315_I57@PURE_QUANTA.Q_CAP(CHIPS)':
 C_PATH='@t6g_mb_lib.t6g(sch_1):page315_i57@pure_quanta.q_cap(chips)';

PART_NAME
 PC473 'Q_CAP_0402-1000PF,50V,5%,EMPTY,TMP_QCH21006JB10':;

SECTION_NUMBER 1
 '@T6G_MB_LIB.T6G(SCH_1):PAGE315_I58@PURE_QUANTA.Q_CAP(CHIPS)':
 C_PATH='@t6g_mb_lib.t6g(sch_1):page315_i58@pure_quanta.q_cap(chips)';

PART_NAME
 PC472 'Q_CAP_0402-1000PF,50V,5%,X7R,TMP_QCH21006JB10':;

SECTION_NUMBER 1
 '@T6G_MB_LIB.T6G(SCH_1):PAGE315_I59@PURE_QUANTA.Q_CAP(CHIPS)':
 C_PATH='@t6g_mb_lib.t6g(sch_1):page315_i59@pure_quanta.q_cap(chips)';

PART_NAME
 PC471 'Q_CAP_0402-1000PF,50V,5%,EMPTY,TMP_QCH21006JB10':;

SECTION_NUMBER 1
 '@T6G_MB_LIB.T6G(SCH_1):PAGE315_I76@PURE_QUANTA.Q_CAP(CHIPS)':
 C_PATH='@t6g_mb_lib.t6g(sch_1):page315_i76@pure_quanta.q_cap(chips)';

PART_NAME
 PC470 'Q_CAP_0402-1000PF,50V,5%,X7R,TMP_QCH21006JB10':;

SECTION_NUMBER 1
 '@T6G_MB_LIB.T6G(SCH_1):PAGE315_I74@PURE_QUANTA.Q_CAP(CHIPS)':
 C_PATH='@t6g_mb_lib.t6g(sch_1):page315_i74@pure_quanta.q_cap(chips)';

PART_NAME
 PC469 'Q_CAP_0402-3300PF,50V,10%,X7R,TMP_QCH2336K1B12':;

SECTION_NUMBER 1
 '@T6G_MB_LIB.T6G(SCH_1):PAGE315_I64@PURE_QUANTA.Q_CAP(CHIPS)':
 C_PATH='@t6g_mb_lib.t6g(sch_1):page315_i64@pure_quanta.q_cap(chips)',
 CDSVAR_REPCELL_MPS='pure_quanta|Q_cap',
 VAR_0_MPS='VALUE|3300PF|VOLTAGE|50V|TOLERANCE|10%|PACK_TYPE|C0402|MATERIAL|EMPT~
Y|PART_NUMBER|CH2336K1B06|STANDARD||LIFECYCLE||ASS_PART||PART_NUMBER|CH2336K1B06~
|JEDEC_TYPE|C0402|ALT_SYMBOLS|(C0402-0201)|VALUE|NA|RATED_VOLTAGE|50V|TOL|10%|CL~
ASS|IO|DESCRIPTION|CAP CHIP 3300P 50V(+-10%,X7R,0402)MUR|COMPONENT_TYPE|CHIP0402~
|LEAD_LENGTH||LPID||DATE|20150617|VARIANT_DEVICE_TYPE|Q_CAP-3300PF,50V,10%,C0402~
,EMP';

PART_NAME
 PC468 'Q_CAP_0402-3300PF,50V,10%,X7R,TMP_QCH2336K1B12':;

SECTION_NUMBER 1
 '@T6G_MB_LIB.T6G(SCH_1):PAGE315_I65@PURE_QUANTA.Q_CAP(CHIPS)':
 C_PATH='@t6g_mb_lib.t6g(sch_1):page315_i65@pure_quanta.q_cap(chips)',
 CDSVAR_REPCELL_MPS='pure_quanta|Q_cap',
 VAR_0_MPS='VALUE|3300PF|VOLTAGE|50V|TOLERANCE|10%|PACK_TYPE|C0402|MATERIAL|EMPT~
Y|PART_NUMBER|CH2336K1B06|STANDARD||LIFECYCLE||ASS_PART||PART_NUMBER|CH2336K1B06~
|JEDEC_TYPE|C0402|ALT_SYMBOLS|(C0402-0201)|VALUE|NA|RATED_VOLTAGE|50V|TOL|10%|CL~
ASS|IO|DESCRIPTION|CAP CHIP 3300P 50V(+-10%,X7R,0402)MUR|COMPONENT_TYPE|CHIP0402~
|LEAD_LENGTH||LPID||DATE|20150617|VARIANT_DEVICE_TYPE|Q_CAP-3300PF,50V,10%,C0402~
,EMP';

PART_NAME
 PC467 'Q_CAP_0402-0.1UF,25V,10%,EMPTY,CH4104K1B00':;

SECTION_NUMBER 1
 '@T6G_MB_LIB.T6G(SCH_1):PAGE315_I54@PURE_QUANTA.Q_CAP(CHIPS)':
 C_PATH='@t6g_mb_lib.t6g(sch_1):page315_i54@pure_quanta.q_cap(chips)',
 VAR_0_MPS='';

PART_NAME
 PU51_P1_2 'RAA2213404GNPHB0-RAA2213404GNP#HB0,SMLF,IC,AL221340000':;

SECTION_NUMBER 1
 '@T6G_MB_LIB.T6G(SCH_1):PAGE316_I12@PURE_QUANTA.RAA2213404GNPHB0(CHIPS)':
 C_PATH='@t6g_mb_lib.t6g(sch_1):page316_i12@pure_quanta.raa2213404gnphb0(chips)',
 CDSVAR_REPCELL_MPS='pure_quanta|mp86950glvtz',
 VAR_0_MPS='VAR_REPLACED|RAA2213404GNPHB0|VAR_PARTNAME|MP86950GLVTZ|VALUE|MP8695~
0GLVT-Z|PART_TYPE|SMLF|MATERIAL|IC|PART_NUMBER|AL086950A00|STANDARD||LIFECYCLE||~
PART_NUMBER|AL086950A00|JEDEC_TYPE|LGA17_5X4|DESCRIPTION|IC OTHER(27P)MP86950GLV~
T-Z(LGA)|MANUFTR|MPS|MANUF_PN|MP86950GLVT-Z|RD_CMPLS_LVL|EP(V1)|CMPLS_LVL||FROM_~
PJ|S69-CARSON|CLASS|IC|DIP_SMD||DATA|MPS_MP86950GLVT-Z.pdf|EE_CHECK_LIST||FP_ECN~
||PSL||CREATOR||STATUS||MSD|Level-3|ESD_CDM|NA|ESD_HBM|NA|ESD_MM|NA|PIN_LENGTH_S~
HORT_PIN|0 MILS|PIN_LENGTH_LONG_PIN|0 MILS|CREATEDAY|20180807|VARIANT_DEVICE_TYP~
E|MP86950GLVTZ-MP86950GLVT-Z,SML';

PART_NAME
 PU50_P1_1 'RAA2213404GNPHB0-RAA2213404GNP#HB0,SMLF,IC,AL221340000':;

SECTION_NUMBER 1
 '@T6G_MB_LIB.T6G(SCH_1):PAGE316_I17@PURE_QUANTA.RAA2213404GNPHB0(CHIPS)':
 C_PATH='@t6g_mb_lib.t6g(sch_1):page316_i17@pure_quanta.raa2213404gnphb0(chips)',
 CDSVAR_REPCELL_MPS='pure_quanta|mp86950glvtz',
 VAR_0_MPS='VAR_REPLACED|RAA2213404GNPHB0|VAR_PARTNAME|MP86950GLVTZ|VALUE|MP8695~
0GLVT-Z|PART_TYPE|SMLF|MATERIAL|IC|PART_NUMBER|AL086950A00|STANDARD||LIFECYCLE||~
PART_NUMBER|AL086950A00|JEDEC_TYPE|LGA17_5X4|DESCRIPTION|IC OTHER(27P)MP86950GLV~
T-Z(LGA)|MANUFTR|MPS|MANUF_PN|MP86950GLVT-Z|RD_CMPLS_LVL|EP(V1)|CMPLS_LVL||FROM_~
PJ|S69-CARSON|CLASS|IC|DIP_SMD||DATA|MPS_MP86950GLVT-Z.pdf|EE_CHECK_LIST||FP_ECN~
||PSL||CREATOR||STATUS||MSD|Level-3|ESD_CDM|NA|ESD_HBM|NA|ESD_MM|NA|PIN_LENGTH_S~
HORT_PIN|0 MILS|PIN_LENGTH_LONG_PIN|0 MILS|CREATEDAY|20180807|VARIANT_DEVICE_TYP~
E|MP86950GLVTZ-MP86950GLVT-Z,SML';

PART_NAME
 PR1797 'Q_RES_0402LF-0,5%,1/16W,CHIP,CS00002JB38':;

SECTION_NUMBER 1
 '@T6G_MB_LIB.T6G(SCH_1):PAGE316_I31@PURE_QUANTA.Q_RES(CHIPS)':
 C_PATH='@t6g_mb_lib.t6g(sch_1):page316_i31@pure_quanta.q_res(chips)',
 CDSVAR_REPCELL_MPS='pure_quanta|Q_res',
 VAR_0_MPS='VALUE|0|TOLERANCE|5%|WATTAGE|1/16W|PACK_TYPE|0402LF|MATERIAL|EMPTY|P~
ART_NUMBER|CS00002JB38|STANDARD|End of Design|LIFECYCLE|Comp-Approve|PART_NUMBER~
|CS00002JB38|JEDEC_TYPE|R0402|ALT_SYMBOLS|(R0402-0201)|VALUE|0|TOL|5%|WATTAGE|1/~
16W|CLASS|IO|DESCRIPTION|RESISTOR CHIP 0 1/16W +-5%(0402)|COMPONENT_TYPE|CHIP040~
2|LEAD_LENGTH||DFM_EXCLUSION||DAY|20100618|VARIANT_DEVICE_TYPE|Q_RES-0,5%,1/16W,~
0402LF,EMPTY,';

PART_NAME
 PR1796 'Q_RES_0402LF-0,5%,1/16W,CHIP,CS00002JB38':;

SECTION_NUMBER 1
 '@T6G_MB_LIB.T6G(SCH_1):PAGE316_I49@PURE_QUANTA.Q_RES(CHIPS)':
 C_PATH='@t6g_mb_lib.t6g(sch_1):page316_i49@pure_quanta.q_res(chips)',
 CDSVAR_REPCELL_MPS='pure_quanta|Q_res',
 VAR_0_MPS='VALUE|0|TOLERANCE|5%|WATTAGE|1/16W|PACK_TYPE|0402LF|MATERIAL|EMPTY|P~
ART_NUMBER|CS00002JB38|STANDARD|End of Design|LIFECYCLE|Comp-Approve|PART_NUMBER~
|CS00002JB38|JEDEC_TYPE|R0402|ALT_SYMBOLS|(R0402-0201)|VALUE|0|TOL|5%|WATTAGE|1/~
16W|CLASS|IO|DESCRIPTION|RESISTOR CHIP 0 1/16W +-5%(0402)|COMPONENT_TYPE|CHIP040~
2|LEAD_LENGTH||DFM_EXCLUSION||DAY|20100618|VARIANT_DEVICE_TYPE|Q_RES-0,5%,1/16W,~
0402LF,EMPTY,';

PART_NAME
 PR1795 'Q_RES_0402LF-4.7,1%,1/16W,CHIP,CS-4702FB19':;

SECTION_NUMBER 1
 '@T6G_MB_LIB.T6G(SCH_1):PAGE316_I35@PURE_QUANTA.Q_RES(CHIPS)':
 C_PATH='@t6g_mb_lib.t6g(sch_1):page316_i35@pure_quanta.q_res(chips)',
 CDSVAR_REPCELL_MPS='pure_quanta|Q_res',
 VAR_0_MPS='VALUE|0|TOLERANCE|5%|WATTAGE|1/16W|PACK_TYPE|0402LF|MATERIAL|CHIP|PA~
RT_NUMBER|CS00002JB38|STANDARD|End of Design|LIFECYCLE|Comp-Approve|PART_NUMBER|~
CS00002JB38|JEDEC_TYPE|R0402|ALT_SYMBOLS|(R0402-0201)|VALUE|0|TOL|5%|WATTAGE|1/1~
6W|CLASS|DISCRETE|DESCRIPTION|RESISTOR CHIP 0 1/16W +-5%(0402)|COMPONENT_TYPE|CH~
IP0402|LEAD_LENGTH||DFM_EXCLUSION||DAY|20100618|VARIANT_DEVICE_TYPE|Q_RES-0,5%,1~
/16W,0402LF,CHIP,C';

PART_NAME
 PR1794 'Q_RES_0402LF-4.7,1%,1/16W,CHIP,CS-4702FB19':;

SECTION_NUMBER 1
 '@T6G_MB_LIB.T6G(SCH_1):PAGE316_I52@PURE_QUANTA.Q_RES(CHIPS)':
 C_PATH='@t6g_mb_lib.t6g(sch_1):page316_i52@pure_quanta.q_res(chips)',
 CDSVAR_REPCELL_MPS='pure_quanta|Q_res',
 VAR_0_MPS='VALUE|0|TOLERANCE|5%|WATTAGE|1/16W|PACK_TYPE|0402LF|MATERIAL|CHIP|PA~
RT_NUMBER|CS00002JB38|STANDARD|End of Design|LIFECYCLE|Comp-Approve|PART_NUMBER|~
CS00002JB38|JEDEC_TYPE|R0402|ALT_SYMBOLS|(R0402-0201)|VALUE|0|TOL|5%|WATTAGE|1/1~
6W|CLASS|DISCRETE|DESCRIPTION|RESISTOR CHIP 0 1/16W +-5%(0402)|COMPONENT_TYPE|CH~
IP0402|LEAD_LENGTH||DFM_EXCLUSION||DAY|20100618|VARIANT_DEVICE_TYPE|Q_RES-0,5%,1~
/16W,0402LF,CHIP,C';

PART_NAME
 PR1727 'Q_RES_0402LF-8.87K,1%,1/16W,EMPTY,CS28872FB01':;

SECTION_NUMBER 1
 '@T6G_MB_LIB.T6G(SCH_1):PAGE316_I3@PURE_QUANTA.Q_RES(CHIPS)':
 C_PATH='@t6g_mb_lib.t6g(sch_1):page316_i3@pure_quanta.q_res(chips)';

PART_NAME
 PR1726 'Q_RES_0402LF-8.87K,1%,1/16W,EMPTY,CS28872FB01':;

SECTION_NUMBER 1
 '@T6G_MB_LIB.T6G(SCH_1):PAGE316_I7@PURE_QUANTA.Q_RES(CHIPS)':
 C_PATH='@t6g_mb_lib.t6g(sch_1):page316_i7@pure_quanta.q_res(chips)';

PART_NAME
 PR677 'Q_RES_0402LF-0,5%,1/16W,EMPTY,CS00002JB38':;

SECTION_NUMBER 1
 '@T6G_MB_LIB.T6G(SCH_1):PAGE316_I28@PURE_QUANTA.Q_RES(CHIPS)':
 C_PATH='@t6g_mb_lib.t6g(sch_1):page316_i28@pure_quanta.q_res(chips)',
 CDSVAR_REPCELL_MPS='pure_quanta|Q_res',
 VAR_0_MPS='VALUE|0|TOLERANCE|5%|WATTAGE|1/16W|PACK_TYPE|0402LF|MATERIAL|CHIP|PA~
RT_NUMBER|CS00002JB38|STANDARD|End of Design|LIFECYCLE|Comp-Approve|PART_NUMBER|~
CS00002JB38|JEDEC_TYPE|R0402|ALT_SYMBOLS|(R0402-0201)|VALUE|0|TOL|5%|WATTAGE|1/1~
6W|CLASS|DISCRETE|DESCRIPTION|RESISTOR CHIP 0 1/16W +-5%(0402)|COMPONENT_TYPE|CH~
IP0402|LEAD_LENGTH||DFM_EXCLUSION||DAY|20100618|VARIANT_DEVICE_TYPE|Q_RES-0,5%,1~
/16W,0402LF,CHIP,C';

PART_NAME
 PR668 'Q_RES_0402LF-0,5%,1/16W,CHIP,CS00002JB38':;

SECTION_NUMBER 1
 '@T6G_MB_LIB.T6G(SCH_1):PAGE316_I20@PURE_QUANTA.Q_RES(CHIPS)':
 C_PATH='@t6g_mb_lib.t6g(sch_1):page316_i20@pure_quanta.q_res(chips)',
 CDSVAR_REPCELL_MPS='pure_quanta|Q_res',
 VAR_0_MPS='VALUE|0|TOLERANCE|5%|WATTAGE|1/16W|PACK_TYPE|0402LF|MATERIAL|EMPTY|P~
ART_NUMBER|CS00002JB38|STANDARD|End of Design|LIFECYCLE|Comp-Approve|PART_NUMBER~
|CS00002JB38|JEDEC_TYPE|R0402|ALT_SYMBOLS|(R0402-0201)|VALUE|0|TOL|5%|WATTAGE|1/~
16W|CLASS|IO|DESCRIPTION|RESISTOR CHIP 0 1/16W +-5%(0402)|COMPONENT_TYPE|CHIP040~
2|LEAD_LENGTH||DFM_EXCLUSION||DAY|20100618|VARIANT_DEVICE_TYPE|Q_RES-0,5%,1/16W,~
0402LF,EMPTY,';

PART_NAME
 PR255 'Q_RES_0402LF-2.2,1%,1/16W,CHIP,CS-2202FB00':;

SECTION_NUMBER 1
 '@T6G_MB_LIB.T6G(SCH_1):PAGE316_I15@PURE_QUANTA.Q_RES(CHIPS)':
 C_PATH='@t6g_mb_lib.t6g(sch_1):page316_i15@pure_quanta.q_res(chips)';

PART_NAME
 PR254 'Q_RES_0402LF-2.2,1%,1/16W,CHIP,CS-2202FB00':;

SECTION_NUMBER 1
 '@T6G_MB_LIB.T6G(SCH_1):PAGE316_I27@PURE_QUANTA.Q_RES(CHIPS)':
 C_PATH='@t6g_mb_lib.t6g(sch_1):page316_i27@pure_quanta.q_res(chips)';

PART_NAME
 PL23 'Q_INDUCTOR_SMLF-100NH/16A,IND,CV+10G0MZ04':;

SECTION_NUMBER 1
 '@T6G_MB_LIB.T6G(SCH_1):PAGE316_I65@PURE_QUANTA.Q_INDUCTOR(CHIPS)':
 C_PATH='@t6g_mb_lib.t6g(sch_1):page316_i65@pure_quanta.q_inductor(chips)';

PART_NAME
 PL22 'Q_INDUCTOR_SMLF-120NH/94A,IND,CV+12^0KZ16':;

SECTION_NUMBER 1
 '@T6G_MB_LIB.T6G(SCH_1):PAGE316_I33@PURE_QUANTA.Q_INDUCTOR(CHIPS)':
 C_PATH='@t6g_mb_lib.t6g(sch_1):page316_i33@pure_quanta.q_inductor(chips)';

PART_NAME
 PL21 'Q_INDUCTOR_SMLF-120NH/94A,IND,CV+12^0KZ16':;

SECTION_NUMBER 1
 '@T6G_MB_LIB.T6G(SCH_1):PAGE316_I55@PURE_QUANTA.Q_INDUCTOR(CHIPS)':
 C_PATH='@t6g_mb_lib.t6g(sch_1):page316_i55@pure_quanta.q_inductor(chips)';

PART_NAME
 PC1596 'Q_CAPP_THLF-560UF,2.5V,20%,OSCON,CC7560JMD18':;

SECTION_NUMBER 1
 '@T6G_MB_LIB.T6G(SCH_1):PAGE316_I69@PURE_QUANTA.Q_CAPP(CHIPS)':
 C_PATH='@t6g_mb_lib.t6g(sch_1):page316_i69@pure_quanta.q_capp(chips)';

PART_NAME
 PC1595 'Q_CAPP_THLF-560UF,2.5V,20%,OSCON,CC7560JMD18':;

SECTION_NUMBER 1
 '@T6G_MB_LIB.T6G(SCH_1):PAGE316_I67@PURE_QUANTA.Q_CAPP(CHIPS)':
 C_PATH='@t6g_mb_lib.t6g(sch_1):page316_i67@pure_quanta.q_capp(chips)';

PART_NAME
 PC1594 'Q_CAPP_SMLF-330UF,2V,35%,SPCAP,CH733RY8807':;

SECTION_NUMBER 1
 '@T6G_MB_LIB.T6G(SCH_1):PAGE316_I68@PURE_QUANTA.Q_CAPP(CHIPS)':
 C_PATH='@t6g_mb_lib.t6g(sch_1):page316_i68@pure_quanta.q_capp(chips)';

PART_NAME
 PC1593 'Q_CAPP_THLF-560UF,2.5V,20%,OSCON,CC7560JMD18':;

SECTION_NUMBER 1
 '@T6G_MB_LIB.T6G(SCH_1):PAGE316_I47@PURE_QUANTA.Q_CAPP(CHIPS)':
 C_PATH='@t6g_mb_lib.t6g(sch_1):page316_i47@pure_quanta.q_capp(chips)';

PART_NAME
 PC1588 'Q_CAPP_SMLF-330UF,2V,35%,SPCAP,CH733RY8807':;

SECTION_NUMBER 1
 '@T6G_MB_LIB.T6G(SCH_1):PAGE316_I48@PURE_QUANTA.Q_CAPP(CHIPS)':
 C_PATH='@t6g_mb_lib.t6g(sch_1):page316_i48@pure_quanta.q_capp(chips)';

PART_NAME
 PC1365 'Q_CAP_0402-0.1UF,25V,10%,X7R,CH4104K1B00':;

SECTION_NUMBER 1
 '@T6G_MB_LIB.T6G(SCH_1):PAGE316_I11@PURE_QUANTA.Q_CAP(CHIPS)':
 C_PATH='@t6g_mb_lib.t6g(sch_1):page316_i11@pure_quanta.q_cap(chips)',
 CDSVAR_REPCELL_MPS='pure_quanta|Q_cap',
 VAR_0_MPS='VALUE|0.1UF|VOLTAGE|25V|TOLERANCE|10%|PACK_TYPE|0402|MATERIAL|EMPTY|~
PART_NUMBER|CH4104K1B00|STANDARD||LIFECYCLE||ASS_PART||PART_NUMBER|CH4104K1B00|J~
EDEC_TYPE|C0402|ALT_SYMBOLS|(C0402_OCTAGONXA,C0402-0201)|VALUE|NA|RATED_VOLTAGE|~
25V|TOL|10%|CLASS|IO|DESCRIPTION|CAP CHIP 0.1U 25V(+-10%,X7R,0402)|COMPONENT_TYP~
E|CHIP0402|LEAD_LENGTH||LPID||DATE|20160113|VARIANT_DEVICE_TYPE|Q_CAP-0.1UF,25V,~
10%,0402,EMPTY';

PART_NAME
 PC1364 'Q_CAP_0402-0.1UF,25V,10%,X7R,CH4104K1B00':;

SECTION_NUMBER 1
 '@T6G_MB_LIB.T6G(SCH_1):PAGE316_I24@PURE_QUANTA.Q_CAP(CHIPS)':
 C_PATH='@t6g_mb_lib.t6g(sch_1):page316_i24@pure_quanta.q_cap(chips)',
 CDSVAR_REPCELL_MPS='pure_quanta|Q_cap',
 VAR_0_MPS='VALUE|0.1UF|VOLTAGE|25V|TOLERANCE|10%|PACK_TYPE|0402|MATERIAL|EMPTY|~
PART_NUMBER|CH4104K1B00|STANDARD||LIFECYCLE||ASS_PART||PART_NUMBER|CH4104K1B00|J~
EDEC_TYPE|C0402|ALT_SYMBOLS|(C0402_OCTAGONXA,C0402-0201)|VALUE|NA|RATED_VOLTAGE|~
25V|TOL|10%|CLASS|IO|DESCRIPTION|CAP CHIP 0.1U 25V(+-10%,X7R,0402)|COMPONENT_TYP~
E|CHIP0402|LEAD_LENGTH||LPID||DATE|20160113|VARIANT_DEVICE_TYPE|Q_CAP-0.1UF,25V,~
10%,0402,EMPTY';

PART_NAME
 PC461 'Q_CAPP_THLF-270UF,16V,20%,OSCON,CC72703MD33':;

SECTION_NUMBER 1
 '@T6G_MB_LIB.T6G(SCH_1):PAGE316_I75@PURE_QUANTA.Q_CAPP(CHIPS)':
 C_PATH='@t6g_mb_lib.t6g(sch_1):page316_i75@pure_quanta.q_capp(chips)';

PART_NAME
 PC460 'Q_CAPP_THLF-270UF,16V,20%,OSCON,CC72703MD33':;

SECTION_NUMBER 1
 '@T6G_MB_LIB.T6G(SCH_1):PAGE316_I74@PURE_QUANTA.Q_CAPP(CHIPS)':
 C_PATH='@t6g_mb_lib.t6g(sch_1):page316_i74@pure_quanta.q_capp(chips)';

PART_NAME
 PC458_P1_2 'Q_CAP_0805-22UF,4V,20%,X6S,TMP_QCH622KMEA01':;

SECTION_NUMBER 1
 '@T6G_MB_LIB.T6G(SCH_1):PAGE316_I43@PURE_QUANTA.Q_CAP(CHIPS)':
 C_PATH='@t6g_mb_lib.t6g(sch_1):page316_i43@pure_quanta.q_cap(chips)';

PART_NAME
 PC457_P1_1 'Q_CAP_0805-22UF,4V,20%,X6S,TMP_QCH622KMEA01':;

SECTION_NUMBER 1
 '@T6G_MB_LIB.T6G(SCH_1):PAGE316_I62@PURE_QUANTA.Q_CAP(CHIPS)':
 C_PATH='@t6g_mb_lib.t6g(sch_1):page316_i62@pure_quanta.q_cap(chips)';

PART_NAME
 PC456_P1_2 'Q_CAP_0805-22UF,4V,20%,X6S,TMP_QCH622KMEA01':;

SECTION_NUMBER 1
 '@T6G_MB_LIB.T6G(SCH_1):PAGE316_I41@PURE_QUANTA.Q_CAP(CHIPS)':
 C_PATH='@t6g_mb_lib.t6g(sch_1):page316_i41@pure_quanta.q_cap(chips)';

PART_NAME
 PC455_P1_1 'Q_CAP_0805-22UF,4V,20%,X6S,TMP_QCH622KMEA01':;

SECTION_NUMBER 1
 '@T6G_MB_LIB.T6G(SCH_1):PAGE316_I59@PURE_QUANTA.Q_CAP(CHIPS)':
 C_PATH='@t6g_mb_lib.t6g(sch_1):page316_i59@pure_quanta.q_cap(chips)';

PART_NAME
 PC452_P1_1 'Q_CAP_C0402-100NF,50V,10%,X7R,CH4106K1B01':;

SECTION_NUMBER 1
 '@T6G_MB_LIB.T6G(SCH_1):PAGE316_I58@PURE_QUANTA.Q_CAP(CHIPS)':
 C_PATH='@t6g_mb_lib.t6g(sch_1):page316_i58@pure_quanta.q_cap(chips)';

PART_NAME
 PC451_P1_2 'Q_CAP_C0805-22UF,16V,20%,X6S,CH6223MEA00':;

SECTION_NUMBER 1
 '@T6G_MB_LIB.T6G(SCH_1):PAGE316_I39@PURE_QUANTA.Q_CAP(CHIPS)':
 C_PATH='@t6g_mb_lib.t6g(sch_1):page316_i39@pure_quanta.q_cap(chips)';

PART_NAME
 PC450_P1_1 'Q_CAP_C0805-22UF,16V,20%,X6S,CH6223MEA00':;

SECTION_NUMBER 1
 '@T6G_MB_LIB.T6G(SCH_1):PAGE316_I57@PURE_QUANTA.Q_CAP(CHIPS)':
 C_PATH='@t6g_mb_lib.t6g(sch_1):page316_i57@pure_quanta.q_cap(chips)';

PART_NAME
 PC449_P1_2 'Q_CAP_C0805-22UF,16V,20%,X6S,CH6223MEA00':;

SECTION_NUMBER 1
 '@T6G_MB_LIB.T6G(SCH_1):PAGE316_I38@PURE_QUANTA.Q_CAP(CHIPS)':
 C_PATH='@t6g_mb_lib.t6g(sch_1):page316_i38@pure_quanta.q_cap(chips)';

PART_NAME
 PC448_P1_1 'Q_CAP_C0805-22UF,16V,20%,X6S,CH6223MEA00':;

SECTION_NUMBER 1
 '@T6G_MB_LIB.T6G(SCH_1):PAGE316_I56@PURE_QUANTA.Q_CAP(CHIPS)':
 C_PATH='@t6g_mb_lib.t6g(sch_1):page316_i56@pure_quanta.q_cap(chips)';

PART_NAME
 PC447 'Q_CAP_C0402-100NF,50V,10%,X7R,CH4106K1B01':;

SECTION_NUMBER 1
 '@T6G_MB_LIB.T6G(SCH_1):PAGE316_I40@PURE_QUANTA.Q_CAP(CHIPS)':
 C_PATH='@t6g_mb_lib.t6g(sch_1):page316_i40@pure_quanta.q_cap(chips)';

PART_NAME
 PC446 'Q_CAP_C0402-100NF,50V,10%,X7R,CH4106K1B01':;

SECTION_NUMBER 1
 '@T6G_MB_LIB.T6G(SCH_1):PAGE316_I54@PURE_QUANTA.Q_CAP(CHIPS)':
 C_PATH='@t6g_mb_lib.t6g(sch_1):page316_i54@pure_quanta.q_cap(chips)';

PART_NAME
 PC445_P1_2 'Q_CAP_C0402-1UF,16V,10%,X6S,CH5103KEB01':;

SECTION_NUMBER 1
 '@T6G_MB_LIB.T6G(SCH_1):PAGE316_I36@PURE_QUANTA.Q_CAP(CHIPS)':
 C_PATH='@t6g_mb_lib.t6g(sch_1):page316_i36@pure_quanta.q_cap(chips)';

PART_NAME
 PC444_P1_1 'Q_CAP_C0402-1UF,16V,10%,X6S,CH5103KEB01':;

SECTION_NUMBER 1
 '@T6G_MB_LIB.T6G(SCH_1):PAGE316_I51@PURE_QUANTA.Q_CAP(CHIPS)':
 C_PATH='@t6g_mb_lib.t6g(sch_1):page316_i51@pure_quanta.q_cap(chips)';

PART_NAME
 PC443_P1_2 'Q_CAP_0402-3300PF,50V,10%,X7R,TMP_QCH2336K1B12':;

SECTION_NUMBER 1
 '@T6G_MB_LIB.T6G(SCH_1):PAGE316_I34@PURE_QUANTA.Q_CAP(CHIPS)':
 C_PATH='@t6g_mb_lib.t6g(sch_1):page316_i34@pure_quanta.q_cap(chips)';

PART_NAME
 PC442_P1_1 'Q_CAP_0402-3300PF,50V,10%,X7R,TMP_QCH2336K1B12':;

SECTION_NUMBER 1
 '@T6G_MB_LIB.T6G(SCH_1):PAGE316_I50@PURE_QUANTA.Q_CAP(CHIPS)':
 C_PATH='@t6g_mb_lib.t6g(sch_1):page316_i50@pure_quanta.q_cap(chips)';

PART_NAME
 PC441 'Q_CAP_C0402-2.2UF,10V,10%,X6S,CH5222KEB01':;

SECTION_NUMBER 1
 '@T6G_MB_LIB.T6G(SCH_1):PAGE316_I14@PURE_QUANTA.Q_CAP(CHIPS)':
 C_PATH='@t6g_mb_lib.t6g(sch_1):page316_i14@pure_quanta.q_cap(chips)';

PART_NAME
 PC440 'Q_CAP_C0402-2.2UF,10V,10%,X6S,CH5222KEB01':;

SECTION_NUMBER 1
 '@T6G_MB_LIB.T6G(SCH_1):PAGE316_I26@PURE_QUANTA.Q_CAP(CHIPS)':
 C_PATH='@t6g_mb_lib.t6g(sch_1):page316_i26@pure_quanta.q_cap(chips)';

PART_NAME
 PU49 'RAA2213404GNPHB0-RAA2213404GNP#HB0,SMLF,IC,AL221340000':;

SECTION_NUMBER 1
 '@T6G_MB_LIB.T6G(SCH_1):PAGE317_I14@PURE_QUANTA.RAA2213404GNPHB0(CHIPS)':
 C_PATH='@t6g_mb_lib.t6g(sch_1):page317_i14@pure_quanta.raa2213404gnphb0(chips)',
 CDSVAR_REPCELL_MPS='pure_quanta|mp86950glvtz',
 VAR_0_MPS='VAR_REPLACED|RAA2213404GNPHB0|VAR_PARTNAME|MP86950GLVTZ|VALUE|MP8695~
0GLVT-Z|PART_TYPE|SMLF|MATERIAL|IC|PART_NUMBER|AL086950A00|STANDARD||LIFECYCLE||~
PART_NUMBER|AL086950A00|JEDEC_TYPE|LGA17_5X4|DESCRIPTION|IC OTHER(27P)MP86950GLV~
T-Z(LGA)|MANUFTR|MPS|MANUF_PN|MP86950GLVT-Z|RD_CMPLS_LVL|EP(V1)|CMPLS_LVL||FROM_~
PJ|S69-CARSON|CLASS|IC|DIP_SMD||DATA|MPS_MP86950GLVT-Z.pdf|EE_CHECK_LIST||FP_ECN~
||PSL||CREATOR||STATUS||MSD|Level-3|ESD_CDM|NA|ESD_HBM|NA|ESD_MM|NA|PIN_LENGTH_S~
HORT_PIN|0 MILS|PIN_LENGTH_LONG_PIN|0 MILS|CREATEDAY|20180807|VARIANT_DEVICE_TYP~
E|MP86950GLVTZ-MP86950GLVT-Z,SML';

PART_NAME
 PR1799 'Q_RES_0402LF-0,5%,1/16W,CHIP,CS00002JB38':;

SECTION_NUMBER 1
 '@T6G_MB_LIB.T6G(SCH_1):PAGE317_I19@PURE_QUANTA.Q_RES(CHIPS)':
 C_PATH='@t6g_mb_lib.t6g(sch_1):page317_i19@pure_quanta.q_res(chips)',
 CDSVAR_REPCELL_MPS='pure_quanta|Q_res',
 VAR_0_MPS='VALUE|0|TOLERANCE|5%|WATTAGE|1/16W|PACK_TYPE|0402LF|MATERIAL|EMPTY|P~
ART_NUMBER|CS00002JB38|STANDARD|End of Design|LIFECYCLE|Comp-Approve|PART_NUMBER~
|CS00002JB38|JEDEC_TYPE|R0402|ALT_SYMBOLS|(R0402-0201)|VALUE|0|TOL|5%|WATTAGE|1/~
16W|CLASS|IO|DESCRIPTION|RESISTOR CHIP 0 1/16W +-5%(0402)|COMPONENT_TYPE|CHIP040~
2|LEAD_LENGTH||DFM_EXCLUSION||DAY|20100618|VARIANT_DEVICE_TYPE|Q_RES-0,5%,1/16W,~
0402LF,EMPTY,';

PART_NAME
 PR1798 'Q_RES_0402LF-4.7,1%,1/16W,CHIP,CS-4702FB19':;

SECTION_NUMBER 1
 '@T6G_MB_LIB.T6G(SCH_1):PAGE317_I18@PURE_QUANTA.Q_RES(CHIPS)':
 C_PATH='@t6g_mb_lib.t6g(sch_1):page317_i18@pure_quanta.q_res(chips)',
 CDSVAR_REPCELL_MPS='pure_quanta|Q_res',
 VAR_0_MPS='VALUE|0|TOLERANCE|5%|WATTAGE|1/16W|PACK_TYPE|0402LF|MATERIAL|CHIP|PA~
RT_NUMBER|CS00002JB38|STANDARD|End of Design|LIFECYCLE|Comp-Approve|PART_NUMBER|~
CS00002JB38|JEDEC_TYPE|R0402|ALT_SYMBOLS|(R0402-0201)|VALUE|0|TOL|5%|WATTAGE|1/1~
6W|CLASS|DISCRETE|DESCRIPTION|RESISTOR CHIP 0 1/16W +-5%(0402)|COMPONENT_TYPE|CH~
IP0402|LEAD_LENGTH||DFM_EXCLUSION||DAY|20100618|VARIANT_DEVICE_TYPE|Q_RES-0,5%,1~
/16W,0402LF,CHIP,C';

PART_NAME
 PR1728 'Q_RES_0402LF-8.87K,1%,1/16W,EMPTY,CS28872FB01':;

SECTION_NUMBER 1
 '@T6G_MB_LIB.T6G(SCH_1):PAGE317_I2@PURE_QUANTA.Q_RES(CHIPS)':
 C_PATH='@t6g_mb_lib.t6g(sch_1):page317_i2@pure_quanta.q_res(chips)';

PART_NAME
 PR699 'Q_RES_0402LF-0,5%,1/16W,EMPTY,CS00002JB38':;

SECTION_NUMBER 1
 '@T6G_MB_LIB.T6G(SCH_1):PAGE317_I16@PURE_QUANTA.Q_RES(CHIPS)':
 C_PATH='@t6g_mb_lib.t6g(sch_1):page317_i16@pure_quanta.q_res(chips)',
 CDSVAR_REPCELL_MPS='pure_quanta|Q_res',
 VAR_0_MPS='VALUE|0|TOLERANCE|5%|WATTAGE|1/16W|PACK_TYPE|0402LF|MATERIAL|CHIP|PA~
RT_NUMBER|CS00002JB38|STANDARD|End of Design|LIFECYCLE|Comp-Approve|PART_NUMBER|~
CS00002JB38|JEDEC_TYPE|R0402|ALT_SYMBOLS|(R0402-0201)|VALUE|0|TOL|5%|WATTAGE|1/1~
6W|CLASS|DISCRETE|DESCRIPTION|RESISTOR CHIP 0 1/16W +-5%(0402)|COMPONENT_TYPE|CH~
IP0402|LEAD_LENGTH||DFM_EXCLUSION||DAY|20100618|VARIANT_DEVICE_TYPE|Q_RES-0,5%,1~
/16W,0402LF,CHIP,C';

PART_NAME
 PR678 'Q_RES_0402LF-0,5%,1/16W,CHIP,CS00002JB38':;

SECTION_NUMBER 1
 '@T6G_MB_LIB.T6G(SCH_1):PAGE317_I11@PURE_QUANTA.Q_RES(CHIPS)':
 C_PATH='@t6g_mb_lib.t6g(sch_1):page317_i11@pure_quanta.q_res(chips)',
 CDSVAR_REPCELL_MPS='pure_quanta|Q_res',
 VAR_0_MPS='VALUE|0|TOLERANCE|5%|WATTAGE|1/16W|PACK_TYPE|0402LF|MATERIAL|EMPTY|P~
ART_NUMBER|CS00002JB38|STANDARD|End of Design|LIFECYCLE|Comp-Approve|PART_NUMBER~
|CS00002JB38|JEDEC_TYPE|R0402|ALT_SYMBOLS|(R0402-0201)|VALUE|0|TOL|5%|WATTAGE|1/~
16W|CLASS|IO|DESCRIPTION|RESISTOR CHIP 0 1/16W +-5%(0402)|COMPONENT_TYPE|CHIP040~
2|LEAD_LENGTH||DFM_EXCLUSION||DAY|20100618|VARIANT_DEVICE_TYPE|Q_RES-0,5%,1/16W,~
0402LF,EMPTY,';

PART_NAME
 PR250 'Q_RES_0402LF-2.2,1%,1/16W,CHIP,CS-2202FB00':;

SECTION_NUMBER 1
 '@T6G_MB_LIB.T6G(SCH_1):PAGE317_I13@PURE_QUANTA.Q_RES(CHIPS)':
 C_PATH='@t6g_mb_lib.t6g(sch_1):page317_i13@pure_quanta.q_res(chips)';

PART_NAME
 PL20 'Q_INDUCTOR_SMLF-300NH/33A,IND,CV+30Y0KZ05':;

SECTION_NUMBER 1
 '@T6G_MB_LIB.T6G(SCH_1):PAGE317_I23@PURE_QUANTA.Q_INDUCTOR(CHIPS)':
 C_PATH='@t6g_mb_lib.t6g(sch_1):page317_i23@pure_quanta.q_inductor(chips)';

PART_NAME
 PC2199 'Q_CAPP_THLF-560UF,2.5V,20%,OSCON,CC7560JMD18':;

SECTION_NUMBER 1
 '@T6G_MB_LIB.T6G(SCH_1):PAGE317_I32@PURE_QUANTA.Q_CAPP(CHIPS)':
 C_PATH='@t6g_mb_lib.t6g(sch_1):page317_i32@pure_quanta.q_capp(chips)';

PART_NAME
 PC1930 'Q_CAPP_SMLF-470UF,2.5V,20%,POSCAP,CH747LM8816':;

SECTION_NUMBER 1
 '@T6G_MB_LIB.T6G(SCH_1):PAGE317_I33@PURE_QUANTA.Q_CAPP(CHIPS)':
 C_PATH='@t6g_mb_lib.t6g(sch_1):page317_i33@pure_quanta.q_capp(chips)';

PART_NAME
 PC1366 'Q_CAP_0402-0.1UF,25V,10%,X7R,CH4104K1B00':;

SECTION_NUMBER 1
 '@T6G_MB_LIB.T6G(SCH_1):PAGE317_I8@PURE_QUANTA.Q_CAP(CHIPS)':
 C_PATH='@t6g_mb_lib.t6g(sch_1):page317_i8@pure_quanta.q_cap(chips)',
 CDSVAR_REPCELL_MPS='pure_quanta|Q_cap',
 VAR_0_MPS='VALUE|0.1UF|VOLTAGE|25V|TOLERANCE|10%|PACK_TYPE|0402|MATERIAL|EMPTY|~
PART_NUMBER|CH4104K1B00|STANDARD||LIFECYCLE||ASS_PART||PART_NUMBER|CH4104K1B00|J~
EDEC_TYPE|C0402|ALT_SYMBOLS|(C0402_OCTAGONXA,C0402-0201)|VALUE|NA|RATED_VOLTAGE|~
25V|TOL|10%|CLASS|IO|DESCRIPTION|CAP CHIP 0.1U 25V(+-10%,X7R,0402)|COMPONENT_TYP~
E|CHIP0402|LEAD_LENGTH||LPID||DATE|20160113|VARIANT_DEVICE_TYPE|Q_CAP-0.1UF,25V,~
10%,0402,EMPTY';

PART_NAME
 PC437 'Q_CAP_0805-22UF,4V,20%,X6S,TMP_QCH622KMEA01':;

SECTION_NUMBER 1
 '@T6G_MB_LIB.T6G(SCH_1):PAGE317_I31@PURE_QUANTA.Q_CAP(CHIPS)':
 C_PATH='@t6g_mb_lib.t6g(sch_1):page317_i31@pure_quanta.q_cap(chips)';

PART_NAME
 PC435 'Q_CAP_0805-22UF,4V,20%,X6S,TMP_QCH622KMEA01':;

SECTION_NUMBER 1
 '@T6G_MB_LIB.T6G(SCH_1):PAGE317_I30@PURE_QUANTA.Q_CAP(CHIPS)':
 C_PATH='@t6g_mb_lib.t6g(sch_1):page317_i30@pure_quanta.q_cap(chips)';

PART_NAME
 PC434 'Q_CAP_C0402-100NF,50V,10%,X7R,CH4106K1B01':;

SECTION_NUMBER 1
 '@T6G_MB_LIB.T6G(SCH_1):PAGE317_I25@PURE_QUANTA.Q_CAP(CHIPS)':
 C_PATH='@t6g_mb_lib.t6g(sch_1):page317_i25@pure_quanta.q_cap(chips)';

PART_NAME
 PC433 'Q_CAP_C0805-22UF,16V,20%,X6S,CH6223MEA00':;

SECTION_NUMBER 1
 '@T6G_MB_LIB.T6G(SCH_1):PAGE317_I27@PURE_QUANTA.Q_CAP(CHIPS)':
 C_PATH='@t6g_mb_lib.t6g(sch_1):page317_i27@pure_quanta.q_cap(chips)';

PART_NAME
 PC432 'Q_CAP_C0805-22UF,16V,20%,X6S,CH6223MEA00':;

SECTION_NUMBER 1
 '@T6G_MB_LIB.T6G(SCH_1):PAGE317_I22@PURE_QUANTA.Q_CAP(CHIPS)':
 C_PATH='@t6g_mb_lib.t6g(sch_1):page317_i22@pure_quanta.q_cap(chips)';

PART_NAME
 PC431 'Q_CAP_C0402-100NF,50V,10%,X7R,CH4106K1B01':;

SECTION_NUMBER 1
 '@T6G_MB_LIB.T6G(SCH_1):PAGE317_I24@PURE_QUANTA.Q_CAP(CHIPS)':
 C_PATH='@t6g_mb_lib.t6g(sch_1):page317_i24@pure_quanta.q_cap(chips)';

PART_NAME
 PC430 'Q_CAP_C0402-1UF,16V,10%,X6S,CH5103KEB01':;

SECTION_NUMBER 1
 '@T6G_MB_LIB.T6G(SCH_1):PAGE317_I21@PURE_QUANTA.Q_CAP(CHIPS)':
 C_PATH='@t6g_mb_lib.t6g(sch_1):page317_i21@pure_quanta.q_cap(chips)';

PART_NAME
 PC429 'Q_CAP_0402-3300PF,50V,10%,X7R,TMP_QCH2336K1B12':;

SECTION_NUMBER 1
 '@T6G_MB_LIB.T6G(SCH_1):PAGE317_I20@PURE_QUANTA.Q_CAP(CHIPS)':
 C_PATH='@t6g_mb_lib.t6g(sch_1):page317_i20@pure_quanta.q_cap(chips)';

PART_NAME
 PC428 'Q_CAP_C0402-2.2UF,10V,10%,X6S,CH5222KEB01':;

SECTION_NUMBER 1
 '@T6G_MB_LIB.T6G(SCH_1):PAGE317_I9@PURE_QUANTA.Q_CAP(CHIPS)':
 C_PATH='@t6g_mb_lib.t6g(sch_1):page317_i9@pure_quanta.q_cap(chips)';

PART_NAME
 PU29 'RAA229126GNPHA0-RAA229126GNP#HA0,SMLF,IC,AL229126000':;

SECTION_NUMBER 1
 '@T6G_MB_LIB.T6G(SCH_1):PAGE307_I211@PURE_QUANTA.RAA229126GNPHA0(CHIPS)':
 C_PATH='@t6g_mb_lib.t6g(sch_1):page307_i211@pure_quanta.raa229126gnpha0(chips)';

PART_NAME
 PR637 'Q_RES_0402LF-10K,1%,1/16W,EMPTY,CS31002FB08':;

SECTION_NUMBER 1
 '@T6G_MB_LIB.T6G(SCH_1):PAGE307_I260@PURE_QUANTA.Q_RES(CHIPS)':
 C_PATH='@t6g_mb_lib.t6g(sch_1):page307_i260@pure_quanta.q_res(chips)',
 CDSVAR_REPCELL_MPS='pure_quanta|Q_res',
 VAR_0_MPS='VALUE|10K|TOLERANCE|1%|WATTAGE|1/16W|PACK_TYPE|0402LF|MATERIAL|CHIP|~
PART_NUMBER|CS31002FB08|STANDARD|End of Design|LIFECYCLE|Comp-Approve|PART_NUMBE~
R|CS31002FB08|JEDEC_TYPE|R0402|ALT_SYMBOLS|(R0402-0201)|VALUE|10K|TOL|1%|WATTAGE~
|1/16W|CLASS|DISCRETE|DESCRIPTION|RES CHIP 10K 1/16W +-1%(0402)EF|COMPONENT_TYPE~
|CHIPR0402|LEAD_LENGTH||DFM_EXCLUSION||DAY|20180208|VARIANT_DEVICE_TYPE|Q_RES-10~
K,1%,1/16W,0402LF,CHIP';

PART_NAME
 PR578 'Q_RES_0402LF-100,1%,1/16W,CHIP,TMP_QCS11002FB22':;

SECTION_NUMBER 1
 '@T6G_MB_LIB.T6G(SCH_1):PAGE307_I188@PURE_QUANTA.Q_RES(CHIPS)':
 C_PATH='@t6g_mb_lib.t6g(sch_1):page307_i188@pure_quanta.q_res(chips)';

PART_NAME
 PR577 'Q_RES_0402LF-49.9     ,1%  ,1/16W,EMPTY,CS04992FB31':;

SECTION_NUMBER 1
 '@T6G_MB_LIB.T6G(SCH_1):PAGE307_I268@PURE_QUANTA.Q_RES(CHIPS)':
 C_PATH='@t6g_mb_lib.t6g(sch_1):page307_i268@pure_quanta.q_res(chips)';

PART_NAME
 PR576 'Q_RES_0402LF-49.9     ,1%  ,1/16W,CHIP,CS04992FB31':;

SECTION_NUMBER 1
 '@T6G_MB_LIB.T6G(SCH_1):PAGE307_I269@PURE_QUANTA.Q_RES(CHIPS)':
 C_PATH='@t6g_mb_lib.t6g(sch_1):page307_i269@pure_quanta.q_res(chips)';

PART_NAME
 PR575 'Q_RES_0402LF-100,1%,1/16W,CHIP,TMP_QCS11002FB22':;

SECTION_NUMBER 1
 '@T6G_MB_LIB.T6G(SCH_1):PAGE307_I272@PURE_QUANTA.Q_RES(CHIPS)':
 C_PATH='@t6g_mb_lib.t6g(sch_1):page307_i272@pure_quanta.q_res(chips)';

PART_NAME
 PR574 'Q_RES_0402LF-100,1%,1/16W,CHIP,TMP_QCS11002FB22':;

SECTION_NUMBER 1
 '@T6G_MB_LIB.T6G(SCH_1):PAGE307_I176@PURE_QUANTA.Q_RES(CHIPS)':
 C_PATH='@t6g_mb_lib.t6g(sch_1):page307_i176@pure_quanta.q_res(chips)';

PART_NAME
 PR561 'Q_RES_0402LF-100,1%,1/16W,CHIP,TMP_QCS11002FB22':;

SECTION_NUMBER 1
 '@T6G_MB_LIB.T6G(SCH_1):PAGE307_I175@PURE_QUANTA.Q_RES(CHIPS)':
 C_PATH='@t6g_mb_lib.t6g(sch_1):page307_i175@pure_quanta.q_res(chips)';

PART_NAME
 PR560 'Q_RES_0402LF-100,1%,1/16W,CHIP,TMP_QCS11002FB22':;

SECTION_NUMBER 1
 '@T6G_MB_LIB.T6G(SCH_1):PAGE307_I171@PURE_QUANTA.Q_RES(CHIPS)':
 C_PATH='@t6g_mb_lib.t6g(sch_1):page307_i171@pure_quanta.q_res(chips)';

PART_NAME
 PR453 'Q_RES_0402LF-0,5%,1/16W,CHIP,CS00002JB38':;

SECTION_NUMBER 1
 '@T6G_MB_LIB.T6G(SCH_1):PAGE307_I262@PURE_QUANTA.Q_RES(CHIPS)':
 C_PATH='@t6g_mb_lib.t6g(sch_1):page307_i262@pure_quanta.q_res(chips)';

PART_NAME
 PR452 'Q_RES_0402LF-0,5%,1/16W,EMPTY,CS00002JB38':;

SECTION_NUMBER 1
 '@T6G_MB_LIB.T6G(SCH_1):PAGE307_I263@PURE_QUANTA.Q_RES(CHIPS)':
 C_PATH='@t6g_mb_lib.t6g(sch_1):page307_i263@pure_quanta.q_res(chips)';

PART_NAME
 PR323 'Q_RES_0402LF-1,1%,1/16W,CHIP,CS-1002FB23':;

SECTION_NUMBER 1
 '@T6G_MB_LIB.T6G(SCH_1):PAGE307_I278@PURE_QUANTA.Q_RES(CHIPS)':
 C_PATH='@t6g_mb_lib.t6g(sch_1):page307_i278@pure_quanta.q_res(chips)';

PART_NAME
 PR318 'Q_RES_0402LF-5.23K,1%,1/16W,CHIP,CS25232FB18':;

SECTION_NUMBER 1
 '@T6G_MB_LIB.T6G(SCH_1):PAGE307_I165@PURE_QUANTA.Q_RES(CHIPS)':
 C_PATH='@t6g_mb_lib.t6g(sch_1):page307_i165@pure_quanta.q_res(chips)',
 CDSVAR_REPCELL_MPS='pure_quanta|Q_res',
 VAR_0_MPS='VALUE|110|TOLERANCE|1%|WATTAGE|1/16W|PACK_TYPE|0402LF|MATERIAL|CHIP|~
PART_NUMBER|TMP_QCS11102FB18|STANDARD|End of Design|LIFECYCLE|Comp-Approve|PART_~
NUMBER|CS11102FB18|JEDEC_TYPE|R0402|ALT_SYMBOLS|(R0402-0201)|VALUE|110|TOL|1%|WA~
TTAGE|1/16W|CLASS|DISCRETE|DESCRIPTION|110ohm 0402|COMPONENT_TYPE|CHIP0402|LEAD_~
LENGTH||DFM_EXCLUSION||DAY||VARIANT_DEVICE_TYPE|Q_RES-110,1%,1/16W,0402LF,CHIP';

PART_NAME
 PR317 'Q_RES_0402LF-0,5%,1/16W,CHIP,CS00002JB38':;

SECTION_NUMBER 1
 '@T6G_MB_LIB.T6G(SCH_1):PAGE307_I238@PURE_QUANTA.Q_RES(CHIPS)':
 C_PATH='@t6g_mb_lib.t6g(sch_1):page307_i238@pure_quanta.q_res(chips)';

PART_NAME
 PR315 'Q_RES_0402LF-0,5%,1/16W,CHIP,CS00002JB38':;

SECTION_NUMBER 1
 '@T6G_MB_LIB.T6G(SCH_1):PAGE307_I239@PURE_QUANTA.Q_RES(CHIPS)':
 C_PATH='@t6g_mb_lib.t6g(sch_1):page307_i239@pure_quanta.q_res(chips)';

PART_NAME
 PR314 'Q_RES_0402LF-0,5%,1/16W,CHIP,CS00002JB38':;

SECTION_NUMBER 1
 '@T6G_MB_LIB.T6G(SCH_1):PAGE307_I241@PURE_QUANTA.Q_RES(CHIPS)':
 C_PATH='@t6g_mb_lib.t6g(sch_1):page307_i241@pure_quanta.q_res(chips)';

PART_NAME
 PR313 'Q_RES_0402LF-1K,1%,1/16W,EMPTY,TMP_QCS21002FB24':;

SECTION_NUMBER 1
 '@T6G_MB_LIB.T6G(SCH_1):PAGE307_I208@PURE_QUANTA.Q_RES(CHIPS)':
 C_PATH='@t6g_mb_lib.t6g(sch_1):page307_i208@pure_quanta.q_res(chips)',
 CDSVAR_REPCELL_MPS='pure_quanta|Q_res',
 VAR_0_MPS='VALUE|1K|TOLERANCE|1%|WATTAGE|1/16W|PACK_TYPE|0402LF|MATERIAL|CHIP|P~
ART_NUMBER|TMP_QCS21002FB24|STANDARD|End of Design|LIFECYCLE|Comp-Approve|PART_N~
UMBER|CS21002FB24|JEDEC_TYPE|R0402|ALT_SYMBOLS|(R0402-0201)|VALUE|1K|TOL|1%|WATT~
AGE|1/16W|CLASS|DISCRETE|DESCRIPTION|RES CHIP 1K 1/16W +-1% (0402)|COMPONENT_TYP~
E|CHIP0402|LEAD_LENGTH||DFM_EXCLUSION||DAY||VARIANT_DEVICE_TYPE|Q_RES-1K,1%,1/16~
W,0402LF,CHIP,';

PART_NAME
 PR312 'Q_RES_0402LF-0,5%,1/16W,CHIP,CS00002JB38':;

SECTION_NUMBER 1
 '@T6G_MB_LIB.T6G(SCH_1):PAGE307_I190@PURE_QUANTA.Q_RES(CHIPS)':
 C_PATH='@t6g_mb_lib.t6g(sch_1):page307_i190@pure_quanta.q_res(chips)';

PART_NAME
 PR311 'Q_RES_0402LF-0,5%,1/16W,CHIP,CS00002JB38':;

SECTION_NUMBER 1
 '@T6G_MB_LIB.T6G(SCH_1):PAGE307_I191@PURE_QUANTA.Q_RES(CHIPS)':
 C_PATH='@t6g_mb_lib.t6g(sch_1):page307_i191@pure_quanta.q_res(chips)';

PART_NAME
 PR310 'Q_RES_0402LF-150,1%,1/16W,CHIP,TMP_QCS11502FB21':;

SECTION_NUMBER 1
 '@T6G_MB_LIB.T6G(SCH_1):PAGE307_I192@PURE_QUANTA.Q_RES(CHIPS)':
 C_PATH='@t6g_mb_lib.t6g(sch_1):page307_i192@pure_quanta.q_res(chips)';

PART_NAME
 PR309 'Q_RES_0402LF-0,5%,1/16W,CHIP,CS00002JB38':;

SECTION_NUMBER 1
 '@T6G_MB_LIB.T6G(SCH_1):PAGE307_I196@PURE_QUANTA.Q_RES(CHIPS)':
 C_PATH='@t6g_mb_lib.t6g(sch_1):page307_i196@pure_quanta.q_res(chips)';

PART_NAME
 PR308 'Q_RES_0402LF-0,5%,1/16W,CHIP,CS00002JB38':;

SECTION_NUMBER 1
 '@T6G_MB_LIB.T6G(SCH_1):PAGE307_I197@PURE_QUANTA.Q_RES(CHIPS)':
 C_PATH='@t6g_mb_lib.t6g(sch_1):page307_i197@pure_quanta.q_res(chips)';

PART_NAME
 PR307 'Q_RES_0402LF-1K,1%,1/16W,CHIP,TMP_QCS21002FB24':;

SECTION_NUMBER 1
 '@T6G_MB_LIB.T6G(SCH_1):PAGE307_I198@PURE_QUANTA.Q_RES(CHIPS)':
 C_PATH='@t6g_mb_lib.t6g(sch_1):page307_i198@pure_quanta.q_res(chips)';

PART_NAME
 PR306 'Q_RES_0402LF-28K,1%,1/16W,EMPTY,CS32802FB05':;

SECTION_NUMBER 1
 '@T6G_MB_LIB.T6G(SCH_1):PAGE307_I161@PURE_QUANTA.Q_RES(CHIPS)':
 C_PATH='@t6g_mb_lib.t6g(sch_1):page307_i161@pure_quanta.q_res(chips)',
 CDSVAR_REPCELL_MPS='pure_quanta|Q_res',
 VAR_0_MPS='VALUE|3.32K|TOLERANCE|1%|WATTAGE|1/16W|PACK_TYPE|0402LF|MATERIAL|CHI~
P|PART_NUMBER|CS23322FB20|STANDARD|End of Design|LIFECYCLE|Comp-Approve|PART_NUM~
BER|CS23322FB20|JEDEC_TYPE|R0402|ALT_SYMBOLS|(R0402-0201)|VALUE|3.32K|TOL|1%|WAT~
TAGE|1/16W|CLASS|DISCRETE|DESCRIPTION|RES CHIP 3.32K 1/16W +-1% (0402)|COMPONENT~
_TYPE|CHIP0402|LEAD_LENGTH||DFM_EXCLUSION||DAY|20140826|VARIANT_DEVICE_TYPE|Q_RE~
S-3.32K,1%,1/16W,0402LF,CH';

PART_NAME
 PR305 'Q_RES_0402LF-0,5%,1/16W,CHIP,CS00002JB38':;

SECTION_NUMBER 1
 '@T6G_MB_LIB.T6G(SCH_1):PAGE307_I199@PURE_QUANTA.Q_RES(CHIPS)':
 C_PATH='@t6g_mb_lib.t6g(sch_1):page307_i199@pure_quanta.q_res(chips)',
 VAR_0_MPS='';

PART_NAME
 PR304 'Q_RES_0402LF-0,5%,1/16W,EMPTY,CS00002JB38':;

SECTION_NUMBER 1
 '@T6G_MB_LIB.T6G(SCH_1):PAGE307_I167@PURE_QUANTA.Q_RES(CHIPS)':
 C_PATH='@t6g_mb_lib.t6g(sch_1):page307_i167@pure_quanta.q_res(chips)',
 VAR_0_MPS='';

PART_NAME
 PR303 'Q_RES_0402LF-0,5%,1/16W,CHIP,CS00002JB38':;

SECTION_NUMBER 1
 '@T6G_MB_LIB.T6G(SCH_1):PAGE307_I166@PURE_QUANTA.Q_RES(CHIPS)':
 C_PATH='@t6g_mb_lib.t6g(sch_1):page307_i166@pure_quanta.q_res(chips)',
 CDSVAR_REPCELL_MPS='pure_quanta|Q_res',
 VAR_0_MPS='VALUE|15K|TOLERANCE|1%|WATTAGE|1/16W|PACK_TYPE|0402LF|MATERIAL|CHIP|~
PART_NUMBER|TMP_QCS31502FB24|STANDARD|End of Design|LIFECYCLE|Comp-Approve|PART_~
NUMBER|CS31502FB24|JEDEC_TYPE|R0402|ALT_SYMBOLS|(R0402-0201)|VALUE|15K|TOL|1%|WA~
TTAGE|1/16W |CLASS|DISCRETE|DESCRIPTION|RES CHIP 15K 1/16W +-1% (0402)|COMPONENT~
_TYPE|CHIP0402|LEAD_LENGTH||DFM_EXCLUSION||DAY||VARIANT_DEVICE_TYPE|Q_RES-15K,1%~
,1/16W,0402LF,CHIP';

PART_NAME
 PR249 'Q_RES_0402LF-1K,1%,1/16W,CHIP,TMP_QCS21002FB24':;

SECTION_NUMBER 1
 '@T6G_MB_LIB.T6G(SCH_1):PAGE307_I218@PURE_QUANTA.Q_RES(CHIPS)':
 C_PATH='@t6g_mb_lib.t6g(sch_1):page307_i218@pure_quanta.q_res(chips)';

PART_NAME
 PR243 'Q_RES_0402LF-1K,1%,1/16W,CHIP,TMP_QCS21002FB24':;

SECTION_NUMBER 1
 '@T6G_MB_LIB.T6G(SCH_1):PAGE307_I215@PURE_QUANTA.Q_RES(CHIPS)':
 C_PATH='@t6g_mb_lib.t6g(sch_1):page307_i215@pure_quanta.q_res(chips)';

PART_NAME
 PR242 'Q_RES_0402LF-0,5%,1/16W,CHIP,CS00002JB38':;

SECTION_NUMBER 1
 '@T6G_MB_LIB.T6G(SCH_1):PAGE307_I220@PURE_QUANTA.Q_RES(CHIPS)':
 C_PATH='@t6g_mb_lib.t6g(sch_1):page307_i220@pure_quanta.q_res(chips)';

PART_NAME
 PR241 'Q_RES_0402LF-1K,1%,1/16W,CHIP,TMP_QCS21002FB24':;

SECTION_NUMBER 1
 '@T6G_MB_LIB.T6G(SCH_1):PAGE307_I214@PURE_QUANTA.Q_RES(CHIPS)':
 C_PATH='@t6g_mb_lib.t6g(sch_1):page307_i214@pure_quanta.q_res(chips)';

PART_NAME
 PR234 'Q_RES_0402LF-0,5%,1/16W,CHIP,CS00002JB38':;

SECTION_NUMBER 1
 '@T6G_MB_LIB.T6G(SCH_1):PAGE307_I204@PURE_QUANTA.Q_RES(CHIPS)':
 C_PATH='@t6g_mb_lib.t6g(sch_1):page307_i204@pure_quanta.q_res(chips)';

PART_NAME
 PR233 'Q_RES_0402LF-0,5%,1/16W,CHIP,CS00002JB38':;

SECTION_NUMBER 1
 '@T6G_MB_LIB.T6G(SCH_1):PAGE307_I202@PURE_QUANTA.Q_RES(CHIPS)':
 C_PATH='@t6g_mb_lib.t6g(sch_1):page307_i202@pure_quanta.q_res(chips)';

PART_NAME
 PR232 'Q_RES_0402LF-1K,1%,1/16W,CHIP,TMP_QCS21002FB24':;

SECTION_NUMBER 1
 '@T6G_MB_LIB.T6G(SCH_1):PAGE307_I203@PURE_QUANTA.Q_RES(CHIPS)':
 C_PATH='@t6g_mb_lib.t6g(sch_1):page307_i203@pure_quanta.q_res(chips)';

PART_NAME
 PJ52 'Q_SHORT_SM-EMPTY,SHORT6':;

SECTION_NUMBER 1
 '@T6G_MB_LIB.T6G(SCH_1):PAGE307_I187@PURE_QUANTA.Q_SHORT(CHIPS)':
 C_PATH='@t6g_mb_lib.t6g(sch_1):page307_i187@pure_quanta.q_short(chips)';

PART_NAME
 PJ49 'Q_SHORT_SM-EMPTY,SHORT6':;

SECTION_NUMBER 1
 '@T6G_MB_LIB.T6G(SCH_1):PAGE307_I174@PURE_QUANTA.Q_SHORT(CHIPS)':
 C_PATH='@t6g_mb_lib.t6g(sch_1):page307_i174@pure_quanta.q_short(chips)';

PART_NAME
 PC1194 'Q_CAP_C0402-1UF,16V,10%,X6S,CH5103KEB01':;

SECTION_NUMBER 1
 '@T6G_MB_LIB.T6G(SCH_1):PAGE307_I255@PURE_QUANTA.Q_CAP(CHIPS)':
 C_PATH='@t6g_mb_lib.t6g(sch_1):page307_i255@pure_quanta.q_cap(chips)';

PART_NAME
 PC555 'Q_CAP_C0402-1UF,16V,10%,X6S,CH5103KEB01':;

SECTION_NUMBER 1
 '@T6G_MB_LIB.T6G(SCH_1):PAGE307_I258@PURE_QUANTA.Q_CAP(CHIPS)':
 C_PATH='@t6g_mb_lib.t6g(sch_1):page307_i258@pure_quanta.q_cap(chips)';

PART_NAME
 PC554 'Q_CAP_0402-470PF,50V,10%,X7R,TMP_QCH14706KB18':;

SECTION_NUMBER 1
 '@T6G_MB_LIB.T6G(SCH_1):PAGE307_I221@PURE_QUANTA.Q_CAP(CHIPS)':
 C_PATH='@t6g_mb_lib.t6g(sch_1):page307_i221@pure_quanta.q_cap(chips)',
 CDSVAR_REPCELL_MPS='pure_quanta|Q_cap',
 VAR_0_MPS='VALUE|0.01UF|VOLTAGE|25V|TOLERANCE|10%|PACK_TYPE|0402|MATERIAL|X7R|P~
ART_NUMBER|TMP_QCH31004KB17|STANDARD|End of Design|LIFECYCLE|Comp-Approve|ASS_PA~
RT||PART_NUMBER|CH31004KB17|JEDEC_TYPE|C0402|ALT_SYMBOLS|(C0402-0201)|VALUE|0.01~
UF|RATED_VOLTAGE|25V|TOL|10%|CLASS|DISCRETE|DESCRIPTION|CAP CHIP 0.01U 25V(+-10%~
,X7R,0402)|COMPONENT_TYPE|CHIP0402|LEAD_LENGTH||LPID||DATE|20100528|VARIANT_DEVI~
CE_TYPE|Q_CAP-0.01UF,25V,10%,0402,X7R,';

PART_NAME
 PC553 'Q_CAP_0402-4.7UF,6.3V,20%,X6S,CH5471MEB01':;

SECTION_NUMBER 1
 '@T6G_MB_LIB.T6G(SCH_1):PAGE307_I253@PURE_QUANTA.Q_CAP(CHIPS)':
 C_PATH='@t6g_mb_lib.t6g(sch_1):page307_i253@pure_quanta.q_cap(chips)',
 CDSVAR_REPCELL_MPS='pure_quanta|Q_cap',
 VAR_0_MPS='VALUE|4.7UF|VOLTAGE|6.3V|TOLERANCE|20%|PACK_TYPE|0402|MATERIAL|EMPTY~
|PART_NUMBER|CH5471MEB01|STANDARD||LIFECYCLE||ASS_PART||PART_NUMBER|CH5471MEB01|~
JEDEC_TYPE|C0402|ALT_SYMBOLS|(C0402_OCTAGON,C0402_OCTAGONXA,C0402-0201)|VALUE|NA~
|RATED_VOLTAGE|6.3V|TOL|20%|CLASS|IO|DESCRIPTION|CAP CHIP 4.7UF 6.3V(+-20%,X6S,0~
402)|COMPONENT_TYPE|CHIP0402|LEAD_LENGTH||LPID||DATE|20151211|VARIANT_DEVICE_TYP~
E|Q_CAP-4.7UF,6.3V,20%,0402,EMPT';

PART_NAME
 PC552 'Q_CAP_C0402-100NF,50V,10%,EMPTY,CH4106K1B01':;

SECTION_NUMBER 1
 '@T6G_MB_LIB.T6G(SCH_1):PAGE307_I254@PURE_QUANTA.Q_CAP(CHIPS)':
 C_PATH='@t6g_mb_lib.t6g(sch_1):page307_i254@pure_quanta.q_cap(chips)';

PART_NAME
 PC551 'Q_CAP_0402-1000PF,50V,5%,EMPTY,TMP_QCH21006JB10':;

SECTION_NUMBER 1
 '@T6G_MB_LIB.T6G(SCH_1):PAGE307_I244@PURE_QUANTA.Q_CAP(CHIPS)':
 C_PATH='@t6g_mb_lib.t6g(sch_1):page307_i244@pure_quanta.q_cap(chips)';

PART_NAME
 PC550 'Q_CAP_0402-1000PF,50V,5%,X7R,TMP_QCH21006JB10':;

SECTION_NUMBER 1
 '@T6G_MB_LIB.T6G(SCH_1):PAGE307_I242@PURE_QUANTA.Q_CAP(CHIPS)':
 C_PATH='@t6g_mb_lib.t6g(sch_1):page307_i242@pure_quanta.q_cap(chips)';

PART_NAME
 PC549 'Q_CAP_0402-3300PF,50V,10%,X7R,TMP_QCH2336K1B12':;

SECTION_NUMBER 1
 '@T6G_MB_LIB.T6G(SCH_1):PAGE307_I240@PURE_QUANTA.Q_CAP(CHIPS)':
 C_PATH='@t6g_mb_lib.t6g(sch_1):page307_i240@pure_quanta.q_cap(chips)',
 CDSVAR_REPCELL_MPS='pure_quanta|Q_cap',
 VAR_0_MPS='VALUE|3300PF|VOLTAGE|50V|TOLERANCE|10%|PACK_TYPE|C0402|MATERIAL|EMPT~
Y|PART_NUMBER|CH2336K1B06|STANDARD||LIFECYCLE||ASS_PART||PART_NUMBER|CH2336K1B06~
|JEDEC_TYPE|C0402|ALT_SYMBOLS|(C0402-0201)|VALUE|NA|RATED_VOLTAGE|50V|TOL|10%|CL~
ASS|IO|DESCRIPTION|CAP CHIP 3300P 50V(+-10%,X7R,0402)MUR|COMPONENT_TYPE|CHIP0402~
|LEAD_LENGTH||LPID||DATE|20150617|VARIANT_DEVICE_TYPE|Q_CAP-3300PF,50V,10%,C0402~
,EMP';

PART_NAME
 PC548 'Q_CAP_0402-0.1UF,25V,10%,X7R,CH4104K1B00':;

SECTION_NUMBER 1
 '@T6G_MB_LIB.T6G(SCH_1):PAGE307_I209@PURE_QUANTA.Q_CAP(CHIPS)':
 C_PATH='@t6g_mb_lib.t6g(sch_1):page307_i209@pure_quanta.q_cap(chips)';

PART_NAME
 PC547 'Q_CAP_0402-0.1UF,25V,10%,EMPTY,CH4104K1B00':;

SECTION_NUMBER 1
 '@T6G_MB_LIB.T6G(SCH_1):PAGE307_I201@PURE_QUANTA.Q_CAP(CHIPS)':
 C_PATH='@t6g_mb_lib.t6g(sch_1):page307_i201@pure_quanta.q_cap(chips)',
 VAR_0_MPS='';

PART_NAME
 PC546 'Q_CAP_C0402-100NF,50V,10%,X7R,CH4106K1B01':;

SECTION_NUMBER 1
 '@T6G_MB_LIB.T6G(SCH_1):PAGE307_I273@PURE_QUANTA.Q_CAP(CHIPS)':
 C_PATH='@t6g_mb_lib.t6g(sch_1):page307_i273@pure_quanta.q_cap(chips)';

PART_NAME
 PC545 'Q_CAP_C0603-10UF,4V,20%,EMPTY,CH610KME907':;

SECTION_NUMBER 1
 '@T6G_MB_LIB.T6G(SCH_1):PAGE307_I271@PURE_QUANTA.Q_CAP(CHIPS)':
 C_PATH='@t6g_mb_lib.t6g(sch_1):page307_i271@pure_quanta.q_cap(chips)';

PART_NAME
 PC422 'Q_CAP_0402-3300PF,50V,10%,X7R,TMP_QCH2336K1B12':;

SECTION_NUMBER 1
 '@T6G_MB_LIB.T6G(SCH_1):PAGE307_I219@PURE_QUANTA.Q_CAP(CHIPS)':
 C_PATH='@t6g_mb_lib.t6g(sch_1):page307_i219@pure_quanta.q_cap(chips)',
 CDSVAR_REPCELL_MPS='pure_quanta|Q_cap',
 VAR_0_MPS='VALUE|3300PF|VOLTAGE|50V|TOLERANCE|10%|PACK_TYPE|C0402|MATERIAL|EMPT~
Y|PART_NUMBER|CH2336K1B06|STANDARD||LIFECYCLE||ASS_PART||PART_NUMBER|CH2336K1B06~
|JEDEC_TYPE|C0402|ALT_SYMBOLS|(C0402-0201)|VALUE|NA|RATED_VOLTAGE|50V|TOL|10%|CL~
ASS|IO|DESCRIPTION|CAP CHIP 3300P 50V(+-10%,X7R,0402)MUR|COMPONENT_TYPE|CHIP0402~
|LEAD_LENGTH||LPID||DATE|20150617|VARIANT_DEVICE_TYPE|Q_CAP-3300PF,50V,10%,C0402~
,EMP';

PART_NAME
 PC421 'Q_CAP_0402-1000PF,50V,5%,EMPTY,TMP_QCH21006JB10':;

SECTION_NUMBER 1
 '@T6G_MB_LIB.T6G(SCH_1):PAGE307_I205@PURE_QUANTA.Q_CAP(CHIPS)':
 C_PATH='@t6g_mb_lib.t6g(sch_1):page307_i205@pure_quanta.q_cap(chips)';

PART_NAME
 PC420 'Q_CAP_0402-1000PF,50V,5%,X7R,TMP_QCH21006JB10':;

SECTION_NUMBER 1
 '@T6G_MB_LIB.T6G(SCH_1):PAGE307_I206@PURE_QUANTA.Q_CAP(CHIPS)':
 C_PATH='@t6g_mb_lib.t6g(sch_1):page307_i206@pure_quanta.q_cap(chips)';

PART_NAME
 PU76_P1_2 'ISL99390FRZTR5935-ISL99390FRZ-TR5935,SMLF,IC,AL099390004':;

SECTION_NUMBER 1
 '@T6G_MB_LIB.T6G(SCH_1):PAGE312_I221@PURE_QUANTA.ISL99390FRZTR5935(CHIPS)':
 C_PATH='@t6g_mb_lib.t6g(sch_1):page312_i221@pure_quanta.isl99390frztr5935(chips~
)';

PART_NAME
 PU75_P1_1 'ISL99390FRZTR5935-ISL99390FRZ-TR5935,SMLF,IC,AL099390004':;

SECTION_NUMBER 1
 '@T6G_MB_LIB.T6G(SCH_1):PAGE312_I278@PURE_QUANTA.ISL99390FRZTR5935(CHIPS)':
 C_PATH='@t6g_mb_lib.t6g(sch_1):page312_i278@pure_quanta.isl99390frztr5935(chips~
)';

PART_NAME
 PR1801 'Q_RES_0402LF-3.3,1%,1/16W,CHIP,CS-3302FB00':;

SECTION_NUMBER 1
 '@T6G_MB_LIB.T6G(SCH_1):PAGE312_I242@PURE_QUANTA.Q_RES(CHIPS)':
 C_PATH='@t6g_mb_lib.t6g(sch_1):page312_i242@pure_quanta.q_res(chips)',
 CDSVAR_REPCELL_MPS='pure_quanta|Q_res',
 VAR_0_MPS='VALUE|0|TOLERANCE|5%|WATTAGE|1/16W|PACK_TYPE|0402LF|MATERIAL|CHIP|PA~
RT_NUMBER|CS00002JB38|STANDARD|End of Design|LIFECYCLE|Comp-Approve|PART_NUMBER|~
CS00002JB38|JEDEC_TYPE|R0402|ALT_SYMBOLS|(R0402-0201)|VALUE|0|TOL|5%|WATTAGE|1/1~
6W|CLASS|DISCRETE|DESCRIPTION|RESISTOR CHIP 0 1/16W +-5%(0402)|COMPONENT_TYPE|CH~
IP0402|LEAD_LENGTH||DFM_EXCLUSION||DAY|20100618|VARIANT_DEVICE_TYPE|Q_RES-0,5%,1~
/16W,0402LF,CHIP,C';

PART_NAME
 PR1800 'Q_RES_0402LF-3.3,1%,1/16W,CHIP,CS-3302FB00':;

SECTION_NUMBER 1
 '@T6G_MB_LIB.T6G(SCH_1):PAGE312_I256@PURE_QUANTA.Q_RES(CHIPS)':
 C_PATH='@t6g_mb_lib.t6g(sch_1):page312_i256@pure_quanta.q_res(chips)',
 CDSVAR_REPCELL_MPS='pure_quanta|Q_res',
 VAR_0_MPS='VALUE|0|TOLERANCE|5%|WATTAGE|1/16W|PACK_TYPE|0402LF|MATERIAL|CHIP|PA~
RT_NUMBER|CS00002JB38|STANDARD|End of Design|LIFECYCLE|Comp-Approve|PART_NUMBER|~
CS00002JB38|JEDEC_TYPE|R0402|ALT_SYMBOLS|(R0402-0201)|VALUE|0|TOL|5%|WATTAGE|1/1~
6W|CLASS|DISCRETE|DESCRIPTION|RESISTOR CHIP 0 1/16W +-5%(0402)|COMPONENT_TYPE|CH~
IP0402|LEAD_LENGTH||DFM_EXCLUSION||DAY|20100618|VARIANT_DEVICE_TYPE|Q_RES-0,5%,1~
/16W,0402LF,CHIP,C';

PART_NAME
 PR1332 'Q_RES_0402LF-0,5%,1/16W,CHIP,CS00002JB38':;

SECTION_NUMBER 1
 '@T6G_MB_LIB.T6G(SCH_1):PAGE312_I239@PURE_QUANTA.Q_RES(CHIPS)':
 C_PATH='@t6g_mb_lib.t6g(sch_1):page312_i239@pure_quanta.q_res(chips)',
 CDSVAR_REPCELL_MPS='pure_quanta|Q_res',
 VAR_0_MPS='VALUE|0|TOLERANCE|5%|WATTAGE|1/16W|PACK_TYPE|0402LF|MATERIAL|EMPTY|P~
ART_NUMBER|CS00002JB38|STANDARD|End of Design|LIFECYCLE|Comp-Approve|PART_NUMBER~
|CS00002JB38|JEDEC_TYPE|R0402|ALT_SYMBOLS|(R0402-0201)|VALUE|0|TOL|5%|WATTAGE|1/~
16W|CLASS|IO|DESCRIPTION|RESISTOR CHIP 0 1/16W +-5%(0402)|COMPONENT_TYPE|CHIP040~
2|LEAD_LENGTH||DFM_EXCLUSION||DAY|20100618|VARIANT_DEVICE_TYPE|Q_RES-0,5%,1/16W,~
0402LF,EMPTY,';

PART_NAME
 PR1331 'Q_RES_0402LF-0,5%,1/16W,CHIP,CS00002JB38':;

SECTION_NUMBER 1
 '@T6G_MB_LIB.T6G(SCH_1):PAGE312_I260@PURE_QUANTA.Q_RES(CHIPS)':
 C_PATH='@t6g_mb_lib.t6g(sch_1):page312_i260@pure_quanta.q_res(chips)',
 CDSVAR_REPCELL_MPS='pure_quanta|Q_res',
 VAR_0_MPS='VALUE|0|TOLERANCE|5%|WATTAGE|1/16W|PACK_TYPE|0402LF|MATERIAL|EMPTY|P~
ART_NUMBER|CS00002JB38|STANDARD|End of Design|LIFECYCLE|Comp-Approve|PART_NUMBER~
|CS00002JB38|JEDEC_TYPE|R0402|ALT_SYMBOLS|(R0402-0201)|VALUE|0|TOL|5%|WATTAGE|1/~
16W|CLASS|IO|DESCRIPTION|RESISTOR CHIP 0 1/16W +-5%(0402)|COMPONENT_TYPE|CHIP040~
2|LEAD_LENGTH||DFM_EXCLUSION||DAY|20100618|VARIANT_DEVICE_TYPE|Q_RES-0,5%,1/16W,~
0402LF,EMPTY,';

PART_NAME
 PR704 'Q_RES_0402LF-0,5%,1/16W,EMPTY,CS00002JB38':;

SECTION_NUMBER 1
 '@T6G_MB_LIB.T6G(SCH_1):PAGE312_I219@PURE_QUANTA.Q_RES(CHIPS)':
 C_PATH='@t6g_mb_lib.t6g(sch_1):page312_i219@pure_quanta.q_res(chips)',
 CDSVAR_REPCELL_MPS='pure_quanta|Q_res',
 VAR_0_MPS='VALUE|0|TOLERANCE|5%|WATTAGE|1/16W|PACK_TYPE|0402LF|MATERIAL|CHIP|PA~
RT_NUMBER|CS00002JB38|STANDARD|End of Design|LIFECYCLE|Comp-Approve|PART_NUMBER|~
CS00002JB38|JEDEC_TYPE|R0402|ALT_SYMBOLS|(R0402-0201)|VALUE|0|TOL|5%|WATTAGE|1/1~
6W|CLASS|DISCRETE|DESCRIPTION|RESISTOR CHIP 0 1/16W +-5%(0402)|COMPONENT_TYPE|CH~
IP0402|LEAD_LENGTH||DFM_EXCLUSION||DAY|20100618|VARIANT_DEVICE_TYPE|Q_RES-0,5%,1~
/16W,0402LF,CHIP,C';

PART_NAME
 PR703 'Q_RES_0402LF-0,5%,1/16W,EMPTY,CS00002JB38':;

SECTION_NUMBER 1
 '@T6G_MB_LIB.T6G(SCH_1):PAGE312_I235@PURE_QUANTA.Q_RES(CHIPS)':
 C_PATH='@t6g_mb_lib.t6g(sch_1):page312_i235@pure_quanta.q_res(chips)',
 CDSVAR_REPCELL_MPS='pure_quanta|Q_res',
 VAR_0_MPS='VALUE|0|TOLERANCE|5%|WATTAGE|1/16W|PACK_TYPE|0402LF|MATERIAL|CHIP|PA~
RT_NUMBER|CS00002JB38|STANDARD|End of Design|LIFECYCLE|Comp-Approve|PART_NUMBER|~
CS00002JB38|JEDEC_TYPE|R0402|ALT_SYMBOLS|(R0402-0201)|VALUE|0|TOL|5%|WATTAGE|1/1~
6W|CLASS|DISCRETE|DESCRIPTION|RESISTOR CHIP 0 1/16W +-5%(0402)|COMPONENT_TYPE|CH~
IP0402|LEAD_LENGTH||DFM_EXCLUSION||DAY|20100618|VARIANT_DEVICE_TYPE|Q_RES-0,5%,1~
/16W,0402LF,CHIP,C';

PART_NAME
 PR702 'Q_RES_0402LF-0,5%,1/16W,CHIP,CS00002JB38':;

SECTION_NUMBER 1
 '@T6G_MB_LIB.T6G(SCH_1):PAGE312_I210@PURE_QUANTA.Q_RES(CHIPS)':
 C_PATH='@t6g_mb_lib.t6g(sch_1):page312_i210@pure_quanta.q_res(chips)',
 CDSVAR_REPCELL_MPS='pure_quanta|Q_res',
 VAR_0_MPS='VALUE|0|TOLERANCE|5%|WATTAGE|1/16W|PACK_TYPE|0402LF|MATERIAL|EMPTY|P~
ART_NUMBER|CS00002JB38|STANDARD|End of Design|LIFECYCLE|Comp-Approve|PART_NUMBER~
|CS00002JB38|JEDEC_TYPE|R0402|ALT_SYMBOLS|(R0402-0201)|VALUE|0|TOL|5%|WATTAGE|1/~
16W|CLASS|IO|DESCRIPTION|RESISTOR CHIP 0 1/16W +-5%(0402)|COMPONENT_TYPE|CHIP040~
2|LEAD_LENGTH||DFM_EXCLUSION||DAY|20100618|VARIANT_DEVICE_TYPE|Q_RES-0,5%,1/16W,~
0402LF,EMPTY,';

PART_NAME
 PR701 'Q_RES_0402LF-0,5%,1/16W,CHIP,CS00002JB38':;

SECTION_NUMBER 1
 '@T6G_MB_LIB.T6G(SCH_1):PAGE312_I277@PURE_QUANTA.Q_RES(CHIPS)':
 C_PATH='@t6g_mb_lib.t6g(sch_1):page312_i277@pure_quanta.q_res(chips)',
 CDSVAR_REPCELL_MPS='pure_quanta|Q_res',
 VAR_0_MPS='VALUE|0|TOLERANCE|5%|WATTAGE|1/16W|PACK_TYPE|0402LF|MATERIAL|EMPTY|P~
ART_NUMBER|CS00002JB38|STANDARD|End of Design|LIFECYCLE|Comp-Approve|PART_NUMBER~
|CS00002JB38|JEDEC_TYPE|R0402|ALT_SYMBOLS|(R0402-0201)|VALUE|0|TOL|5%|WATTAGE|1/~
16W|CLASS|IO|DESCRIPTION|RESISTOR CHIP 0 1/16W +-5%(0402)|COMPONENT_TYPE|CHIP040~
2|LEAD_LENGTH||DFM_EXCLUSION||DAY|20100618|VARIANT_DEVICE_TYPE|Q_RES-0,5%,1/16W,~
0402LF,EMPTY,';

PART_NAME
 PR227 'Q_RES_0402LF-2.2,1%,1/16W,CHIP,CS-2202FB00':;

SECTION_NUMBER 1
 '@T6G_MB_LIB.T6G(SCH_1):PAGE312_I215@PURE_QUANTA.Q_RES(CHIPS)':
 C_PATH='@t6g_mb_lib.t6g(sch_1):page312_i215@pure_quanta.q_res(chips)';

PART_NAME
 PR226 'Q_RES_0402LF-2.2,1%,1/16W,CHIP,CS-2202FB00':;

SECTION_NUMBER 1
 '@T6G_MB_LIB.T6G(SCH_1):PAGE312_I232@PURE_QUANTA.Q_RES(CHIPS)':
 C_PATH='@t6g_mb_lib.t6g(sch_1):page312_i232@pure_quanta.q_res(chips)';

PART_NAME
 PR225 'Q_RES_0402LF-8.87K,1%,1/16W,EMPTY,CS28872FB01':;

SECTION_NUMBER 1
 '@T6G_MB_LIB.T6G(SCH_1):PAGE312_I213@PURE_QUANTA.Q_RES(CHIPS)':
 C_PATH='@t6g_mb_lib.t6g(sch_1):page312_i213@pure_quanta.q_res(chips)';

PART_NAME
 PR224 'Q_RES_0402LF-8.87K,1%,1/16W,EMPTY,CS28872FB01':;

SECTION_NUMBER 1
 '@T6G_MB_LIB.T6G(SCH_1):PAGE312_I202@PURE_QUANTA.Q_RES(CHIPS)':
 C_PATH='@t6g_mb_lib.t6g(sch_1):page312_i202@pure_quanta.q_res(chips)';

PART_NAME
 PL43 'Q_INDUCTOR_SMLF-100NH/16A,IND,CV+10G0MZ04':;

SECTION_NUMBER 1
 '@T6G_MB_LIB.T6G(SCH_1):PAGE312_I266@PURE_QUANTA.Q_INDUCTOR(CHIPS)':
 C_PATH='@t6g_mb_lib.t6g(sch_1):page312_i266@pure_quanta.q_inductor(chips)';

PART_NAME
 PL19 'Q_INDUCTOR_SMLF-130NH/106A,IND,CV+13^0KZ11':;

SECTION_NUMBER 1
 '@T6G_MB_LIB.T6G(SCH_1):PAGE312_I280@PURE_QUANTA.Q_INDUCTOR(CHIPS)':
 C_PATH='@t6g_mb_lib.t6g(sch_1):page312_i280@pure_quanta.q_inductor(chips)';

PART_NAME
 PL18 'Q_INDUCTOR_SMLF-130NH/106A,IND,CV+13^0KZ11':;

SECTION_NUMBER 1
 '@T6G_MB_LIB.T6G(SCH_1):PAGE312_I279@PURE_QUANTA.Q_INDUCTOR(CHIPS)':
 C_PATH='@t6g_mb_lib.t6g(sch_1):page312_i279@pure_quanta.q_inductor(chips)';

PART_NAME
 PC2171 'Q_CAPP_SMLF-470UF,2.5V,20%,EMPTY,CH747LM8816':;

SECTION_NUMBER 1
 '@T6G_MB_LIB.T6G(SCH_1):PAGE312_I272@PURE_QUANTA.Q_CAPP(CHIPS)':
 C_PATH='@t6g_mb_lib.t6g(sch_1):page312_i272@pure_quanta.q_capp(chips)';

PART_NAME
 PC1368 'Q_CAP_0402-0.1UF,25V,10%,X7R,CH4104K1B00':;

SECTION_NUMBER 1
 '@T6G_MB_LIB.T6G(SCH_1):PAGE312_I209@PURE_QUANTA.Q_CAP(CHIPS)':
 C_PATH='@t6g_mb_lib.t6g(sch_1):page312_i209@pure_quanta.q_cap(chips)',
 CDSVAR_REPCELL_MPS='pure_quanta|Q_cap',
 VAR_0_MPS='VALUE|0.1UF|VOLTAGE|25V|TOLERANCE|10%|PACK_TYPE|0402|MATERIAL|EMPTY|~
PART_NUMBER|CH4104K1B00|STANDARD||LIFECYCLE||ASS_PART||PART_NUMBER|CH4104K1B00|J~
EDEC_TYPE|C0402|ALT_SYMBOLS|(C0402_OCTAGONXA,C0402-0201)|VALUE|NA|RATED_VOLTAGE|~
25V|TOL|10%|CLASS|IO|DESCRIPTION|CAP CHIP 0.1U 25V(+-10%,X7R,0402)|COMPONENT_TYP~
E|CHIP0402|LEAD_LENGTH||LPID||DATE|20160113|VARIANT_DEVICE_TYPE|Q_CAP-0.1UF,25V,~
10%,0402,EMPTY';

PART_NAME
 PC1367 'Q_CAP_0402-0.1UF,25V,10%,X7R,CH4104K1B00':;

SECTION_NUMBER 1
 '@T6G_MB_LIB.T6G(SCH_1):PAGE312_I231@PURE_QUANTA.Q_CAP(CHIPS)':
 C_PATH='@t6g_mb_lib.t6g(sch_1):page312_i231@pure_quanta.q_cap(chips)',
 CDSVAR_REPCELL_MPS='pure_quanta|Q_cap',
 VAR_0_MPS='VALUE|0.1UF|VOLTAGE|25V|TOLERANCE|10%|PACK_TYPE|0402|MATERIAL|EMPTY|~
PART_NUMBER|CH4104K1B00|STANDARD||LIFECYCLE||ASS_PART||PART_NUMBER|CH4104K1B00|J~
EDEC_TYPE|C0402|ALT_SYMBOLS|(C0402_OCTAGONXA,C0402-0201)|VALUE|NA|RATED_VOLTAGE|~
25V|TOL|10%|CLASS|IO|DESCRIPTION|CAP CHIP 0.1U 25V(+-10%,X7R,0402)|COMPONENT_TYP~
E|CHIP0402|LEAD_LENGTH||LPID||DATE|20160113|VARIANT_DEVICE_TYPE|Q_CAP-0.1UF,25V,~
10%,0402,EMPTY';

PART_NAME
 PC1243_P1_2 'Q_CAP_C0402-2.2UF,10V,10%,X6S,CH5222KEB01':;

SECTION_NUMBER 1
 '@T6G_MB_LIB.T6G(SCH_1):PAGE312_I217@PURE_QUANTA.Q_CAP(CHIPS)':
 C_PATH='@t6g_mb_lib.t6g(sch_1):page312_i217@pure_quanta.q_cap(chips)';

PART_NAME
 PC1242_P1_1 'Q_CAP_C0402-2.2UF,10V,10%,X6S,CH5222KEB01':;

SECTION_NUMBER 1
 '@T6G_MB_LIB.T6G(SCH_1):PAGE312_I234@PURE_QUANTA.Q_CAP(CHIPS)':
 C_PATH='@t6g_mb_lib.t6g(sch_1):page312_i234@pure_quanta.q_cap(chips)';

PART_NAME
 PC621_P1_1 'Q_CAP_C0402-100NF,50V,10%,X7R,CH4106K1B01':;

SECTION_NUMBER 1
 '@T6G_MB_LIB.T6G(SCH_1):PAGE312_I281@PURE_QUANTA.Q_CAP(CHIPS)':
 C_PATH='@t6g_mb_lib.t6g(sch_1):page312_i281@pure_quanta.q_cap(chips)';

PART_NAME
 PC418 'Q_CAPP_SMLF-470UF,2.5V,20%,POSCAP,CH747LM8816':;

SECTION_NUMBER 1
 '@T6G_MB_LIB.T6G(SCH_1):PAGE312_I270@PURE_QUANTA.Q_CAPP(CHIPS)':
 C_PATH='@t6g_mb_lib.t6g(sch_1):page312_i270@pure_quanta.q_capp(chips)';

PART_NAME
 PC417 'Q_CAPP_THLF-270UF,16V,20%,OSCON,CC72703MD33':;

SECTION_NUMBER 1
 '@T6G_MB_LIB.T6G(SCH_1):PAGE312_I275@PURE_QUANTA.Q_CAPP(CHIPS)':
 C_PATH='@t6g_mb_lib.t6g(sch_1):page312_i275@pure_quanta.q_capp(chips)';

PART_NAME
 PC416 'Q_CAPP_THLF-560UF,2.5V,20%,OSCON,CC7560JMD18':;

SECTION_NUMBER 1
 '@T6G_MB_LIB.T6G(SCH_1):PAGE312_I254@PURE_QUANTA.Q_CAPP(CHIPS)':
 C_PATH='@t6g_mb_lib.t6g(sch_1):page312_i254@pure_quanta.q_capp(chips)';

PART_NAME
 PC415 'Q_CAPP_THLF-560UF,2.5V,20%,OSCON,CC7560JMD18':;

SECTION_NUMBER 1
 '@T6G_MB_LIB.T6G(SCH_1):PAGE312_I253@PURE_QUANTA.Q_CAPP(CHIPS)':
 C_PATH='@t6g_mb_lib.t6g(sch_1):page312_i253@pure_quanta.q_capp(chips)';

PART_NAME
 PC414 'Q_CAPP_THLF-560UF,2.5V,20%,OSCON,CC7560JMD18':;

SECTION_NUMBER 1
 '@T6G_MB_LIB.T6G(SCH_1):PAGE312_I252@PURE_QUANTA.Q_CAPP(CHIPS)':
 C_PATH='@t6g_mb_lib.t6g(sch_1):page312_i252@pure_quanta.q_capp(chips)';

PART_NAME
 PC413_P1_2 'Q_CAP_0805-22UF,4V,20%,X6S,TMP_QCH622KMEA01':;

SECTION_NUMBER 1
 '@T6G_MB_LIB.T6G(SCH_1):PAGE312_I249@PURE_QUANTA.Q_CAP(CHIPS)':
 C_PATH='@t6g_mb_lib.t6g(sch_1):page312_i249@pure_quanta.q_cap(chips)';

PART_NAME
 PC412_P1_1 'Q_CAP_0805-22UF,4V,20%,X6S,TMP_QCH622KMEA01':;

SECTION_NUMBER 1
 '@T6G_MB_LIB.T6G(SCH_1):PAGE312_I268@PURE_QUANTA.Q_CAP(CHIPS)':
 C_PATH='@t6g_mb_lib.t6g(sch_1):page312_i268@pure_quanta.q_cap(chips)';

PART_NAME
 PC411_P1_2 'Q_CAP_0805-22UF,4V,20%,X6S,TMP_QCH622KMEA01':;

SECTION_NUMBER 1
 '@T6G_MB_LIB.T6G(SCH_1):PAGE312_I248@PURE_QUANTA.Q_CAP(CHIPS)':
 C_PATH='@t6g_mb_lib.t6g(sch_1):page312_i248@pure_quanta.q_cap(chips)';

PART_NAME
 PC410_P1_1 'Q_CAP_0805-22UF,4V,20%,X6S,TMP_QCH622KMEA01':;

SECTION_NUMBER 1
 '@T6G_MB_LIB.T6G(SCH_1):PAGE312_I265@PURE_QUANTA.Q_CAP(CHIPS)':
 C_PATH='@t6g_mb_lib.t6g(sch_1):page312_i265@pure_quanta.q_cap(chips)';

PART_NAME
 PC408_P1_2 'Q_CAP_C0402-1UF,16V,10%,X6S,CH5103KEB01':;

SECTION_NUMBER 1
 '@T6G_MB_LIB.T6G(SCH_1):PAGE312_I282@PURE_QUANTA.Q_CAP(CHIPS)':
 C_PATH='@t6g_mb_lib.t6g(sch_1):page312_i282@pure_quanta.q_cap(chips)';

PART_NAME
 PC406_P1_2 'Q_CAP_C0805-22UF,16V,20%,X6S,CH6223MEA00':;

SECTION_NUMBER 1
 '@T6G_MB_LIB.T6G(SCH_1):PAGE312_I245@PURE_QUANTA.Q_CAP(CHIPS)':
 C_PATH='@t6g_mb_lib.t6g(sch_1):page312_i245@pure_quanta.q_cap(chips)';

PART_NAME
 PC405_P1_1 'Q_CAP_C0805-22UF,16V,20%,X6S,CH6223MEA00':;

SECTION_NUMBER 1
 '@T6G_MB_LIB.T6G(SCH_1):PAGE312_I259@PURE_QUANTA.Q_CAP(CHIPS)':
 C_PATH='@t6g_mb_lib.t6g(sch_1):page312_i259@pure_quanta.q_cap(chips)';

PART_NAME
 PC404_P1_2 'Q_CAP_C0805-22UF,16V,20%,X6S,CH6223MEA00':;

SECTION_NUMBER 1
 '@T6G_MB_LIB.T6G(SCH_1):PAGE312_I244@PURE_QUANTA.Q_CAP(CHIPS)':
 C_PATH='@t6g_mb_lib.t6g(sch_1):page312_i244@pure_quanta.q_cap(chips)';

PART_NAME
 PC403_P1_1 'Q_CAP_C0805-22UF,16V,20%,X6S,CH6223MEA00':;

SECTION_NUMBER 1
 '@T6G_MB_LIB.T6G(SCH_1):PAGE312_I258@PURE_QUANTA.Q_CAP(CHIPS)':
 C_PATH='@t6g_mb_lib.t6g(sch_1):page312_i258@pure_quanta.q_cap(chips)';

PART_NAME
 PC402 'Q_CAP_C0402-100NF,50V,10%,X7R,CH4106K1B01':;

SECTION_NUMBER 1
 '@T6G_MB_LIB.T6G(SCH_1):PAGE312_I241@PURE_QUANTA.Q_CAP(CHIPS)':
 C_PATH='@t6g_mb_lib.t6g(sch_1):page312_i241@pure_quanta.q_cap(chips)';

PART_NAME
 PC401 'Q_CAP_C0402-100NF,50V,10%,X7R,CH4106K1B01':;

SECTION_NUMBER 1
 '@T6G_MB_LIB.T6G(SCH_1):PAGE312_I261@PURE_QUANTA.Q_CAP(CHIPS)':
 C_PATH='@t6g_mb_lib.t6g(sch_1):page312_i261@pure_quanta.q_cap(chips)';

PART_NAME
 PC400_P1_2 'Q_CAP_C0402-1UF,16V,10%,X6S,CH5103KEB01':;

SECTION_NUMBER 1
 '@T6G_MB_LIB.T6G(SCH_1):PAGE312_I243@PURE_QUANTA.Q_CAP(CHIPS)':
 C_PATH='@t6g_mb_lib.t6g(sch_1):page312_i243@pure_quanta.q_cap(chips)';

PART_NAME
 PC399_P1_1 'Q_CAP_C0402-1UF,16V,10%,X6S,CH5103KEB01':;

SECTION_NUMBER 1
 '@T6G_MB_LIB.T6G(SCH_1):PAGE312_I257@PURE_QUANTA.Q_CAP(CHIPS)':
 C_PATH='@t6g_mb_lib.t6g(sch_1):page312_i257@pure_quanta.q_cap(chips)';

PART_NAME
 PC398_P1_2 'Q_CAP_0402-3300PF,50V,10%,X7R,TMP_QCH2336K1B12':;

SECTION_NUMBER 1
 '@T6G_MB_LIB.T6G(SCH_1):PAGE312_I223@PURE_QUANTA.Q_CAP(CHIPS)':
 C_PATH='@t6g_mb_lib.t6g(sch_1):page312_i223@pure_quanta.q_cap(chips)';

PART_NAME
 PC397_P1_1 'Q_CAP_0402-3300PF,50V,10%,X7R,TMP_QCH2336K1B12':;

SECTION_NUMBER 1
 '@T6G_MB_LIB.T6G(SCH_1):PAGE312_I238@PURE_QUANTA.Q_CAP(CHIPS)':
 C_PATH='@t6g_mb_lib.t6g(sch_1):page312_i238@pure_quanta.q_cap(chips)';

PART_NAME
 PC396 'Q_CAP_C0402-2.2UF,10V,10%,X6S,CH5222KEB01':;

SECTION_NUMBER 1
 '@T6G_MB_LIB.T6G(SCH_1):PAGE312_I214@PURE_QUANTA.Q_CAP(CHIPS)':
 C_PATH='@t6g_mb_lib.t6g(sch_1):page312_i214@pure_quanta.q_cap(chips)';

PART_NAME
 PC395 'Q_CAP_C0402-2.2UF,10V,10%,X6S,CH5222KEB01':;

SECTION_NUMBER 1
 '@T6G_MB_LIB.T6G(SCH_1):PAGE312_I230@PURE_QUANTA.Q_CAP(CHIPS)':
 C_PATH='@t6g_mb_lib.t6g(sch_1):page312_i230@pure_quanta.q_cap(chips)';

PART_NAME
 PU18 'ISL69260IRAZT-ISL69260IRAZ-T,SMLF,IC,AL069260000':;

SECTION_NUMBER 1
 '@T6G_MB_LIB.T6G(SCH_1):PAGE319_I243@PURE_QUANTA.ISL69260IRAZT(CHIPS)':
 C_PATH='@t6g_mb_lib.t6g(sch_1):page319_i243@pure_quanta.isl69260irazt(chips)';

PART_NAME
 PR1747 'Q_RES_0402LF-100,1%,1/16W,CHIP,TMP_QCS11002FB22':;

SECTION_NUMBER 1
 '@T6G_MB_LIB.T6G(SCH_1):PAGE319_I217@PURE_QUANTA.Q_RES(CHIPS)':
 C_PATH='@t6g_mb_lib.t6g(sch_1):page319_i217@pure_quanta.q_res(chips)';

PART_NAME
 PR1718 'Q_RES_0402LF-49.9     ,1%  ,1/16W,CHIP,CS04992FB31':;

SECTION_NUMBER 1
 '@T6G_MB_LIB.T6G(SCH_1):PAGE319_I216@PURE_QUANTA.Q_RES(CHIPS)':
 C_PATH='@t6g_mb_lib.t6g(sch_1):page319_i216@pure_quanta.q_res(chips)';

PART_NAME
 PR1410 'Q_RES_0402LF-49.9     ,1%  ,1/16W,CHIP,CS04992FB31':;

SECTION_NUMBER 1
 '@T6G_MB_LIB.T6G(SCH_1):PAGE319_I202@PURE_QUANTA.Q_RES(CHIPS)':
 C_PATH='@t6g_mb_lib.t6g(sch_1):page319_i202@pure_quanta.q_res(chips)',
 CDSVAR_REPCELL_MPS='pure_quanta|Q_res',
 VAR_0_MPS='VALUE|15K|TOLERANCE|1%|WATTAGE|1/16W|PACK_TYPE|0402LF|MATERIAL|CHIP|~
PART_NUMBER|TMP_QCS31502FB24|STANDARD|End of Design|LIFECYCLE|Comp-Approve|PART_~
NUMBER|CS31502FB24|JEDEC_TYPE|R0402|ALT_SYMBOLS|(R0402-0201)|VALUE|15K|TOL|1%|WA~
TTAGE|1/16W |CLASS|DISCRETE|DESCRIPTION|RES CHIP 15K 1/16W +-1% (0402)|COMPONENT~
_TYPE|CHIP0402|LEAD_LENGTH||DFM_EXCLUSION||DAY||VARIANT_DEVICE_TYPE|Q_RES-15K,1%~
,1/16W,0402LF,CHIP';

PART_NAME
 PR1400 'Q_RES_0402LF-49.9     ,1%  ,1/16W,CHIP,CS04992FB31':;

SECTION_NUMBER 1
 '@T6G_MB_LIB.T6G(SCH_1):PAGE319_I203@PURE_QUANTA.Q_RES(CHIPS)':
 C_PATH='@t6g_mb_lib.t6g(sch_1):page319_i203@pure_quanta.q_res(chips)',
 CDSVAR_REPCELL_MPS='pure_quanta|Q_res',
 VAR_0_MPS='VALUE|49.9     |TOLERANCE|1%  |WATTAGE|1/16W|PACK_TYPE|0402LF|MATERI~
AL|EMPTY|PART_NUMBER|CS04992FB31|STANDARD|End of Design|LIFECYCLE|Comp-Approve|P~
ART_NUMBER|CS04992FB31|JEDEC_TYPE|R0402|ALT_SYMBOLS|(R0402-0201)|VALUE|49.9|TOL|~
1%|WATTAGE|1/16W |CLASS|IO|DESCRIPTION|RES CHIP 49.9 1/16W +-1% (0402)|COMPONENT~
_TYPE|CHIP0402|LEAD_LENGTH||DFM_EXCLUSION||DAY|20100716|VARIANT_DEVICE_TYPE|Q_RE~
S-49.9     ,1%  ,1/16W,040';

PART_NAME
 PR1315 'Q_RES_0402LF-0,5%,1/16W,CHIP,CS00002JB38':;

SECTION_NUMBER 1
 '@T6G_MB_LIB.T6G(SCH_1):PAGE319_I259@PURE_QUANTA.Q_RES(CHIPS)':
 C_PATH='@t6g_mb_lib.t6g(sch_1):page319_i259@pure_quanta.q_res(chips)',
 CDSVAR_REPCELL_MPS='pure_quanta|Q_res',
 VAR_0_MPS='VALUE|0|TOLERANCE|5%|WATTAGE|1/16W|PACK_TYPE|0402LF|MATERIAL|EMPTY|P~
ART_NUMBER|CS00002JB38|STANDARD|End of Design|LIFECYCLE|Comp-Approve|PART_NUMBER~
|CS00002JB38|JEDEC_TYPE|R0402|ALT_SYMBOLS|(R0402-0201)|VALUE|0|TOL|5%|WATTAGE|1/~
16W|CLASS|IO|DESCRIPTION|RESISTOR CHIP 0 1/16W +-5%(0402)|COMPONENT_TYPE|CHIP040~
2|LEAD_LENGTH||DFM_EXCLUSION||DAY|20100618|VARIANT_DEVICE_TYPE|Q_RES-0,5%,1/16W,~
0402LF,EMPTY,';

PART_NAME
 PR705 'Q_RES_0402LF-10K,1%,1/16W,EMPTY,CS31002FB08':;

SECTION_NUMBER 1
 '@T6G_MB_LIB.T6G(SCH_1):PAGE319_I263@PURE_QUANTA.Q_RES(CHIPS)':
 C_PATH='@t6g_mb_lib.t6g(sch_1):page319_i263@pure_quanta.q_res(chips)',
 CDSVAR_REPCELL_MPS='pure_quanta|Q_res',
 VAR_0_MPS='VALUE|10K|TOLERANCE|1%|WATTAGE|1/16W|PACK_TYPE|0402LF|MATERIAL|CHIP|~
PART_NUMBER|CS31002FB08|STANDARD|End of Design|LIFECYCLE|Comp-Approve|PART_NUMBE~
R|CS31002FB08|JEDEC_TYPE|R0402|ALT_SYMBOLS|(R0402-0201)|VALUE|10K|TOL|1%|WATTAGE~
|1/16W|CLASS|DISCRETE|DESCRIPTION|RES CHIP 10K 1/16W +-1%(0402)EF|COMPONENT_TYPE~
|CHIPR0402|LEAD_LENGTH||DFM_EXCLUSION||DAY|20180208|VARIANT_DEVICE_TYPE|Q_RES-10~
K,1%,1/16W,0402LF,CHIP';

PART_NAME
 PR559 'Q_RES_0402LF-100,1%,1/16W,CHIP,TMP_QCS11002FB22':;

SECTION_NUMBER 1
 '@T6G_MB_LIB.T6G(SCH_1):PAGE319_I223@PURE_QUANTA.Q_RES(CHIPS)':
 C_PATH='@t6g_mb_lib.t6g(sch_1):page319_i223@pure_quanta.q_res(chips)';

PART_NAME
 PR558 'Q_RES_0402LF-100,1%,1/16W,CHIP,TMP_QCS11002FB22':;

SECTION_NUMBER 1
 '@T6G_MB_LIB.T6G(SCH_1):PAGE319_I206@PURE_QUANTA.Q_RES(CHIPS)':
 C_PATH='@t6g_mb_lib.t6g(sch_1):page319_i206@pure_quanta.q_res(chips)';

PART_NAME
 PR410 'Q_RES_0402LF-0,5%,1/16W,EMPTY,CS00002JB38':;

SECTION_NUMBER 1
 '@T6G_MB_LIB.T6G(SCH_1):PAGE319_I260@PURE_QUANTA.Q_RES(CHIPS)':
 C_PATH='@t6g_mb_lib.t6g(sch_1):page319_i260@pure_quanta.q_res(chips)',
 CDSVAR_REPCELL_MPS='pure_quanta|Q_res',
 VAR_0_MPS='VALUE|0|TOLERANCE|5%|WATTAGE|1/16W|PACK_TYPE|0402LF|MATERIAL|CHIP|PA~
RT_NUMBER|CS00002JB38|STANDARD|End of Design|LIFECYCLE|Comp-Approve|PART_NUMBER|~
CS00002JB38|JEDEC_TYPE|R0402|ALT_SYMBOLS|(R0402-0201)|VALUE|0|TOL|5%|WATTAGE|1/1~
6W|CLASS|DISCRETE|DESCRIPTION|RESISTOR CHIP 0 1/16W +-5%(0402)|COMPONENT_TYPE|CH~
IP0402|LEAD_LENGTH||DFM_EXCLUSION||DAY|20100618|VARIANT_DEVICE_TYPE|Q_RES-0,5%,1~
/16W,0402LF,CHIP,C';

PART_NAME
 PR223 'Q_RES_0402LF-1K,1%,1/16W,CHIP,TMP_QCS21002FB24':;

SECTION_NUMBER 1
 '@T6G_MB_LIB.T6G(SCH_1):PAGE319_I261@PURE_QUANTA.Q_RES(CHIPS)':
 C_PATH='@t6g_mb_lib.t6g(sch_1):page319_i261@pure_quanta.q_res(chips)';

PART_NAME
 PR220 'Q_RES_0402LF-1,1%,1/16W,CHIP,CS-1002FB23':;

SECTION_NUMBER 1
 '@T6G_MB_LIB.T6G(SCH_1):PAGE319_I274@PURE_QUANTA.Q_RES(CHIPS)':
 C_PATH='@t6g_mb_lib.t6g(sch_1):page319_i274@pure_quanta.q_res(chips)';

PART_NAME
 PR218 'Q_RES_0402LF-1K,1%,1/16W,EMPTY,TMP_QCS21002FB24':;

SECTION_NUMBER 1
 '@T6G_MB_LIB.T6G(SCH_1):PAGE319_I238@PURE_QUANTA.Q_RES(CHIPS)':
 C_PATH='@t6g_mb_lib.t6g(sch_1):page319_i238@pure_quanta.q_res(chips)',
 CDSVAR_REPCELL_MPS='pure_quanta|Q_res',
 VAR_0_MPS='VALUE|1K|TOLERANCE|1%|WATTAGE|1/16W|PACK_TYPE|0402LF|MATERIAL|CHIP|P~
ART_NUMBER|TMP_QCS21002FB24|STANDARD|End of Design|LIFECYCLE|Comp-Approve|PART_N~
UMBER|CS21002FB24|JEDEC_TYPE|R0402|ALT_SYMBOLS|(R0402-0201)|VALUE|1K|TOL|1%|WATT~
AGE|1/16W|CLASS|DISCRETE|DESCRIPTION|RES CHIP 1K 1/16W +-1% (0402)|COMPONENT_TYP~
E|CHIP0402|LEAD_LENGTH||DFM_EXCLUSION||DAY||VARIANT_DEVICE_TYPE|Q_RES-1K,1%,1/16~
W,0402LF,CHIP,';

PART_NAME
 PR217 'Q_RES_0402LF-1K,1%,1/16W,CHIP,TMP_QCS21002FB24':;

SECTION_NUMBER 1
 '@T6G_MB_LIB.T6G(SCH_1):PAGE319_I247@PURE_QUANTA.Q_RES(CHIPS)':
 C_PATH='@t6g_mb_lib.t6g(sch_1):page319_i247@pure_quanta.q_res(chips)';

PART_NAME
 PR216 'Q_RES_0402LF-0,5%,1/16W,CHIP,CS00002JB38':;

SECTION_NUMBER 1
 '@T6G_MB_LIB.T6G(SCH_1):PAGE319_I252@PURE_QUANTA.Q_RES(CHIPS)':
 C_PATH='@t6g_mb_lib.t6g(sch_1):page319_i252@pure_quanta.q_res(chips)';

PART_NAME
 PR215 'Q_RES_0402LF-1K,1%,1/16W,CHIP,TMP_QCS21002FB24':;

SECTION_NUMBER 1
 '@T6G_MB_LIB.T6G(SCH_1):PAGE319_I245@PURE_QUANTA.Q_RES(CHIPS)':
 C_PATH='@t6g_mb_lib.t6g(sch_1):page319_i245@pure_quanta.q_res(chips)';

PART_NAME
 PR214 'Q_RES_0402LF-1K,1%,1/16W,EMPTY,TMP_QCS21002FB24':;

SECTION_NUMBER 1
 '@T6G_MB_LIB.T6G(SCH_1):PAGE319_I236@PURE_QUANTA.Q_RES(CHIPS)':
 C_PATH='@t6g_mb_lib.t6g(sch_1):page319_i236@pure_quanta.q_res(chips)',
 CDSVAR_REPCELL_MPS='pure_quanta|Q_res',
 VAR_0_MPS='VALUE|0|TOLERANCE|5%|WATTAGE|1/16W|PACK_TYPE|0402LF|MATERIAL|CHIP|PA~
RT_NUMBER|CS00002JB38|STANDARD|End of Design|LIFECYCLE|Comp-Approve|PART_NUMBER|~
CS00002JB38|JEDEC_TYPE|R0402|ALT_SYMBOLS|(R0402-0201)|VALUE|0|TOL|5%|WATTAGE|1/1~
6W|CLASS|DISCRETE|DESCRIPTION|RESISTOR CHIP 0 1/16W +-5%(0402)|COMPONENT_TYPE|CH~
IP0402|LEAD_LENGTH||DFM_EXCLUSION||DAY|20100618|VARIANT_DEVICE_TYPE|Q_RES-0,5%,1~
/16W,0402LF,CHIP,C';

PART_NAME
 PR213 'Q_RES_0402LF-0,5%,1/16W,CHIP,CS00002JB38':;

SECTION_NUMBER 1
 '@T6G_MB_LIB.T6G(SCH_1):PAGE319_I226@PURE_QUANTA.Q_RES(CHIPS)':
 C_PATH='@t6g_mb_lib.t6g(sch_1):page319_i226@pure_quanta.q_res(chips)';

PART_NAME
 PR212 'Q_RES_0402LF-0,5%,1/16W,CHIP,CS00002JB38':;

SECTION_NUMBER 1
 '@T6G_MB_LIB.T6G(SCH_1):PAGE319_I225@PURE_QUANTA.Q_RES(CHIPS)':
 C_PATH='@t6g_mb_lib.t6g(sch_1):page319_i225@pure_quanta.q_res(chips)';

PART_NAME
 PR211 'Q_RES_0402LF-0,5%,1/16W,CHIP,CS00002JB38':;

SECTION_NUMBER 1
 '@T6G_MB_LIB.T6G(SCH_1):PAGE319_I227@PURE_QUANTA.Q_RES(CHIPS)':
 C_PATH='@t6g_mb_lib.t6g(sch_1):page319_i227@pure_quanta.q_res(chips)';

PART_NAME
 PR210 'Q_RES_0402LF-0,5%,1/16W,CHIP,CS00002JB38':;

SECTION_NUMBER 1
 '@T6G_MB_LIB.T6G(SCH_1):PAGE319_I228@PURE_QUANTA.Q_RES(CHIPS)':
 C_PATH='@t6g_mb_lib.t6g(sch_1):page319_i228@pure_quanta.q_res(chips)';

PART_NAME
 PR209 'Q_RES_0402LF-150,1%,1/16W,CHIP,TMP_QCS11502FB21':;

SECTION_NUMBER 1
 '@T6G_MB_LIB.T6G(SCH_1):PAGE319_I229@PURE_QUANTA.Q_RES(CHIPS)':
 C_PATH='@t6g_mb_lib.t6g(sch_1):page319_i229@pure_quanta.q_res(chips)';

PART_NAME
 PR208 'Q_RES_0402LF-0,5%,1/16W,CHIP,CS00002JB38':;

SECTION_NUMBER 1
 '@T6G_MB_LIB.T6G(SCH_1):PAGE319_I230@PURE_QUANTA.Q_RES(CHIPS)':
 C_PATH='@t6g_mb_lib.t6g(sch_1):page319_i230@pure_quanta.q_res(chips)';

PART_NAME
 PR207 'Q_RES_0402LF-0,5%,1/16W,CHIP,CS00002JB38':;

SECTION_NUMBER 1
 '@T6G_MB_LIB.T6G(SCH_1):PAGE319_I232@PURE_QUANTA.Q_RES(CHIPS)':
 C_PATH='@t6g_mb_lib.t6g(sch_1):page319_i232@pure_quanta.q_res(chips)';

PART_NAME
 PR206 'Q_RES_0402LF-1K,1%,1/16W,CHIP,TMP_QCS21002FB24':;

SECTION_NUMBER 1
 '@T6G_MB_LIB.T6G(SCH_1):PAGE319_I233@PURE_QUANTA.Q_RES(CHIPS)':
 C_PATH='@t6g_mb_lib.t6g(sch_1):page319_i233@pure_quanta.q_res(chips)';

PART_NAME
 PR203 'Q_RES_0402LF-30.1K    ,1%  ,1/16W,CHIP,CS33012FB18':;

SECTION_NUMBER 1
 '@T6G_MB_LIB.T6G(SCH_1):PAGE319_I201@PURE_QUANTA.Q_RES(CHIPS)':
 C_PATH='@t6g_mb_lib.t6g(sch_1):page319_i201@pure_quanta.q_res(chips)',
 CDSVAR_REPCELL_MPS='pure_quanta|Q_res',
 VAR_0_MPS='VALUE|110|TOLERANCE|1%|WATTAGE|1/16W|PACK_TYPE|0402LF|MATERIAL|CHIP|~
PART_NUMBER|TMP_QCS11102FB18|STANDARD|End of Design|LIFECYCLE|Comp-Approve|PART_~
NUMBER|CS11102FB18|JEDEC_TYPE|R0402|ALT_SYMBOLS|(R0402-0201)|VALUE|110|TOL|1%|WA~
TTAGE|1/16W|CLASS|DISCRETE|DESCRIPTION|110ohm 0402|COMPONENT_TYPE|CHIP0402|LEAD_~
LENGTH||DFM_EXCLUSION||DAY||VARIANT_DEVICE_TYPE|Q_RES-110,1%,1/16W,0402LF,CHIP';

PART_NAME
 PR202 'Q_RES_0402LF-28K,1%,1/16W,EMPTY,CS32802FB05':;

SECTION_NUMBER 1
 '@T6G_MB_LIB.T6G(SCH_1):PAGE319_I204@PURE_QUANTA.Q_RES(CHIPS)':
 C_PATH='@t6g_mb_lib.t6g(sch_1):page319_i204@pure_quanta.q_res(chips)',
 CDSVAR_REPCELL_MPS='pure_quanta|Q_res',
 VAR_0_MPS='VALUE|3.32K|TOLERANCE|1%|WATTAGE|1/16W|PACK_TYPE|0402LF|MATERIAL|CHI~
P|PART_NUMBER|CS23322FB20|STANDARD|End of Design|LIFECYCLE|Comp-Approve|PART_NUM~
BER|CS23322FB20|JEDEC_TYPE|R0402|ALT_SYMBOLS|(R0402-0201)|VALUE|3.32K|TOL|1%|WAT~
TAGE|1/16W|CLASS|DISCRETE|DESCRIPTION|RES CHIP 3.32K 1/16W +-1% (0402)|COMPONENT~
_TYPE|CHIP0402|LEAD_LENGTH||DFM_EXCLUSION||DAY|20140826|VARIANT_DEVICE_TYPE|Q_RE~
S-3.32K,1%,1/16W,0402LF,CH';

PART_NAME
 PJ48 'Q_SHORT_SM-EMPTY,SHORT6':;

SECTION_NUMBER 1
 '@T6G_MB_LIB.T6G(SCH_1):PAGE319_I207@PURE_QUANTA.Q_SHORT(CHIPS)':
 C_PATH='@t6g_mb_lib.t6g(sch_1):page319_i207@pure_quanta.q_short(chips)';

PART_NAME
 PC1337 'Q_CAP_0402-0.1UF,25V,10%,X7R,CH4104K1B00':;

SECTION_NUMBER 1
 '@T6G_MB_LIB.T6G(SCH_1):PAGE319_I215@PURE_QUANTA.Q_CAP(CHIPS)':
 C_PATH='@t6g_mb_lib.t6g(sch_1):page319_i215@pure_quanta.q_cap(chips)';

PART_NAME
 PC1336 'Q_CAP_C0402-10UF,6.3V,20%,X6S,CH6101MEB01':;

SECTION_NUMBER 1
 '@T6G_MB_LIB.T6G(SCH_1):PAGE319_I210@PURE_QUANTA.Q_CAP(CHIPS)':
 C_PATH='@t6g_mb_lib.t6g(sch_1):page319_i210@pure_quanta.q_cap(chips)';

PART_NAME
 PC1289 'Q_CAP_C0402-1UF,16V,10%,X6S,CH5103KEB01':;

SECTION_NUMBER 1
 '@T6G_MB_LIB.T6G(SCH_1):PAGE319_I256@PURE_QUANTA.Q_CAP(CHIPS)':
 C_PATH='@t6g_mb_lib.t6g(sch_1):page319_i256@pure_quanta.q_cap(chips)';

PART_NAME
 PC814 'Q_CAP_C0402-1UF,16V,10%,X6S,CH5103KEB01':;

SECTION_NUMBER 1
 '@T6G_MB_LIB.T6G(SCH_1):PAGE319_I241@PURE_QUANTA.Q_CAP(CHIPS)':
 C_PATH='@t6g_mb_lib.t6g(sch_1):page319_i241@pure_quanta.q_cap(chips)',
 CDSVAR_REPCELL_MPS='pure_quanta|Q_cap',
 VAR_0_MPS='VALUE|1UF|VOLTAGE|16V|TOLERANCE|10%|PACK_TYPE|C0402|MATERIAL|EMPTY|P~
ART_NUMBER|CH5103KEB01|STANDARD||LIFECYCLE||ASS_PART||PART_NUMBER|CH5103KEB01|JE~
DEC_TYPE|C0402|ALT_SYMBOLS|(C0402-0201)|VALUE|NA|RATED_VOLTAGE|16V|TOL|10%|CLASS~
|IO|DESCRIPTION|CAP CHIP 1UF 16V(10%,X6S,0402)|COMPONENT_TYPE|CHIP0402|LEAD_LENG~
TH||LPID||DATE|20140828|VARIANT_DEVICE_TYPE|Q_CAP-1UF,16V,10%,C0402,EMPTY,';

PART_NAME
 PC394 'Q_CAP_C0402-1UF,16V,10%,X6S,CH5103KEB01':;

SECTION_NUMBER 1
 '@T6G_MB_LIB.T6G(SCH_1):PAGE319_I258@PURE_QUANTA.Q_CAP(CHIPS)':
 C_PATH='@t6g_mb_lib.t6g(sch_1):page319_i258@pure_quanta.q_cap(chips)';

PART_NAME
 PC393 'Q_CAP_0402-470PF,50V,10%,X7R,TMP_QCH14706KB18':;

SECTION_NUMBER 1
 '@T6G_MB_LIB.T6G(SCH_1):PAGE319_I251@PURE_QUANTA.Q_CAP(CHIPS)':
 C_PATH='@t6g_mb_lib.t6g(sch_1):page319_i251@pure_quanta.q_cap(chips)',
 CDSVAR_REPCELL_MPS='pure_quanta|Q_cap',
 VAR_0_MPS='VALUE|0.01UF|VOLTAGE|25V|TOLERANCE|10%|PACK_TYPE|0402|MATERIAL|X7R|P~
ART_NUMBER|TMP_QCH31004KB17|STANDARD|End of Design|LIFECYCLE|Comp-Approve|ASS_PA~
RT||PART_NUMBER|CH31004KB17|JEDEC_TYPE|C0402|ALT_SYMBOLS|(C0402-0201)|VALUE|0.01~
UF|RATED_VOLTAGE|25V|TOL|10%|CLASS|DISCRETE|DESCRIPTION|CAP CHIP 0.01U 25V(+-10%~
,X7R,0402)|COMPONENT_TYPE|CHIP0402|LEAD_LENGTH||LPID||DATE|20100528|VARIANT_DEVI~
CE_TYPE|Q_CAP-0.01UF,25V,10%,0402,X7R,';

PART_NAME
 PC392 'Q_CAP_0402-4.7UF,6.3V,20%,X6S,CH5471MEB01':;

SECTION_NUMBER 1
 '@T6G_MB_LIB.T6G(SCH_1):PAGE319_I255@PURE_QUANTA.Q_CAP(CHIPS)':
 C_PATH='@t6g_mb_lib.t6g(sch_1):page319_i255@pure_quanta.q_cap(chips)',
 CDSVAR_REPCELL_MPS='pure_quanta|Q_cap',
 VAR_0_MPS='VALUE|4.7UF|VOLTAGE|6.3V|TOLERANCE|20%|PACK_TYPE|0402|MATERIAL|EMPTY~
|PART_NUMBER|CH5471MEB01|STANDARD||LIFECYCLE||ASS_PART||PART_NUMBER|CH5471MEB01|~
JEDEC_TYPE|C0402|ALT_SYMBOLS|(C0402_OCTAGON,C0402_OCTAGONXA,C0402-0201)|VALUE|NA~
|RATED_VOLTAGE|6.3V|TOL|20%|CLASS|IO|DESCRIPTION|CAP CHIP 4.7UF 6.3V(+-20%,X6S,0~
402)|COMPONENT_TYPE|CHIP0402|LEAD_LENGTH||LPID||DATE|20151211|VARIANT_DEVICE_TYP~
E|Q_CAP-4.7UF,6.3V,20%,0402,EMPT';

PART_NAME
 PC391 'Q_CAP_C0402-100NF,50V,10%,EMPTY,CH4106K1B01':;

SECTION_NUMBER 1
 '@T6G_MB_LIB.T6G(SCH_1):PAGE319_I257@PURE_QUANTA.Q_CAP(CHIPS)':
 C_PATH='@t6g_mb_lib.t6g(sch_1):page319_i257@pure_quanta.q_cap(chips)';

PART_NAME
 PC390 'Q_CAP_0402-0.1UF,25V,10%,X7R,CH4104K1B00':;

SECTION_NUMBER 1
 '@T6G_MB_LIB.T6G(SCH_1):PAGE319_I240@PURE_QUANTA.Q_CAP(CHIPS)':
 C_PATH='@t6g_mb_lib.t6g(sch_1):page319_i240@pure_quanta.q_cap(chips)';

PART_NAME
 PC389 'Q_CAP_0402-3300PF,50V,10%,X7R,TMP_QCH2336K1B12':;

SECTION_NUMBER 1
 '@T6G_MB_LIB.T6G(SCH_1):PAGE319_I248@PURE_QUANTA.Q_CAP(CHIPS)':
 C_PATH='@t6g_mb_lib.t6g(sch_1):page319_i248@pure_quanta.q_cap(chips)',
 CDSVAR_REPCELL_MPS='pure_quanta|Q_cap',
 VAR_0_MPS='VALUE|3300PF|VOLTAGE|50V|TOLERANCE|10%|PACK_TYPE|C0402|MATERIAL|EMPT~
Y|PART_NUMBER|CH2336K1B06|STANDARD||LIFECYCLE||ASS_PART||PART_NUMBER|CH2336K1B06~
|JEDEC_TYPE|C0402|ALT_SYMBOLS|(C0402-0201)|VALUE|NA|RATED_VOLTAGE|50V|TOL|10%|CL~
ASS|IO|DESCRIPTION|CAP CHIP 3300P 50V(+-10%,X7R,0402)MUR|COMPONENT_TYPE|CHIP0402~
|LEAD_LENGTH||LPID||DATE|20150617|VARIANT_DEVICE_TYPE|Q_CAP-3300PF,50V,10%,C0402~
,EMP';

PART_NAME
 PC388 'Q_CAP_0402-1000PF,50V,5%,EMPTY,TMP_QCH21006JB10':;

SECTION_NUMBER 1
 '@T6G_MB_LIB.T6G(SCH_1):PAGE319_I253@PURE_QUANTA.Q_CAP(CHIPS)':
 C_PATH='@t6g_mb_lib.t6g(sch_1):page319_i253@pure_quanta.q_cap(chips)';

PART_NAME
 PC386 'Q_CAP_0402-0.1UF,25V,10%,X7R,CH4104K1B00':;

SECTION_NUMBER 1
 '@T6G_MB_LIB.T6G(SCH_1):PAGE319_I237@PURE_QUANTA.Q_CAP(CHIPS)':
 C_PATH='@t6g_mb_lib.t6g(sch_1):page319_i237@pure_quanta.q_cap(chips)',
 CDSVAR_REPCELL_MPS='pure_quanta|Q_cap',
 VAR_0_MPS='VALUE|0.1UF|VOLTAGE|25V|TOLERANCE|10%|PACK_TYPE|0402|MATERIAL|EMPTY|~
PART_NUMBER|CH4104K1B00|STANDARD||LIFECYCLE||ASS_PART||PART_NUMBER|CH4104K1B00|J~
EDEC_TYPE|C0402|ALT_SYMBOLS|(C0402_OCTAGONXA,C0402-0201)|VALUE|NA|RATED_VOLTAGE|~
25V|TOL|10%|CLASS|IO|DESCRIPTION|CAP CHIP 0.1U 25V(+-10%,X7R,0402)|COMPONENT_TYP~
E|CHIP0402|LEAD_LENGTH||LPID||DATE|20160113|VARIANT_DEVICE_TYPE|Q_CAP-0.1UF,25V,~
10%,0402,EMPTY';

PART_NAME
 PU17 'RAA2213404GNPHB0-RAA2213404GNP#HB0,SMLF,IC,AL221340000':;

SECTION_NUMBER 1
 '@T6G_MB_LIB.T6G(SCH_1):PAGE320_I38@PURE_QUANTA.RAA2213404GNPHB0(CHIPS)':
 C_PATH='@t6g_mb_lib.t6g(sch_1):page320_i38@pure_quanta.raa2213404gnphb0(chips)',
 CDSVAR_REPCELL_MPS='pure_quanta|mp86950glvtz',
 VAR_0_MPS='VAR_REPLACED|RAA2213404GNPHB0|VAR_PARTNAME|MP86950GLVTZ|VALUE|MP8695~
0GLVT-Z|PART_TYPE|SMLF|MATERIAL|IC|PART_NUMBER|AL086950A00|STANDARD||LIFECYCLE||~
PART_NUMBER|AL086950A00|JEDEC_TYPE|LGA17_5X4|DESCRIPTION|IC OTHER(27P)MP86950GLV~
T-Z(LGA)|MANUFTR|MPS|MANUF_PN|MP86950GLVT-Z|RD_CMPLS_LVL|EP(V1)|CMPLS_LVL||FROM_~
PJ|S69-CARSON|CLASS|IC|DIP_SMD||DATA|MPS_MP86950GLVT-Z.pdf|EE_CHECK_LIST||FP_ECN~
||PSL||CREATOR||STATUS||MSD|Level-3|ESD_CDM|NA|ESD_HBM|NA|ESD_MM|NA|PIN_LENGTH_S~
HORT_PIN|0 MILS|PIN_LENGTH_LONG_PIN|0 MILS|CREATEDAY|20180807|VARIANT_DEVICE_TYP~
E|MP86950GLVTZ-MP86950GLVT-Z,SML';

PART_NAME
 PR1805 'Q_RES_0402LF-0,5%,1/16W,CHIP,CS00002JB38':;

SECTION_NUMBER 1
 '@T6G_MB_LIB.T6G(SCH_1):PAGE320_I17@PURE_QUANTA.Q_RES(CHIPS)':
 C_PATH='@t6g_mb_lib.t6g(sch_1):page320_i17@pure_quanta.q_res(chips)',
 CDSVAR_REPCELL_MPS='pure_quanta|Q_res',
 VAR_0_MPS='VALUE|0|TOLERANCE|5%|WATTAGE|1/16W|PACK_TYPE|0402LF|MATERIAL|EMPTY|P~
ART_NUMBER|CS00002JB38|STANDARD|End of Design|LIFECYCLE|Comp-Approve|PART_NUMBER~
|CS00002JB38|JEDEC_TYPE|R0402|ALT_SYMBOLS|(R0402-0201)|VALUE|0|TOL|5%|WATTAGE|1/~
16W|CLASS|IO|DESCRIPTION|RESISTOR CHIP 0 1/16W +-5%(0402)|COMPONENT_TYPE|CHIP040~
2|LEAD_LENGTH||DFM_EXCLUSION||DAY|20100618|VARIANT_DEVICE_TYPE|Q_RES-0,5%,1/16W,~
0402LF,EMPTY,';

PART_NAME
 PR1804 'Q_RES_0402LF-4.7,1%,1/16W,CHIP,CS-4702FB19':;

SECTION_NUMBER 1
 '@T6G_MB_LIB.T6G(SCH_1):PAGE320_I19@PURE_QUANTA.Q_RES(CHIPS)':
 C_PATH='@t6g_mb_lib.t6g(sch_1):page320_i19@pure_quanta.q_res(chips)',
 CDSVAR_REPCELL_MPS='pure_quanta|Q_res',
 VAR_0_MPS='VALUE|0|TOLERANCE|5%|WATTAGE|1/16W|PACK_TYPE|0402LF|MATERIAL|CHIP|PA~
RT_NUMBER|CS00002JB38|STANDARD|End of Design|LIFECYCLE|Comp-Approve|PART_NUMBER|~
CS00002JB38|JEDEC_TYPE|R0402|ALT_SYMBOLS|(R0402-0201)|VALUE|0|TOL|5%|WATTAGE|1/1~
6W|CLASS|DISCRETE|DESCRIPTION|RESISTOR CHIP 0 1/16W +-5%(0402)|COMPONENT_TYPE|CH~
IP0402|LEAD_LENGTH||DFM_EXCLUSION||DAY|20100618|VARIANT_DEVICE_TYPE|Q_RES-0,5%,1~
/16W,0402LF,CHIP,C';

PART_NAME
 PR1746 'Q_RES_0402LF-8.87K,1%,1/16W,EMPTY,CS28872FB01':;

SECTION_NUMBER 1
 '@T6G_MB_LIB.T6G(SCH_1):PAGE320_I2@PURE_QUANTA.Q_RES(CHIPS)':
 C_PATH='@t6g_mb_lib.t6g(sch_1):page320_i2@pure_quanta.q_res(chips)';

PART_NAME
 PR707 'Q_RES_0402LF-0,5%,1/16W,EMPTY,CS00002JB38':;

SECTION_NUMBER 1
 '@T6G_MB_LIB.T6G(SCH_1):PAGE320_I14@PURE_QUANTA.Q_RES(CHIPS)':
 C_PATH='@t6g_mb_lib.t6g(sch_1):page320_i14@pure_quanta.q_res(chips)',
 CDSVAR_REPCELL_MPS='pure_quanta|Q_res',
 VAR_0_MPS='VALUE|0|TOLERANCE|5%|WATTAGE|1/16W|PACK_TYPE|0402LF|MATERIAL|CHIP|PA~
RT_NUMBER|CS00002JB38|STANDARD|End of Design|LIFECYCLE|Comp-Approve|PART_NUMBER|~
CS00002JB38|JEDEC_TYPE|R0402|ALT_SYMBOLS|(R0402-0201)|VALUE|0|TOL|5%|WATTAGE|1/1~
6W|CLASS|DISCRETE|DESCRIPTION|RESISTOR CHIP 0 1/16W +-5%(0402)|COMPONENT_TYPE|CH~
IP0402|LEAD_LENGTH||DFM_EXCLUSION||DAY|20100618|VARIANT_DEVICE_TYPE|Q_RES-0,5%,1~
/16W,0402LF,CHIP,C';

PART_NAME
 PR706 'Q_RES_0402LF-0,5%,1/16W,CHIP,CS00002JB38':;

SECTION_NUMBER 1
 '@T6G_MB_LIB.T6G(SCH_1):PAGE320_I11@PURE_QUANTA.Q_RES(CHIPS)':
 C_PATH='@t6g_mb_lib.t6g(sch_1):page320_i11@pure_quanta.q_res(chips)',
 CDSVAR_REPCELL_MPS='pure_quanta|Q_res',
 VAR_0_MPS='VALUE|0|TOLERANCE|5%|WATTAGE|1/16W|PACK_TYPE|0402LF|MATERIAL|EMPTY|P~
ART_NUMBER|CS00002JB38|STANDARD|End of Design|LIFECYCLE|Comp-Approve|PART_NUMBER~
|CS00002JB38|JEDEC_TYPE|R0402|ALT_SYMBOLS|(R0402-0201)|VALUE|0|TOL|5%|WATTAGE|1/~
16W|CLASS|IO|DESCRIPTION|RESISTOR CHIP 0 1/16W +-5%(0402)|COMPONENT_TYPE|CHIP040~
2|LEAD_LENGTH||DFM_EXCLUSION||DAY|20100618|VARIANT_DEVICE_TYPE|Q_RES-0,5%,1/16W,~
0402LF,EMPTY,';

PART_NAME
 PR200 'Q_RES_0402LF-2.2,1%,1/16W,CHIP,CS-2202FB00':;

SECTION_NUMBER 1
 '@T6G_MB_LIB.T6G(SCH_1):PAGE320_I13@PURE_QUANTA.Q_RES(CHIPS)':
 C_PATH='@t6g_mb_lib.t6g(sch_1):page320_i13@pure_quanta.q_res(chips)';

PART_NAME
 PL17 'Q_INDUCTOR_SMLF-120NH/94A,IND,CV+12^0KZ16':;

SECTION_NUMBER 1
 '@T6G_MB_LIB.T6G(SCH_1):PAGE320_I26@PURE_QUANTA.Q_INDUCTOR(CHIPS)':
 C_PATH='@t6g_mb_lib.t6g(sch_1):page320_i26@pure_quanta.q_inductor(chips)';

PART_NAME
 PC1940 'Q_CAPP_SMLF-330UF,2V,35%,SPCAP,CH733RY8807':;

SECTION_NUMBER 1
 '@T6G_MB_LIB.T6G(SCH_1):PAGE320_I37@PURE_QUANTA.Q_CAPP(CHIPS)':
 C_PATH='@t6g_mb_lib.t6g(sch_1):page320_i37@pure_quanta.q_capp(chips)';

PART_NAME
 PC1371 'Q_CAP_0402-0.1UF,25V,10%,X7R,CH4104K1B00':;

SECTION_NUMBER 1
 '@T6G_MB_LIB.T6G(SCH_1):PAGE320_I8@PURE_QUANTA.Q_CAP(CHIPS)':
 C_PATH='@t6g_mb_lib.t6g(sch_1):page320_i8@pure_quanta.q_cap(chips)',
 CDSVAR_REPCELL_MPS='pure_quanta|Q_cap',
 VAR_0_MPS='VALUE|0.1UF|VOLTAGE|25V|TOLERANCE|10%|PACK_TYPE|0402|MATERIAL|EMPTY|~
PART_NUMBER|CH4104K1B00|STANDARD||LIFECYCLE||ASS_PART||PART_NUMBER|CH4104K1B00|J~
EDEC_TYPE|C0402|ALT_SYMBOLS|(C0402_OCTAGONXA,C0402-0201)|VALUE|NA|RATED_VOLTAGE|~
25V|TOL|10%|CLASS|IO|DESCRIPTION|CAP CHIP 0.1U 25V(+-10%,X7R,0402)|COMPONENT_TYP~
E|CHIP0402|LEAD_LENGTH||LPID||DATE|20160113|VARIANT_DEVICE_TYPE|Q_CAP-0.1UF,25V,~
10%,0402,EMPTY';

PART_NAME
 PC385 'Q_CAPP_THLF-560UF,2.5V,20%,OSCON,CC7560JMD18':;

SECTION_NUMBER 1
 '@T6G_MB_LIB.T6G(SCH_1):PAGE320_I23@PURE_QUANTA.Q_CAPP(CHIPS)':
 C_PATH='@t6g_mb_lib.t6g(sch_1):page320_i23@pure_quanta.q_capp(chips)';

PART_NAME
 PC384 'Q_CAPP_THLF-560UF,2.5V,20%,OSCON,CC7560JMD18':;

SECTION_NUMBER 1
 '@T6G_MB_LIB.T6G(SCH_1):PAGE320_I21@PURE_QUANTA.Q_CAPP(CHIPS)':
 C_PATH='@t6g_mb_lib.t6g(sch_1):page320_i21@pure_quanta.q_capp(chips)';

PART_NAME
 PC382 'Q_CAP_0805-22UF,4V,20%,X6S,TMP_QCH622KMEA01':;

SECTION_NUMBER 1
 '@T6G_MB_LIB.T6G(SCH_1):PAGE320_I34@PURE_QUANTA.Q_CAP(CHIPS)':
 C_PATH='@t6g_mb_lib.t6g(sch_1):page320_i34@pure_quanta.q_cap(chips)';

PART_NAME
 PC381 'Q_CAP_0805-22UF,4V,20%,X6S,TMP_QCH622KMEA01':;

SECTION_NUMBER 1
 '@T6G_MB_LIB.T6G(SCH_1):PAGE320_I28@PURE_QUANTA.Q_CAP(CHIPS)':
 C_PATH='@t6g_mb_lib.t6g(sch_1):page320_i28@pure_quanta.q_cap(chips)';

PART_NAME
 PC379 'Q_CAP_C0402-100NF,50V,10%,X7R,CH4106K1B01':;

SECTION_NUMBER 1
 '@T6G_MB_LIB.T6G(SCH_1):PAGE320_I27@PURE_QUANTA.Q_CAP(CHIPS)':
 C_PATH='@t6g_mb_lib.t6g(sch_1):page320_i27@pure_quanta.q_cap(chips)';

PART_NAME
 PC378 'Q_CAP_C0805-22UF,16V,20%,X6S,CH6223MEA00':;

SECTION_NUMBER 1
 '@T6G_MB_LIB.T6G(SCH_1):PAGE320_I30@PURE_QUANTA.Q_CAP(CHIPS)':
 C_PATH='@t6g_mb_lib.t6g(sch_1):page320_i30@pure_quanta.q_cap(chips)';

PART_NAME
 PC377 'Q_CAP_C0805-22UF,16V,20%,X6S,CH6223MEA00':;

SECTION_NUMBER 1
 '@T6G_MB_LIB.T6G(SCH_1):PAGE320_I29@PURE_QUANTA.Q_CAP(CHIPS)':
 C_PATH='@t6g_mb_lib.t6g(sch_1):page320_i29@pure_quanta.q_cap(chips)';

PART_NAME
 PC376 'Q_CAP_C0402-100NF,50V,10%,X7R,CH4106K1B01':;

SECTION_NUMBER 1
 '@T6G_MB_LIB.T6G(SCH_1):PAGE320_I25@PURE_QUANTA.Q_CAP(CHIPS)':
 C_PATH='@t6g_mb_lib.t6g(sch_1):page320_i25@pure_quanta.q_cap(chips)';

PART_NAME
 PC375 'Q_CAP_C0402-1UF,16V,10%,X6S,CH5103KEB01':;

SECTION_NUMBER 1
 '@T6G_MB_LIB.T6G(SCH_1):PAGE320_I20@PURE_QUANTA.Q_CAP(CHIPS)':
 C_PATH='@t6g_mb_lib.t6g(sch_1):page320_i20@pure_quanta.q_cap(chips)';

PART_NAME
 PC374 'Q_CAP_0402-3300PF,50V,10%,X7R,TMP_QCH2336K1B12':;

SECTION_NUMBER 1
 '@T6G_MB_LIB.T6G(SCH_1):PAGE320_I18@PURE_QUANTA.Q_CAP(CHIPS)':
 C_PATH='@t6g_mb_lib.t6g(sch_1):page320_i18@pure_quanta.q_cap(chips)';

PART_NAME
 PC373 'Q_CAP_C0402-2.2UF,10V,10%,X6S,CH5222KEB01':;

SECTION_NUMBER 1
 '@T6G_MB_LIB.T6G(SCH_1):PAGE320_I10@PURE_QUANTA.Q_CAP(CHIPS)':
 C_PATH='@t6g_mb_lib.t6g(sch_1):page320_i10@pure_quanta.q_cap(chips)';

PART_NAME
 R541 'Q_RES_0402LF-0,5%,1/16W,CHIP,CS00002JB38':;

SECTION_NUMBER 1
 '@T6G_MB_LIB.T6G(SCH_1):PAGE289_I232@PURE_QUANTA.Q_RES(CHIPS)':
 C_PATH='@t6g_mb_lib.t6g(sch_1):page289_i232@pure_quanta.q_res(chips)';

PART_NAME
 PU14 'RAA229126GNPHA0-RAA229126GNP#HA0,SMLF,IC,AL229126000':;

SECTION_NUMBER 1
 '@T6G_MB_LIB.T6G(SCH_1):PAGE289_I339@PURE_QUANTA.RAA229126GNPHA0(CHIPS)':
 C_PATH='@t6g_mb_lib.t6g(sch_1):page289_i339@pure_quanta.raa229126gnpha0(chips)',
 VAR_0_MPS='';

PART_NAME
 PR587 'Q_RES_0402LF-100,1%,1/16W,CHIP,TMP_QCS11002FB22':;

SECTION_NUMBER 1
 '@T6G_MB_LIB.T6G(SCH_1):PAGE289_I239@PURE_QUANTA.Q_RES(CHIPS)':
 C_PATH='@t6g_mb_lib.t6g(sch_1):page289_i239@pure_quanta.q_res(chips)';

PART_NAME
 PR586 'Q_RES_0402LF-100,1%,1/16W,CHIP,TMP_QCS11002FB22':;

SECTION_NUMBER 1
 '@T6G_MB_LIB.T6G(SCH_1):PAGE289_I233@PURE_QUANTA.Q_RES(CHIPS)':
 C_PATH='@t6g_mb_lib.t6g(sch_1):page289_i233@pure_quanta.q_res(chips)';

PART_NAME
 PR531 'Q_RES_0402LF-100,1%,1/16W,CHIP,TMP_QCS11002FB22':;

SECTION_NUMBER 1
 '@T6G_MB_LIB.T6G(SCH_1):PAGE289_I261@PURE_QUANTA.Q_RES(CHIPS)':
 C_PATH='@t6g_mb_lib.t6g(sch_1):page289_i261@pure_quanta.q_res(chips)';

PART_NAME
 PR530 'Q_RES_0402LF-49.9     ,1%  ,1/16W,EMPTY,CS04992FB31':;

SECTION_NUMBER 1
 '@T6G_MB_LIB.T6G(SCH_1):PAGE289_I331@PURE_QUANTA.Q_RES(CHIPS)':
 C_PATH='@t6g_mb_lib.t6g(sch_1):page289_i331@pure_quanta.q_res(chips)';

PART_NAME
 PR529 'Q_RES_0402LF-49.9     ,1%  ,1/16W,CHIP,CS04992FB31':;

SECTION_NUMBER 1
 '@T6G_MB_LIB.T6G(SCH_1):PAGE289_I332@PURE_QUANTA.Q_RES(CHIPS)':
 C_PATH='@t6g_mb_lib.t6g(sch_1):page289_i332@pure_quanta.q_res(chips)';

PART_NAME
 PR528 'Q_RES_0402LF-100,1%,1/16W,CHIP,TMP_QCS11002FB22':;

SECTION_NUMBER 1
 '@T6G_MB_LIB.T6G(SCH_1):PAGE289_I333@PURE_QUANTA.Q_RES(CHIPS)':
 C_PATH='@t6g_mb_lib.t6g(sch_1):page289_i333@pure_quanta.q_res(chips)';

PART_NAME
 PR527 'Q_RES_0402LF-100,1%,1/16W,CHIP,TMP_QCS11002FB22':;

SECTION_NUMBER 1
 '@T6G_MB_LIB.T6G(SCH_1):PAGE289_I240@PURE_QUANTA.Q_RES(CHIPS)':
 C_PATH='@t6g_mb_lib.t6g(sch_1):page289_i240@pure_quanta.q_res(chips)';

PART_NAME
 PR451 'Q_RES_0402LF-0,5%,1/16W,CHIP,CS00002JB38':;

SECTION_NUMBER 1
 '@T6G_MB_LIB.T6G(SCH_1):PAGE289_I292@PURE_QUANTA.Q_RES(CHIPS)':
 C_PATH='@t6g_mb_lib.t6g(sch_1):page289_i292@pure_quanta.q_res(chips)';

PART_NAME
 PR450 'Q_RES_0402LF-0,5%,1/16W,EMPTY,CS00002JB38':;

SECTION_NUMBER 1
 '@T6G_MB_LIB.T6G(SCH_1):PAGE289_I293@PURE_QUANTA.Q_RES(CHIPS)':
 C_PATH='@t6g_mb_lib.t6g(sch_1):page289_i293@pure_quanta.q_res(chips)',
 VAR_0_MPS='';

PART_NAME
 PR400 'Q_RES_0402LF-10K,1%,1/16W,EMPTY,CS31002FB08':;

SECTION_NUMBER 1
 '@T6G_MB_LIB.T6G(SCH_1):PAGE289_I288@PURE_QUANTA.Q_RES(CHIPS)':
 C_PATH='@t6g_mb_lib.t6g(sch_1):page289_i288@pure_quanta.q_res(chips)',
 CDSVAR_REPCELL_MPS='pure_quanta|Q_res',
 VAR_0_MPS='VALUE|10K|TOLERANCE|1%|WATTAGE|1/16W|PACK_TYPE|0402LF|MATERIAL|CHIP|~
PART_NUMBER|CS31002FB08|STANDARD|End of Design|LIFECYCLE|Comp-Approve|PART_NUMBE~
R|CS31002FB08|JEDEC_TYPE|R0402|ALT_SYMBOLS|(R0402-0201)|VALUE|10K|TOL|1%|WATTAGE~
|1/16W|CLASS|DISCRETE|DESCRIPTION|RES CHIP 10K 1/16W +-1%(0402)EF|COMPONENT_TYPE~
|CHIPR0402|LEAD_LENGTH||DFM_EXCLUSION||DAY|20180208|VARIANT_DEVICE_TYPE|Q_RES-10~
K,1%,1/16W,0402LF,CHIP';

PART_NAME
 PR345 'Q_RES_0402LF-0,5%,1/16W,CHIP,CS00002JB38':;

SECTION_NUMBER 1
 '@T6G_MB_LIB.T6G(SCH_1):PAGE289_I246@PURE_QUANTA.Q_RES(CHIPS)':
 C_PATH='@t6g_mb_lib.t6g(sch_1):page289_i246@pure_quanta.q_res(chips)';

PART_NAME
 PR337 'Q_RES_0402LF-0,5%,1/16W,CHIP,CS00002JB38':;

SECTION_NUMBER 1
 '@T6G_MB_LIB.T6G(SCH_1):PAGE289_I225@PURE_QUANTA.Q_RES(CHIPS)':
 C_PATH='@t6g_mb_lib.t6g(sch_1):page289_i225@pure_quanta.q_res(chips)';

PART_NAME
 PR336 'Q_RES_0402LF-0,5%,1/16W,CHIP,CS00002JB38':;

SECTION_NUMBER 1
 '@T6G_MB_LIB.T6G(SCH_1):PAGE289_I223@PURE_QUANTA.Q_RES(CHIPS)':
 C_PATH='@t6g_mb_lib.t6g(sch_1):page289_i223@pure_quanta.q_res(chips)';

PART_NAME
 PR335 'Q_RES_0402LF-1K,1%,1/16W,CHIP,TMP_QCS21002FB24':;

SECTION_NUMBER 1
 '@T6G_MB_LIB.T6G(SCH_1):PAGE289_I224@PURE_QUANTA.Q_RES(CHIPS)':
 C_PATH='@t6g_mb_lib.t6g(sch_1):page289_i224@pure_quanta.q_res(chips)';

PART_NAME
 PR177 'Q_RES_0402LF-1K,1%,1/16W,CHIP,TMP_QCS21002FB24':;

SECTION_NUMBER 1
 '@T6G_MB_LIB.T6G(SCH_1):PAGE289_I244@PURE_QUANTA.Q_RES(CHIPS)':
 C_PATH='@t6g_mb_lib.t6g(sch_1):page289_i244@pure_quanta.q_res(chips)';

PART_NAME
 PR176 'Q_RES_0402LF-1,1%,1/16W,CHIP,CS-1002FB23':;

SECTION_NUMBER 1
 '@T6G_MB_LIB.T6G(SCH_1):PAGE289_I325@PURE_QUANTA.Q_RES(CHIPS)':
 C_PATH='@t6g_mb_lib.t6g(sch_1):page289_i325@pure_quanta.q_res(chips)';

PART_NAME
 PR172 'Q_RES_0402LF-1K,1%,1/16W,CHIP,TMP_QCS21002FB24':;

SECTION_NUMBER 1
 '@T6G_MB_LIB.T6G(SCH_1):PAGE289_I235@PURE_QUANTA.Q_RES(CHIPS)':
 C_PATH='@t6g_mb_lib.t6g(sch_1):page289_i235@pure_quanta.q_res(chips)';

PART_NAME
 PR171 'Q_RES_0402LF-0,5%,1/16W,CHIP,CS00002JB38':;

SECTION_NUMBER 1
 '@T6G_MB_LIB.T6G(SCH_1):PAGE289_I218@PURE_QUANTA.Q_RES(CHIPS)':
 C_PATH='@t6g_mb_lib.t6g(sch_1):page289_i218@pure_quanta.q_res(chips)';

PART_NAME
 PR170 'Q_RES_0402LF-0,5%,1/16W,CHIP,CS00002JB38':;

SECTION_NUMBER 1
 '@T6G_MB_LIB.T6G(SCH_1):PAGE289_I271@PURE_QUANTA.Q_RES(CHIPS)':
 C_PATH='@t6g_mb_lib.t6g(sch_1):page289_i271@pure_quanta.q_res(chips)';

PART_NAME
 PR169 'Q_RES_0402LF-1K,1%,1/16W,CHIP,TMP_QCS21002FB24':;

SECTION_NUMBER 1
 '@T6G_MB_LIB.T6G(SCH_1):PAGE289_I236@PURE_QUANTA.Q_RES(CHIPS)':
 C_PATH='@t6g_mb_lib.t6g(sch_1):page289_i236@pure_quanta.q_res(chips)';

PART_NAME
 PR168 'Q_RES_0402LF-0,5%,1/16W,CHIP,CS00002JB38':;

SECTION_NUMBER 1
 '@T6G_MB_LIB.T6G(SCH_1):PAGE289_I272@PURE_QUANTA.Q_RES(CHIPS)':
 C_PATH='@t6g_mb_lib.t6g(sch_1):page289_i272@pure_quanta.q_res(chips)';

PART_NAME
 PR167 'Q_RES_0402LF-0,5%,1/16W,CHIP,CS00002JB38':;

SECTION_NUMBER 1
 '@T6G_MB_LIB.T6G(SCH_1):PAGE289_I273@PURE_QUANTA.Q_RES(CHIPS)':
 C_PATH='@t6g_mb_lib.t6g(sch_1):page289_i273@pure_quanta.q_res(chips)';

PART_NAME
 PR166 'Q_RES_0402LF-1K,1%,1/16W,EMPTY,TMP_QCS21002FB24':;

SECTION_NUMBER 1
 '@T6G_MB_LIB.T6G(SCH_1):PAGE289_I229@PURE_QUANTA.Q_RES(CHIPS)':
 C_PATH='@t6g_mb_lib.t6g(sch_1):page289_i229@pure_quanta.q_res(chips)',
 VAR_0_MPS='VALUE|1K|TOLERANCE|1%|WATTAGE|1/16W|PACK_TYPE|0402LF|MATERIAL|CHIP|P~
ART_NUMBER|TMP_QCS21002FB24|STANDARD|End of Design|LIFECYCLE|Comp-Approve|PART_N~
UMBER|CS21002FB24|JEDEC_TYPE|R0402|ALT_SYMBOLS|(R0402-0201)|VALUE|1K|TOL|1%|WATT~
AGE|1/16W|CLASS|DISCRETE|DESCRIPTION|RES CHIP 1K 1/16W +-1% (0402)|COMPONENT_TYP~
E|CHIP0402|LEAD_LENGTH||DFM_EXCLUSION||DAY||VARIANT_DEVICE_TYPE|Q_RES-1K,1%,1/16~
W,0402LF,CHIP,',
 CDSVAR_REPCELL_MPS='pure_quanta|Q_res';

PART_NAME
 PR165 'Q_RES_0402LF-0,5%,1/16W,CHIP,CS00002JB38':;

SECTION_NUMBER 1
 '@T6G_MB_LIB.T6G(SCH_1):PAGE289_I267@PURE_QUANTA.Q_RES(CHIPS)':
 C_PATH='@t6g_mb_lib.t6g(sch_1):page289_i267@pure_quanta.q_res(chips)';

PART_NAME
 PR164 'Q_RES_0402LF-0,5%,1/16W,CHIP,CS00002JB38':;

SECTION_NUMBER 1
 '@T6G_MB_LIB.T6G(SCH_1):PAGE289_I269@PURE_QUANTA.Q_RES(CHIPS)':
 C_PATH='@t6g_mb_lib.t6g(sch_1):page289_i269@pure_quanta.q_res(chips)';

PART_NAME
 PR163 'Q_RES_0402LF-150,1%,1/16W,CHIP,TMP_QCS11502FB21':;

SECTION_NUMBER 1
 '@T6G_MB_LIB.T6G(SCH_1):PAGE289_I270@PURE_QUANTA.Q_RES(CHIPS)':
 C_PATH='@t6g_mb_lib.t6g(sch_1):page289_i270@pure_quanta.q_res(chips)';

PART_NAME
 PR162 'Q_RES_0402LF-0,5%,1/16W,CHIP,CS00002JB38':;

SECTION_NUMBER 1
 '@T6G_MB_LIB.T6G(SCH_1):PAGE289_I275@PURE_QUANTA.Q_RES(CHIPS)':
 C_PATH='@t6g_mb_lib.t6g(sch_1):page289_i275@pure_quanta.q_res(chips)';

PART_NAME
 PR161 'Q_RES_0402LF-0,5%,1/16W,CHIP,CS00002JB38':;

SECTION_NUMBER 1
 '@T6G_MB_LIB.T6G(SCH_1):PAGE289_I277@PURE_QUANTA.Q_RES(CHIPS)':
 C_PATH='@t6g_mb_lib.t6g(sch_1):page289_i277@pure_quanta.q_res(chips)';

PART_NAME
 PR160 'Q_RES_0402LF-1K,1%,1/16W,CHIP,TMP_QCS21002FB24':;

SECTION_NUMBER 1
 '@T6G_MB_LIB.T6G(SCH_1):PAGE289_I278@PURE_QUANTA.Q_RES(CHIPS)':
 C_PATH='@t6g_mb_lib.t6g(sch_1):page289_i278@pure_quanta.q_res(chips)';

PART_NAME
 PR159 'Q_RES_0402LF-28K,1%,1/16W,EMPTY,CS32802FB05':;

SECTION_NUMBER 1
 '@T6G_MB_LIB.T6G(SCH_1):PAGE289_I212@PURE_QUANTA.Q_RES(CHIPS)':
 C_PATH='@t6g_mb_lib.t6g(sch_1):page289_i212@pure_quanta.q_res(chips)';

PART_NAME
 PR158 'Q_RES_0402LF-0,5%,1/16W,CHIP,CS00002JB38':;

SECTION_NUMBER 1
 '@T6G_MB_LIB.T6G(SCH_1):PAGE289_I227@PURE_QUANTA.Q_RES(CHIPS)':
 C_PATH='@t6g_mb_lib.t6g(sch_1):page289_i227@pure_quanta.q_res(chips)';

PART_NAME
 PR157 'Q_RES_0402LF-0,5%,1/16W,EMPTY,CS00002JB38':;

SECTION_NUMBER 1
 '@T6G_MB_LIB.T6G(SCH_1):PAGE289_I219@PURE_QUANTA.Q_RES(CHIPS)':
 C_PATH='@t6g_mb_lib.t6g(sch_1):page289_i219@pure_quanta.q_res(chips)';

PART_NAME
 PR156 'Q_RES_0402LF-0,5%,1/16W,CHIP,CS00002JB38':;

SECTION_NUMBER 1
 '@T6G_MB_LIB.T6G(SCH_1):PAGE289_I220@PURE_QUANTA.Q_RES(CHIPS)':
 C_PATH='@t6g_mb_lib.t6g(sch_1):page289_i220@pure_quanta.q_res(chips)',
 VAR_0_MPS='VALUE|15K|TOLERANCE|1%|WATTAGE|1/16W|PACK_TYPE|0402LF|MATERIAL|CHIP|~
PART_NUMBER|TMP_QCS31502FB24|STANDARD|End of Design|LIFECYCLE|Comp-Approve|PART_~
NUMBER|CS31502FB24|JEDEC_TYPE|R0402|ALT_SYMBOLS|(R0402-0201)|VALUE|15K|TOL|1%|WA~
TTAGE|1/16W |CLASS|DISCRETE|DESCRIPTION|RES CHIP 15K 1/16W +-1% (0402)|COMPONENT~
_TYPE|CHIP0402|LEAD_LENGTH||DFM_EXCLUSION||DAY||VARIANT_DEVICE_TYPE|Q_RES-15K,1%~
,1/16W,0402LF,CHIP',
 CDSVAR_REPCELL_MPS='pure_quanta|Q_res';

PART_NAME
 PJ53 'Q_SHORT_SM-EMPTY,SHORT6':;

SECTION_NUMBER 1
 '@T6G_MB_LIB.T6G(SCH_1):PAGE289_I216@PURE_QUANTA.Q_SHORT(CHIPS)':
 C_PATH='@t6g_mb_lib.t6g(sch_1):page289_i216@pure_quanta.q_short(chips)';

PART_NAME
 PJ47 'Q_SHORT_SM-EMPTY,SHORT6':;

SECTION_NUMBER 1
 '@T6G_MB_LIB.T6G(SCH_1):PAGE289_I252@PURE_QUANTA.Q_SHORT(CHIPS)':
 C_PATH='@t6g_mb_lib.t6g(sch_1):page289_i252@pure_quanta.q_short(chips)';

PART_NAME
 PC1173 'Q_CAP_C0402-1UF,16V,10%,X6S,CH5103KEB01':;

SECTION_NUMBER 1
 '@T6G_MB_LIB.T6G(SCH_1):PAGE289_I319@PURE_QUANTA.Q_CAP(CHIPS)':
 C_PATH='@t6g_mb_lib.t6g(sch_1):page289_i319@pure_quanta.q_cap(chips)';

PART_NAME
 PC594 'Q_CAP_0402-3300PF,50V,10%,X7R,TMP_QCH2336K1B12':;

SECTION_NUMBER 1
 '@T6G_MB_LIB.T6G(SCH_1):PAGE289_I245@PURE_QUANTA.Q_CAP(CHIPS)':
 C_PATH='@t6g_mb_lib.t6g(sch_1):page289_i245@pure_quanta.q_cap(chips)',
 CDSVAR_REPCELL_MPS='pure_quanta|Q_cap',
 VAR_0_MPS='VALUE|3300PF|VOLTAGE|50V|TOLERANCE|10%|PACK_TYPE|C0402|MATERIAL|EMPT~
Y|PART_NUMBER|CH2336K1B06|STANDARD||LIFECYCLE||ASS_PART||PART_NUMBER|CH2336K1B06~
|JEDEC_TYPE|C0402|ALT_SYMBOLS|(C0402-0201)|VALUE|NA|RATED_VOLTAGE|50V|TOL|10%|CL~
ASS|IO|DESCRIPTION|CAP CHIP 3300P 50V(+-10%,X7R,0402)MUR|COMPONENT_TYPE|CHIP0402~
|LEAD_LENGTH||LPID||DATE|20150617|VARIANT_DEVICE_TYPE|Q_CAP-3300PF,50V,10%,C0402~
,EMP';

PART_NAME
 PC593 'Q_CAP_0402-1000PF,50V,5%,EMPTY,TMP_QCH21006JB10':;

SECTION_NUMBER 1
 '@T6G_MB_LIB.T6G(SCH_1):PAGE289_I230@PURE_QUANTA.Q_CAP(CHIPS)':
 C_PATH='@t6g_mb_lib.t6g(sch_1):page289_i230@pure_quanta.q_cap(chips)';

PART_NAME
 PC592 'Q_CAP_0402-1000PF,50V,5%,X7R,TMP_QCH21006JB10':;

SECTION_NUMBER 1
 '@T6G_MB_LIB.T6G(SCH_1):PAGE289_I231@PURE_QUANTA.Q_CAP(CHIPS)':
 C_PATH='@t6g_mb_lib.t6g(sch_1):page289_i231@pure_quanta.q_cap(chips)';

PART_NAME
 PC337 'Q_CAP_C0402-1UF,16V,10%,X6S,CH5103KEB01':;

SECTION_NUMBER 1
 '@T6G_MB_LIB.T6G(SCH_1):PAGE289_I322@PURE_QUANTA.Q_CAP(CHIPS)':
 C_PATH='@t6g_mb_lib.t6g(sch_1):page289_i322@pure_quanta.q_cap(chips)';

PART_NAME
 PC336 'Q_CAP_0402-470PF,50V,10%,X7R,TMP_QCH14706KB18':;

SECTION_NUMBER 1
 '@T6G_MB_LIB.T6G(SCH_1):PAGE289_I286@PURE_QUANTA.Q_CAP(CHIPS)':
 C_PATH='@t6g_mb_lib.t6g(sch_1):page289_i286@pure_quanta.q_cap(chips)',
 CDSVAR_REPCELL_MPS='pure_quanta|Q_cap',
 VAR_0_MPS='VALUE|0.01UF|VOLTAGE|25V|TOLERANCE|10%|PACK_TYPE|0402|MATERIAL|X7R|P~
ART_NUMBER|TMP_QCH31004KB17|STANDARD|End of Design|LIFECYCLE|Comp-Approve|ASS_PA~
RT||PART_NUMBER|CH31004KB17|JEDEC_TYPE|C0402|ALT_SYMBOLS|(C0402-0201)|VALUE|0.01~
UF|RATED_VOLTAGE|25V|TOL|10%|CLASS|DISCRETE|DESCRIPTION|CAP CHIP 0.01U 25V(+-10%~
,X7R,0402)|COMPONENT_TYPE|CHIP0402|LEAD_LENGTH||LPID||DATE|20100528|VARIANT_DEVI~
CE_TYPE|Q_CAP-0.01UF,25V,10%,0402,X7R,';

PART_NAME
 PC335 'Q_CAP_0402-4.7UF,6.3V,20%,X6S,CH5471MEB01':;

SECTION_NUMBER 1
 '@T6G_MB_LIB.T6G(SCH_1):PAGE289_I317@PURE_QUANTA.Q_CAP(CHIPS)':
 C_PATH='@t6g_mb_lib.t6g(sch_1):page289_i317@pure_quanta.q_cap(chips)',
 VAR_0_MPS='VALUE|4.7UF|VOLTAGE|6.3V|TOLERANCE|20%|PACK_TYPE|0402|MATERIAL|EMPTY~
|PART_NUMBER|CH5471MEB01|STANDARD||LIFECYCLE||ASS_PART||PART_NUMBER|CH5471MEB01|~
JEDEC_TYPE|C0402|ALT_SYMBOLS|(C0402_OCTAGON,C0402_OCTAGONXA,C0402-0201)|VALUE|NA~
|RATED_VOLTAGE|6.3V|TOL|20%|CLASS|IO|DESCRIPTION|CAP CHIP 4.7UF 6.3V(+-20%,X6S,0~
402)|COMPONENT_TYPE|CHIP0402|LEAD_LENGTH||LPID||DATE|20151211|VARIANT_DEVICE_TYP~
E|Q_CAP-4.7UF,6.3V,20%,0402,EMPT',
 CDSVAR_REPCELL_MPS='pure_quanta|Q_cap';

PART_NAME
 PC334 'Q_CAP_C0402-100NF,50V,10%,EMPTY,CH4106K1B01':;

SECTION_NUMBER 1
 '@T6G_MB_LIB.T6G(SCH_1):PAGE289_I318@PURE_QUANTA.Q_CAP(CHIPS)':
 C_PATH='@t6g_mb_lib.t6g(sch_1):page289_i318@pure_quanta.q_cap(chips)';

PART_NAME
 PC333 'Q_CAP_0402-1000PF,50V,5%,EMPTY,TMP_QCH21006JB10':;

SECTION_NUMBER 1
 '@T6G_MB_LIB.T6G(SCH_1):PAGE289_I279@PURE_QUANTA.Q_CAP(CHIPS)':
 C_PATH='@t6g_mb_lib.t6g(sch_1):page289_i279@pure_quanta.q_cap(chips)';

PART_NAME
 PC332 'Q_CAP_0402-1000PF,50V,5%,X7R,TMP_QCH21006JB10':;

SECTION_NUMBER 1
 '@T6G_MB_LIB.T6G(SCH_1):PAGE289_I274@PURE_QUANTA.Q_CAP(CHIPS)':
 C_PATH='@t6g_mb_lib.t6g(sch_1):page289_i274@pure_quanta.q_cap(chips)';

PART_NAME
 PC331 'Q_CAP_0402-3300PF,50V,10%,X7R,TMP_QCH2336K1B12':;

SECTION_NUMBER 1
 '@T6G_MB_LIB.T6G(SCH_1):PAGE289_I247@PURE_QUANTA.Q_CAP(CHIPS)':
 C_PATH='@t6g_mb_lib.t6g(sch_1):page289_i247@pure_quanta.q_cap(chips)',
 CDSVAR_REPCELL_MPS='pure_quanta|Q_cap',
 VAR_0_MPS='VALUE|3300PF|VOLTAGE|50V|TOLERANCE|10%|PACK_TYPE|C0402|MATERIAL|EMPT~
Y|PART_NUMBER|CH2336K1B06|STANDARD||LIFECYCLE||ASS_PART||PART_NUMBER|CH2336K1B06~
|JEDEC_TYPE|C0402|ALT_SYMBOLS|(C0402-0201)|VALUE|NA|RATED_VOLTAGE|50V|TOL|10%|CL~
ASS|IO|DESCRIPTION|CAP CHIP 3300P 50V(+-10%,X7R,0402)MUR|COMPONENT_TYPE|CHIP0402~
|LEAD_LENGTH||LPID||DATE|20150617|VARIANT_DEVICE_TYPE|Q_CAP-3300PF,50V,10%,C0402~
,EMP';

PART_NAME
 PC330 'Q_CAP_0402-0.1UF,25V,10%,X7R,CH4104K1B00':;

SECTION_NUMBER 1
 '@T6G_MB_LIB.T6G(SCH_1):PAGE289_I281@PURE_QUANTA.Q_CAP(CHIPS)':
 C_PATH='@t6g_mb_lib.t6g(sch_1):page289_i281@pure_quanta.q_cap(chips)';

PART_NAME
 PC329 'Q_CAP_0402-0.1UF,25V,10%,EMPTY,CH4104K1B00':;

SECTION_NUMBER 1
 '@T6G_MB_LIB.T6G(SCH_1):PAGE289_I228@PURE_QUANTA.Q_CAP(CHIPS)':
 C_PATH='@t6g_mb_lib.t6g(sch_1):page289_i228@pure_quanta.q_cap(chips)';

PART_NAME
 PC328 'Q_CAP_C0402-100NF,50V,10%,X7R,CH4106K1B01':;

SECTION_NUMBER 1
 '@T6G_MB_LIB.T6G(SCH_1):PAGE289_I334@PURE_QUANTA.Q_CAP(CHIPS)':
 C_PATH='@t6g_mb_lib.t6g(sch_1):page289_i334@pure_quanta.q_cap(chips)';

PART_NAME
 PC327 'Q_CAP_C0603-10UF,4V,20%,EMPTY,CH610KME907':;

SECTION_NUMBER 1
 '@T6G_MB_LIB.T6G(SCH_1):PAGE289_I330@PURE_QUANTA.Q_CAP(CHIPS)':
 C_PATH='@t6g_mb_lib.t6g(sch_1):page289_i330@pure_quanta.q_cap(chips)';

PART_NAME
 PU11_P0_3 'ISL99390FRZTR5935-ISL99390FRZ-TR5935,SMLF,IC,AL099390004':;

SECTION_NUMBER 1
 '@T6G_MB_LIB.T6G(SCH_1):PAGE291_I30@PURE_QUANTA.ISL99390FRZTR5935(CHIPS)':
 C_PATH='@s6q_mb_lib.s6q(sch_1):page291_i30@pure_quanta.isl99390frztr5935(chips)~
';

PART_NAME
 PU10_P0_4 'ISL99390FRZTR5935-ISL99390FRZ-TR5935,SMLF,IC,AL099390004':;

SECTION_NUMBER 1
 '@T6G_MB_LIB.T6G(SCH_1):PAGE291_I14@PURE_QUANTA.ISL99390FRZTR5935(CHIPS)':
 C_PATH='@s6q_mb_lib.s6q(sch_1):page291_i14@pure_quanta.isl99390frztr5935(chips)~
';

PART_NAME
 PR1769 'Q_RES_0402LF-3.3,1%,1/16W,CHIP,CS-3302FB00':;

SECTION_NUMBER 1
 '@T6G_MB_LIB.T6G(SCH_1):PAGE291_I49@PURE_QUANTA.Q_RES(CHIPS)':
 C_PATH='@t6g_mb_lib.t6g(sch_1):page291_i49@pure_quanta.q_res(chips)',
 CDSVAR_REPCELL_MPS='pure_quanta|Q_res',
 VAR_0_MPS='VALUE|0|TOLERANCE|5%|WATTAGE|1/16W|PACK_TYPE|0402LF|MATERIAL|CHIP|PA~
RT_NUMBER|CS00002JB38|STANDARD|End of Design|LIFECYCLE|Comp-Approve|PART_NUMBER|~
CS00002JB38|JEDEC_TYPE|R0402|ALT_SYMBOLS|(R0402-0201)|VALUE|0|TOL|5%|WATTAGE|1/1~
6W|CLASS|DISCRETE|DESCRIPTION|RESISTOR CHIP 0 1/16W +-5%(0402)|COMPONENT_TYPE|CH~
IP0402|LEAD_LENGTH||DFM_EXCLUSION||DAY|20100618|VARIANT_DEVICE_TYPE|Q_RES-0,5%,1~
/16W,0402LF,CHIP,C';

PART_NAME
 PR1768 'Q_RES_0402LF-3.3,1%,1/16W,CHIP,CS-3302FB00':;

SECTION_NUMBER 1
 '@T6G_MB_LIB.T6G(SCH_1):PAGE291_I35@PURE_QUANTA.Q_RES(CHIPS)':
 C_PATH='@t6g_mb_lib.t6g(sch_1):page291_i35@pure_quanta.q_res(chips)',
 CDSVAR_REPCELL_MPS='pure_quanta|Q_res',
 VAR_0_MPS='VALUE|0|TOLERANCE|5%|WATTAGE|1/16W|PACK_TYPE|0402LF|MATERIAL|CHIP|PA~
RT_NUMBER|CS00002JB38|STANDARD|End of Design|LIFECYCLE|Comp-Approve|PART_NUMBER|~
CS00002JB38|JEDEC_TYPE|R0402|ALT_SYMBOLS|(R0402-0201)|VALUE|0|TOL|5%|WATTAGE|1/1~
6W|CLASS|DISCRETE|DESCRIPTION|RESISTOR CHIP 0 1/16W +-5%(0402)|COMPONENT_TYPE|CH~
IP0402|LEAD_LENGTH||DFM_EXCLUSION||DAY|20100618|VARIANT_DEVICE_TYPE|Q_RES-0,5%,1~
/16W,0402LF,CHIP,C';

PART_NAME
 PR149 'Q_RES_0402LF-0,5%,1/16W,CHIP,CS00002JB38':;

SECTION_NUMBER 1
 '@T6G_MB_LIB.T6G(SCH_1):PAGE291_I76@PURE_QUANTA.Q_RES(CHIPS)':
 C_PATH='@t6g_mb_lib.t6g(sch_1):page291_i76@pure_quanta.q_res(chips)';

PART_NAME
 PR148 'Q_RES_0402LF-0,5%,1/16W,CHIP,CS00002JB38':;

SECTION_NUMBER 1
 '@T6G_MB_LIB.T6G(SCH_1):PAGE291_I92@PURE_QUANTA.Q_RES(CHIPS)':
 C_PATH='@t6g_mb_lib.t6g(sch_1):page291_i92@pure_quanta.q_res(chips)';

PART_NAME
 PR147 'Q_RES_0402LF-2.2,1%,1/16W,CHIP,CS-2202FB00':;

SECTION_NUMBER 1
 '@T6G_MB_LIB.T6G(SCH_1):PAGE291_I27@PURE_QUANTA.Q_RES(CHIPS)':
 C_PATH='@t6g_mb_lib.t6g(sch_1):page291_i27@pure_quanta.q_res(chips)';

PART_NAME
 PR146 'Q_RES_0402LF-2.2,1%,1/16W,CHIP,CS-2202FB00':;

SECTION_NUMBER 1
 '@T6G_MB_LIB.T6G(SCH_1):PAGE291_I10@PURE_QUANTA.Q_RES(CHIPS)':
 C_PATH='@t6g_mb_lib.t6g(sch_1):page291_i10@pure_quanta.q_res(chips)';

PART_NAME
 PR145 'Q_RES_0402LF-8.87K,1%,1/16W,EMPTY,CS28872FB01':;

SECTION_NUMBER 1
 '@T6G_MB_LIB.T6G(SCH_1):PAGE291_I19@PURE_QUANTA.Q_RES(CHIPS)':
 C_PATH='@t6g_mb_lib.t6g(sch_1):page291_i19@pure_quanta.q_res(chips)';

PART_NAME
 PR144 'Q_RES_0402LF-8.87K,1%,1/16W,EMPTY,CS28872FB01':;

SECTION_NUMBER 1
 '@T6G_MB_LIB.T6G(SCH_1):PAGE291_I2@PURE_QUANTA.Q_RES(CHIPS)':
 C_PATH='@t6g_mb_lib.t6g(sch_1):page291_i2@pure_quanta.q_res(chips)';

PART_NAME
 PL112 'Q_INDUCTOR4P_14-150NH,SMLF,IND,CV+15^0TZ01':;

SECTION_NUMBER 1
 '@T6G_MB_LIB.T6G(SCH_1):PAGE291_I74@PURE_QUANTA.Q_INDUCTOR4P_14(CHIPS)':
 C_PATH='@t6g_mb_lib.t6g(sch_1):page291_i74@pure_quanta.q_inductor4p_14(chips)';

PART_NAME
 PL11 'Q_INDUCTOR4P_14-150NH,SMLF,IND,CV+15^0TZ01':;

SECTION_NUMBER 1
 '@T6G_MB_LIB.T6G(SCH_1):PAGE291_I90@PURE_QUANTA.Q_INDUCTOR4P_14(CHIPS)':
 C_PATH='@t6g_mb_lib.t6g(sch_1):page291_i90@pure_quanta.q_inductor4p_14(chips)';

PART_NAME
 PC1341 'Q_CAP_0402-0.1UF,25V,10%,X7R,CH4104K1B00':;

SECTION_NUMBER 1
 '@T6G_MB_LIB.T6G(SCH_1):PAGE291_I29@PURE_QUANTA.Q_CAP(CHIPS)':
 C_PATH='@t6g_mb_lib.t6g(sch_1):page291_i29@pure_quanta.q_cap(chips)',
 CDSVAR_REPCELL_MPS='pure_quanta|Q_cap',
 VAR_0_MPS='VALUE|0.1UF|VOLTAGE|25V|TOLERANCE|10%|PACK_TYPE|0402|MATERIAL|EMPTY|~
PART_NUMBER|CH4104K1B00|STANDARD||LIFECYCLE||ASS_PART||PART_NUMBER|CH4104K1B00|J~
EDEC_TYPE|C0402|ALT_SYMBOLS|(C0402_OCTAGONXA,C0402-0201)|VALUE|NA|RATED_VOLTAGE|~
25V|TOL|10%|CLASS|IO|DESCRIPTION|CAP CHIP 0.1U 25V(+-10%,X7R,0402)|COMPONENT_TYP~
E|CHIP0402|LEAD_LENGTH||LPID||DATE|20160113|VARIANT_DEVICE_TYPE|Q_CAP-0.1UF,25V,~
10%,0402,EMPTY';

PART_NAME
 PC1340 'Q_CAP_0402-0.1UF,25V,10%,X7R,CH4104K1B00':;

SECTION_NUMBER 1
 '@T6G_MB_LIB.T6G(SCH_1):PAGE291_I13@PURE_QUANTA.Q_CAP(CHIPS)':
 C_PATH='@t6g_mb_lib.t6g(sch_1):page291_i13@pure_quanta.q_cap(chips)',
 CDSVAR_REPCELL_MPS='pure_quanta|Q_cap',
 VAR_0_MPS='VALUE|0.1UF|VOLTAGE|25V|TOLERANCE|10%|PACK_TYPE|0402|MATERIAL|EMPTY|~
PART_NUMBER|CH4104K1B00|STANDARD||LIFECYCLE||ASS_PART||PART_NUMBER|CH4104K1B00|J~
EDEC_TYPE|C0402|ALT_SYMBOLS|(C0402_OCTAGONXA,C0402-0201)|VALUE|NA|RATED_VOLTAGE|~
25V|TOL|10%|CLASS|IO|DESCRIPTION|CAP CHIP 0.1U 25V(+-10%,X7R,0402)|COMPONENT_TYP~
E|CHIP0402|LEAD_LENGTH||LPID||DATE|20160113|VARIANT_DEVICE_TYPE|Q_CAP-0.1UF,25V,~
10%,0402,EMPTY';

PART_NAME
 PC291_P0_3 'Q_CAP_0805-22UF,4V,20%,X6S,TMP_QCH622KMEA01':;

SECTION_NUMBER 1
 '@T6G_MB_LIB.T6G(SCH_1):PAGE291_I78@PURE_QUANTA.Q_CAP(CHIPS)':
 C_PATH='@t6g_mb_lib.t6g(sch_1):page291_i78@pure_quanta.q_cap(chips)';

PART_NAME
 PC290_P0_4 'Q_CAP_0805-22UF,4V,20%,X6S,TMP_QCH622KMEA01':;

SECTION_NUMBER 1
 '@T6G_MB_LIB.T6G(SCH_1):PAGE291_I95@PURE_QUANTA.Q_CAP(CHIPS)':
 C_PATH='@t6g_mb_lib.t6g(sch_1):page291_i95@pure_quanta.q_cap(chips)';

PART_NAME
 PC289_P0_3 'Q_CAP_0805-22UF,4V,20%,X6S,TMP_QCH622KMEA01':;

SECTION_NUMBER 1
 '@T6G_MB_LIB.T6G(SCH_1):PAGE291_I79@PURE_QUANTA.Q_CAP(CHIPS)':
 C_PATH='@t6g_mb_lib.t6g(sch_1):page291_i79@pure_quanta.q_cap(chips)';

PART_NAME
 PC288_P0_4 'Q_CAP_0805-22UF,4V,20%,X6S,TMP_QCH622KMEA01':;

SECTION_NUMBER 1
 '@T6G_MB_LIB.T6G(SCH_1):PAGE291_I96@PURE_QUANTA.Q_CAP(CHIPS)':
 C_PATH='@t6g_mb_lib.t6g(sch_1):page291_i96@pure_quanta.q_cap(chips)';

PART_NAME
 PC285_P0_3 'Q_CAP_C0805-22UF,16V,20%,X6S,CH6223MEA00':;

SECTION_NUMBER 1
 '@T6G_MB_LIB.T6G(SCH_1):PAGE291_I56@PURE_QUANTA.Q_CAP(CHIPS)':
 C_PATH='@t6g_mb_lib.t6g(sch_1):page291_i56@pure_quanta.q_cap(chips)';

PART_NAME
 PC284_P0_4 'Q_CAP_C0805-22UF,16V,20%,X6S,CH6223MEA00':;

SECTION_NUMBER 1
 '@T6G_MB_LIB.T6G(SCH_1):PAGE291_I42@PURE_QUANTA.Q_CAP(CHIPS)':
 C_PATH='@t6g_mb_lib.t6g(sch_1):page291_i42@pure_quanta.q_cap(chips)';

PART_NAME
 PC283_P0_3 'Q_CAP_C0805-22UF,16V,20%,X6S,CH6223MEA00':;

SECTION_NUMBER 1
 '@T6G_MB_LIB.T6G(SCH_1):PAGE291_I55@PURE_QUANTA.Q_CAP(CHIPS)':
 C_PATH='@t6g_mb_lib.t6g(sch_1):page291_i55@pure_quanta.q_cap(chips)';

PART_NAME
 PC282_P0_4 'Q_CAP_C0805-22UF,16V,20%,X6S,CH6223MEA00':;

SECTION_NUMBER 1
 '@T6G_MB_LIB.T6G(SCH_1):PAGE291_I40@PURE_QUANTA.Q_CAP(CHIPS)':
 C_PATH='@t6g_mb_lib.t6g(sch_1):page291_i40@pure_quanta.q_cap(chips)';

PART_NAME
 PC281_P0_3 'Q_CAP_C0805-22UF,16V,20%,X6S,CH6223MEA00':;

SECTION_NUMBER 1
 '@T6G_MB_LIB.T6G(SCH_1):PAGE291_I51@PURE_QUANTA.Q_CAP(CHIPS)':
 C_PATH='@t6g_mb_lib.t6g(sch_1):page291_i51@pure_quanta.q_cap(chips)';

PART_NAME
 PC280_P0_4 'Q_CAP_C0805-22UF,16V,20%,X6S,CH6223MEA00':;

SECTION_NUMBER 1
 '@T6G_MB_LIB.T6G(SCH_1):PAGE291_I38@PURE_QUANTA.Q_CAP(CHIPS)':
 C_PATH='@t6g_mb_lib.t6g(sch_1):page291_i38@pure_quanta.q_cap(chips)';

PART_NAME
 PC279 'Q_CAP_C0402-100NF,50V,10%,X7R,CH4106K1B01':;

SECTION_NUMBER 1
 '@T6G_MB_LIB.T6G(SCH_1):PAGE291_I53@PURE_QUANTA.Q_CAP(CHIPS)':
 C_PATH='@t6g_mb_lib.t6g(sch_1):page291_i53@pure_quanta.q_cap(chips)';

PART_NAME
 PC278 'Q_CAP_C0402-100NF,50V,10%,X7R,CH4106K1B01':;

SECTION_NUMBER 1
 '@T6G_MB_LIB.T6G(SCH_1):PAGE291_I39@PURE_QUANTA.Q_CAP(CHIPS)':
 C_PATH='@t6g_mb_lib.t6g(sch_1):page291_i39@pure_quanta.q_cap(chips)';

PART_NAME
 PC277_P0_3 'Q_CAP_C0402-1UF,16V,10%,X6S,CH5103KEB01':;

SECTION_NUMBER 1
 '@T6G_MB_LIB.T6G(SCH_1):PAGE291_I50@PURE_QUANTA.Q_CAP(CHIPS)':
 C_PATH='@t6g_mb_lib.t6g(sch_1):page291_i50@pure_quanta.q_cap(chips)';

PART_NAME
 PC276_P0_4 'Q_CAP_C0402-1UF,16V,10%,X6S,CH5103KEB01':;

SECTION_NUMBER 1
 '@T6G_MB_LIB.T6G(SCH_1):PAGE291_I37@PURE_QUANTA.Q_CAP(CHIPS)':
 C_PATH='@t6g_mb_lib.t6g(sch_1):page291_i37@pure_quanta.q_cap(chips)';

PART_NAME
 PC275_P0_3 'Q_CAP_0402-3300PF,50V,10%,X7R,TMP_QCH2336K1B12':;

SECTION_NUMBER 1
 '@T6G_MB_LIB.T6G(SCH_1):PAGE291_I48@PURE_QUANTA.Q_CAP(CHIPS)':
 C_PATH='@t6g_mb_lib.t6g(sch_1):page291_i48@pure_quanta.q_cap(chips)';

PART_NAME
 PC274_P0_4 'Q_CAP_0402-3300PF,50V,10%,X7R,TMP_QCH2336K1B12':;

SECTION_NUMBER 1
 '@T6G_MB_LIB.T6G(SCH_1):PAGE291_I36@PURE_QUANTA.Q_CAP(CHIPS)':
 C_PATH='@t6g_mb_lib.t6g(sch_1):page291_i36@pure_quanta.q_cap(chips)';

PART_NAME
 PC273_P0_3 'Q_CAP_C0402-2.2UF,10V,10%,X6S,CH5222KEB01':;

SECTION_NUMBER 1
 '@T6G_MB_LIB.T6G(SCH_1):PAGE291_I32@PURE_QUANTA.Q_CAP(CHIPS)':
 C_PATH='@t6g_mb_lib.t6g(sch_1):page291_i32@pure_quanta.q_cap(chips)';

PART_NAME
 PC272_P0_4 'Q_CAP_C0402-2.2UF,10V,10%,X6S,CH5222KEB01':;

SECTION_NUMBER 1
 '@T6G_MB_LIB.T6G(SCH_1):PAGE291_I17@PURE_QUANTA.Q_CAP(CHIPS)':
 C_PATH='@t6g_mb_lib.t6g(sch_1):page291_i17@pure_quanta.q_cap(chips)';

PART_NAME
 PC271 'Q_CAP_C0402-2.2UF,10V,10%,X6S,CH5222KEB01':;

SECTION_NUMBER 1
 '@T6G_MB_LIB.T6G(SCH_1):PAGE291_I26@PURE_QUANTA.Q_CAP(CHIPS)':
 C_PATH='@t6g_mb_lib.t6g(sch_1):page291_i26@pure_quanta.q_cap(chips)';

PART_NAME
 PC270 'Q_CAP_C0402-2.2UF,10V,10%,X6S,CH5222KEB01':;

SECTION_NUMBER 1
 '@T6G_MB_LIB.T6G(SCH_1):PAGE291_I8@PURE_QUANTA.Q_CAP(CHIPS)':
 C_PATH='@t6g_mb_lib.t6g(sch_1):page291_i8@pure_quanta.q_cap(chips)';

PART_NAME
 PU9_P0_5 'ISL99390FRZTR5935-ISL99390FRZ-TR5935,SMLF,IC,AL099390004':;

SECTION_NUMBER 1
 '@T6G_MB_LIB.T6G(SCH_1):PAGE292_I31@PURE_QUANTA.ISL99390FRZTR5935(CHIPS)':
 C_PATH='@s6q_mb_lib.s6q(sch_1):page292_i31@pure_quanta.isl99390frztr5935(chips)~
';

PART_NAME
 PU8_P0_6 'ISL99390FRZTR5935-ISL99390FRZ-TR5935,SMLF,IC,AL099390004':;

SECTION_NUMBER 1
 '@T6G_MB_LIB.T6G(SCH_1):PAGE292_I62@PURE_QUANTA.ISL99390FRZTR5935(CHIPS)':
 C_PATH='@s6q_mb_lib.s6q(sch_1):page292_i62@pure_quanta.isl99390frztr5935(chips)~
';

PART_NAME
 PR1771 'Q_RES_0402LF-3.3,1%,1/16W,CHIP,CS-3302FB00':;

SECTION_NUMBER 1
 '@T6G_MB_LIB.T6G(SCH_1):PAGE292_I37@PURE_QUANTA.Q_RES(CHIPS)':
 C_PATH='@t6g_mb_lib.t6g(sch_1):page292_i37@pure_quanta.q_res(chips)',
 CDSVAR_REPCELL_MPS='pure_quanta|Q_res',
 VAR_0_MPS='VALUE|0|TOLERANCE|5%|WATTAGE|1/16W|PACK_TYPE|0402LF|MATERIAL|CHIP|PA~
RT_NUMBER|CS00002JB38|STANDARD|End of Design|LIFECYCLE|Comp-Approve|PART_NUMBER|~
CS00002JB38|JEDEC_TYPE|R0402|ALT_SYMBOLS|(R0402-0201)|VALUE|0|TOL|5%|WATTAGE|1/1~
6W|CLASS|DISCRETE|DESCRIPTION|RESISTOR CHIP 0 1/16W +-5%(0402)|COMPONENT_TYPE|CH~
IP0402|LEAD_LENGTH||DFM_EXCLUSION||DAY|20100618|VARIANT_DEVICE_TYPE|Q_RES-0,5%,1~
/16W,0402LF,CHIP,C';

PART_NAME
 PR1770 'Q_RES_0402LF-3.3,1%,1/16W,CHIP,CS-3302FB00':;

SECTION_NUMBER 1
 '@T6G_MB_LIB.T6G(SCH_1):PAGE292_I17@PURE_QUANTA.Q_RES(CHIPS)':
 C_PATH='@t6g_mb_lib.t6g(sch_1):page292_i17@pure_quanta.q_res(chips)',
 CDSVAR_REPCELL_MPS='pure_quanta|Q_res',
 VAR_0_MPS='VALUE|0|TOLERANCE|5%|WATTAGE|1/16W|PACK_TYPE|0402LF|MATERIAL|CHIP|PA~
RT_NUMBER|CS00002JB38|STANDARD|End of Design|LIFECYCLE|Comp-Approve|PART_NUMBER|~
CS00002JB38|JEDEC_TYPE|R0402|ALT_SYMBOLS|(R0402-0201)|VALUE|0|TOL|5%|WATTAGE|1/1~
6W|CLASS|DISCRETE|DESCRIPTION|RESISTOR CHIP 0 1/16W +-5%(0402)|COMPONENT_TYPE|CH~
IP0402|LEAD_LENGTH||DFM_EXCLUSION||DAY|20100618|VARIANT_DEVICE_TYPE|Q_RES-0,5%,1~
/16W,0402LF,CHIP,C';

PART_NAME
 PR143 'Q_RES_0402LF-0,5%,1/16W,CHIP,CS00002JB38':;

SECTION_NUMBER 1
 '@T6G_MB_LIB.T6G(SCH_1):PAGE292_I76@PURE_QUANTA.Q_RES(CHIPS)':
 C_PATH='@t6g_mb_lib.t6g(sch_1):page292_i76@pure_quanta.q_res(chips)';

PART_NAME
 PR142 'Q_RES_0402LF-0,5%,1/16W,CHIP,CS00002JB38':;

SECTION_NUMBER 1
 '@T6G_MB_LIB.T6G(SCH_1):PAGE292_I92@PURE_QUANTA.Q_RES(CHIPS)':
 C_PATH='@t6g_mb_lib.t6g(sch_1):page292_i92@pure_quanta.q_res(chips)';

PART_NAME
 PR141 'Q_RES_0402LF-2.2,1%,1/16W,CHIP,CS-2202FB00':;

SECTION_NUMBER 1
 '@T6G_MB_LIB.T6G(SCH_1):PAGE292_I32@PURE_QUANTA.Q_RES(CHIPS)':
 C_PATH='@t6g_mb_lib.t6g(sch_1):page292_i32@pure_quanta.q_res(chips)';

PART_NAME
 PR140 'Q_RES_0402LF-2.2,1%,1/16W,CHIP,CS-2202FB00':;

SECTION_NUMBER 1
 '@T6G_MB_LIB.T6G(SCH_1):PAGE292_I11@PURE_QUANTA.Q_RES(CHIPS)':
 C_PATH='@t6g_mb_lib.t6g(sch_1):page292_i11@pure_quanta.q_res(chips)';

PART_NAME
 PR139 'Q_RES_0402LF-8.87K,1%,1/16W,EMPTY,CS28872FB01':;

SECTION_NUMBER 1
 '@T6G_MB_LIB.T6G(SCH_1):PAGE292_I21@PURE_QUANTA.Q_RES(CHIPS)':
 C_PATH='@t6g_mb_lib.t6g(sch_1):page292_i21@pure_quanta.q_res(chips)';

PART_NAME
 PR138 'Q_RES_0402LF-8.87K,1%,1/16W,EMPTY,CS28872FB01':;

SECTION_NUMBER 1
 '@T6G_MB_LIB.T6G(SCH_1):PAGE292_I2@PURE_QUANTA.Q_RES(CHIPS)':
 C_PATH='@t6g_mb_lib.t6g(sch_1):page292_i2@pure_quanta.q_res(chips)';

PART_NAME
 PL10 'Q_INDUCTOR4P_14-150NH,SMLF,IND,CV+15^0TZ01':;

SECTION_NUMBER 1
 '@T6G_MB_LIB.T6G(SCH_1):PAGE292_I74@PURE_QUANTA.Q_INDUCTOR4P_14(CHIPS)':
 C_PATH='@t6g_mb_lib.t6g(sch_1):page292_i74@pure_quanta.q_inductor4p_14(chips)';

PART_NAME
 PL9 'Q_INDUCTOR4P_14-150NH,SMLF,IND,CV+15^0TZ01':;

SECTION_NUMBER 1
 '@T6G_MB_LIB.T6G(SCH_1):PAGE292_I90@PURE_QUANTA.Q_INDUCTOR4P_14(CHIPS)':
 C_PATH='@t6g_mb_lib.t6g(sch_1):page292_i90@pure_quanta.q_inductor4p_14(chips)';

PART_NAME
 PC1343 'Q_CAP_0402-0.1UF,25V,10%,X7R,CH4104K1B00':;

SECTION_NUMBER 1
 '@T6G_MB_LIB.T6G(SCH_1):PAGE292_I27@PURE_QUANTA.Q_CAP(CHIPS)':
 C_PATH='@t6g_mb_lib.t6g(sch_1):page292_i27@pure_quanta.q_cap(chips)',
 CDSVAR_REPCELL_MPS='pure_quanta|Q_cap',
 VAR_0_MPS='VALUE|0.1UF|VOLTAGE|25V|TOLERANCE|10%|PACK_TYPE|0402|MATERIAL|EMPTY|~
PART_NUMBER|CH4104K1B00|STANDARD||LIFECYCLE||ASS_PART||PART_NUMBER|CH4104K1B00|J~
EDEC_TYPE|C0402|ALT_SYMBOLS|(C0402_OCTAGONXA,C0402-0201)|VALUE|NA|RATED_VOLTAGE|~
25V|TOL|10%|CLASS|IO|DESCRIPTION|CAP CHIP 0.1U 25V(+-10%,X7R,0402)|COMPONENT_TYP~
E|CHIP0402|LEAD_LENGTH||LPID||DATE|20160113|VARIANT_DEVICE_TYPE|Q_CAP-0.1UF,25V,~
10%,0402,EMPTY';

PART_NAME
 PC1342 'Q_CAP_0402-0.1UF,25V,10%,X7R,CH4104K1B00':;

SECTION_NUMBER 1
 '@T6G_MB_LIB.T6G(SCH_1):PAGE292_I8@PURE_QUANTA.Q_CAP(CHIPS)':
 C_PATH='@t6g_mb_lib.t6g(sch_1):page292_i8@pure_quanta.q_cap(chips)',
 CDSVAR_REPCELL_MPS='pure_quanta|Q_cap',
 VAR_0_MPS='VALUE|0.1UF|VOLTAGE|25V|TOLERANCE|10%|PACK_TYPE|0402|MATERIAL|EMPTY|~
PART_NUMBER|CH4104K1B00|STANDARD||LIFECYCLE||ASS_PART||PART_NUMBER|CH4104K1B00|J~
EDEC_TYPE|C0402|ALT_SYMBOLS|(C0402_OCTAGONXA,C0402-0201)|VALUE|NA|RATED_VOLTAGE|~
25V|TOL|10%|CLASS|IO|DESCRIPTION|CAP CHIP 0.1U 25V(+-10%,X7R,0402)|COMPONENT_TYP~
E|CHIP0402|LEAD_LENGTH||LPID||DATE|20160113|VARIANT_DEVICE_TYPE|Q_CAP-0.1UF,25V,~
10%,0402,EMPTY';

PART_NAME
 PC269_P0_5 'Q_CAP_0805-22UF,4V,20%,X6S,TMP_QCH622KMEA01':;

SECTION_NUMBER 1
 '@T6G_MB_LIB.T6G(SCH_1):PAGE292_I79@PURE_QUANTA.Q_CAP(CHIPS)':
 C_PATH='@t6g_mb_lib.t6g(sch_1):page292_i79@pure_quanta.q_cap(chips)';

PART_NAME
 PC268_P0_6 'Q_CAP_0805-22UF,4V,20%,X6S,TMP_QCH622KMEA01':;

SECTION_NUMBER 1
 '@T6G_MB_LIB.T6G(SCH_1):PAGE292_I94@PURE_QUANTA.Q_CAP(CHIPS)':
 C_PATH='@t6g_mb_lib.t6g(sch_1):page292_i94@pure_quanta.q_cap(chips)';

PART_NAME
 PC267_P0_5 'Q_CAP_0805-22UF,4V,20%,X6S,TMP_QCH622KMEA01':;

SECTION_NUMBER 1
 '@T6G_MB_LIB.T6G(SCH_1):PAGE292_I80@PURE_QUANTA.Q_CAP(CHIPS)':
 C_PATH='@t6g_mb_lib.t6g(sch_1):page292_i80@pure_quanta.q_cap(chips)';

PART_NAME
 PC266_P0_6 'Q_CAP_0805-22UF,4V,20%,X6S,TMP_QCH622KMEA01':;

SECTION_NUMBER 1
 '@T6G_MB_LIB.T6G(SCH_1):PAGE292_I95@PURE_QUANTA.Q_CAP(CHIPS)':
 C_PATH='@t6g_mb_lib.t6g(sch_1):page292_i95@pure_quanta.q_cap(chips)';

PART_NAME
 PC263_P0_5 'Q_CAP_C0805-22UF,16V,20%,X6S,CH6223MEA00':;

SECTION_NUMBER 1
 '@T6G_MB_LIB.T6G(SCH_1):PAGE292_I60@PURE_QUANTA.Q_CAP(CHIPS)':
 C_PATH='@t6g_mb_lib.t6g(sch_1):page292_i60@pure_quanta.q_cap(chips)';

PART_NAME
 PC262_P0_6 'Q_CAP_C0805-22UF,16V,20%,X6S,CH6223MEA00':;

SECTION_NUMBER 1
 '@T6G_MB_LIB.T6G(SCH_1):PAGE292_I45@PURE_QUANTA.Q_CAP(CHIPS)':
 C_PATH='@t6g_mb_lib.t6g(sch_1):page292_i45@pure_quanta.q_cap(chips)';

PART_NAME
 PC261_P0_5 'Q_CAP_C0805-22UF,16V,20%,X6S,CH6223MEA00':;

SECTION_NUMBER 1
 '@T6G_MB_LIB.T6G(SCH_1):PAGE292_I59@PURE_QUANTA.Q_CAP(CHIPS)':
 C_PATH='@t6g_mb_lib.t6g(sch_1):page292_i59@pure_quanta.q_cap(chips)';

PART_NAME
 PC260_P0_6 'Q_CAP_C0805-22UF,16V,20%,X6S,CH6223MEA00':;

SECTION_NUMBER 1
 '@T6G_MB_LIB.T6G(SCH_1):PAGE292_I41@PURE_QUANTA.Q_CAP(CHIPS)':
 C_PATH='@t6g_mb_lib.t6g(sch_1):page292_i41@pure_quanta.q_cap(chips)';

PART_NAME
 PC259_P0_5 'Q_CAP_C0805-22UF,16V,20%,X6S,CH6223MEA00':;

SECTION_NUMBER 1
 '@T6G_MB_LIB.T6G(SCH_1):PAGE292_I40@PURE_QUANTA.Q_CAP(CHIPS)':
 C_PATH='@t6g_mb_lib.t6g(sch_1):page292_i40@pure_quanta.q_cap(chips)';

PART_NAME
 PC258_P0_6 'Q_CAP_C0805-22UF,16V,20%,X6S,CH6223MEA00':;

SECTION_NUMBER 1
 '@T6G_MB_LIB.T6G(SCH_1):PAGE292_I19@PURE_QUANTA.Q_CAP(CHIPS)':
 C_PATH='@t6g_mb_lib.t6g(sch_1):page292_i19@pure_quanta.q_cap(chips)';

PART_NAME
 PC257 'Q_CAP_C0402-100NF,50V,10%,X7R,CH4106K1B01':;

SECTION_NUMBER 1
 '@T6G_MB_LIB.T6G(SCH_1):PAGE292_I42@PURE_QUANTA.Q_CAP(CHIPS)':
 C_PATH='@t6g_mb_lib.t6g(sch_1):page292_i42@pure_quanta.q_cap(chips)';

PART_NAME
 PC256 'Q_CAP_C0402-100NF,50V,10%,X7R,CH4106K1B01':;

SECTION_NUMBER 1
 '@T6G_MB_LIB.T6G(SCH_1):PAGE292_I16@PURE_QUANTA.Q_CAP(CHIPS)':
 C_PATH='@t6g_mb_lib.t6g(sch_1):page292_i16@pure_quanta.q_cap(chips)';

PART_NAME
 PC255_P0_5 'Q_CAP_C0402-1UF,16V,10%,X6S,CH5103KEB01':;

SECTION_NUMBER 1
 '@T6G_MB_LIB.T6G(SCH_1):PAGE292_I39@PURE_QUANTA.Q_CAP(CHIPS)':
 C_PATH='@t6g_mb_lib.t6g(sch_1):page292_i39@pure_quanta.q_cap(chips)';

PART_NAME
 PC254_P0_6 'Q_CAP_C0402-1UF,16V,10%,X6S,CH5103KEB01':;

SECTION_NUMBER 1
 '@T6G_MB_LIB.T6G(SCH_1):PAGE292_I18@PURE_QUANTA.Q_CAP(CHIPS)':
 C_PATH='@t6g_mb_lib.t6g(sch_1):page292_i18@pure_quanta.q_cap(chips)';

PART_NAME
 PC253_P0_5 'Q_CAP_0402-3300PF,50V,10%,X7R,TMP_QCH2336K1B12':;

SECTION_NUMBER 1
 '@T6G_MB_LIB.T6G(SCH_1):PAGE292_I38@PURE_QUANTA.Q_CAP(CHIPS)':
 C_PATH='@t6g_mb_lib.t6g(sch_1):page292_i38@pure_quanta.q_cap(chips)';

PART_NAME
 PC252_P0_6 'Q_CAP_0402-3300PF,50V,10%,X7R,TMP_QCH2336K1B12':;

SECTION_NUMBER 1
 '@T6G_MB_LIB.T6G(SCH_1):PAGE292_I15@PURE_QUANTA.Q_CAP(CHIPS)':
 C_PATH='@t6g_mb_lib.t6g(sch_1):page292_i15@pure_quanta.q_cap(chips)';

PART_NAME
 PC251_P0_5 'Q_CAP_C0402-2.2UF,10V,10%,X6S,CH5222KEB01':;

SECTION_NUMBER 1
 '@T6G_MB_LIB.T6G(SCH_1):PAGE292_I34@PURE_QUANTA.Q_CAP(CHIPS)':
 C_PATH='@t6g_mb_lib.t6g(sch_1):page292_i34@pure_quanta.q_cap(chips)';

PART_NAME
 PC250_P0_6 'Q_CAP_C0402-2.2UF,10V,10%,X6S,CH5222KEB01':;

SECTION_NUMBER 1
 '@T6G_MB_LIB.T6G(SCH_1):PAGE292_I12@PURE_QUANTA.Q_CAP(CHIPS)':
 C_PATH='@t6g_mb_lib.t6g(sch_1):page292_i12@pure_quanta.q_cap(chips)';

PART_NAME
 PC249 'Q_CAP_C0402-2.2UF,10V,10%,X6S,CH5222KEB01':;

SECTION_NUMBER 1
 '@T6G_MB_LIB.T6G(SCH_1):PAGE292_I30@PURE_QUANTA.Q_CAP(CHIPS)':
 C_PATH='@t6g_mb_lib.t6g(sch_1):page292_i30@pure_quanta.q_cap(chips)';

PART_NAME
 PC248 'Q_CAP_C0402-2.2UF,10V,10%,X6S,CH5222KEB01':;

SECTION_NUMBER 1
 '@T6G_MB_LIB.T6G(SCH_1):PAGE292_I10@PURE_QUANTA.Q_CAP(CHIPS)':
 C_PATH='@t6g_mb_lib.t6g(sch_1):page292_i10@pure_quanta.q_cap(chips)';

PART_NAME
 PU7_P0_7 'ISL99390FRZTR5935-ISL99390FRZ-TR5935,SMLF,IC,AL099390004':;

SECTION_NUMBER 1
 '@T6G_MB_LIB.T6G(SCH_1):PAGE293_I20@PURE_QUANTA.ISL99390FRZTR5935(CHIPS)':
 C_PATH='@s6q_mb_lib.s6q(sch_1):page293_i20@pure_quanta.isl99390frztr5935(chips)~
';

PART_NAME
 PU6_P0_8 'ISL99390FRZTR5935-ISL99390FRZ-TR5935,SMLF,IC,AL099390004':;

SECTION_NUMBER 1
 '@T6G_MB_LIB.T6G(SCH_1):PAGE293_I64@PURE_QUANTA.ISL99390FRZTR5935(CHIPS)':
 C_PATH='@s6q_mb_lib.s6q(sch_1):page293_i64@pure_quanta.isl99390frztr5935(chips)~
';

PART_NAME
 PR1773 'Q_RES_0402LF-3.3,1%,1/16W,CHIP,CS-3302FB00':;

SECTION_NUMBER 1
 '@T6G_MB_LIB.T6G(SCH_1):PAGE293_I49@PURE_QUANTA.Q_RES(CHIPS)':
 C_PATH='@t6g_mb_lib.t6g(sch_1):page293_i49@pure_quanta.q_res(chips)',
 CDSVAR_REPCELL_MPS='pure_quanta|Q_res',
 VAR_0_MPS='VALUE|0|TOLERANCE|5%|WATTAGE|1/16W|PACK_TYPE|0402LF|MATERIAL|CHIP|PA~
RT_NUMBER|CS00002JB38|STANDARD|End of Design|LIFECYCLE|Comp-Approve|PART_NUMBER|~
CS00002JB38|JEDEC_TYPE|R0402|ALT_SYMBOLS|(R0402-0201)|VALUE|0|TOL|5%|WATTAGE|1/1~
6W|CLASS|DISCRETE|DESCRIPTION|RESISTOR CHIP 0 1/16W +-5%(0402)|COMPONENT_TYPE|CH~
IP0402|LEAD_LENGTH||DFM_EXCLUSION||DAY|20100618|VARIANT_DEVICE_TYPE|Q_RES-0,5%,1~
/16W,0402LF,CHIP,C';

PART_NAME
 PR1772 'Q_RES_0402LF-3.3,1%,1/16W,CHIP,CS-3302FB00':;

SECTION_NUMBER 1
 '@T6G_MB_LIB.T6G(SCH_1):PAGE293_I35@PURE_QUANTA.Q_RES(CHIPS)':
 C_PATH='@t6g_mb_lib.t6g(sch_1):page293_i35@pure_quanta.q_res(chips)',
 CDSVAR_REPCELL_MPS='pure_quanta|Q_res',
 VAR_0_MPS='VALUE|0|TOLERANCE|5%|WATTAGE|1/16W|PACK_TYPE|0402LF|MATERIAL|CHIP|PA~
RT_NUMBER|CS00002JB38|STANDARD|End of Design|LIFECYCLE|Comp-Approve|PART_NUMBER|~
CS00002JB38|JEDEC_TYPE|R0402|ALT_SYMBOLS|(R0402-0201)|VALUE|0|TOL|5%|WATTAGE|1/1~
6W|CLASS|DISCRETE|DESCRIPTION|RESISTOR CHIP 0 1/16W +-5%(0402)|COMPONENT_TYPE|CH~
IP0402|LEAD_LENGTH||DFM_EXCLUSION||DAY|20100618|VARIANT_DEVICE_TYPE|Q_RES-0,5%,1~
/16W,0402LF,CHIP,C';

PART_NAME
 PR137 'Q_RES_0402LF-0,5%,1/16W,CHIP,CS00002JB38':;

SECTION_NUMBER 1
 '@T6G_MB_LIB.T6G(SCH_1):PAGE293_I84@PURE_QUANTA.Q_RES(CHIPS)':
 C_PATH='@t6g_mb_lib.t6g(sch_1):page293_i84@pure_quanta.q_res(chips)';

PART_NAME
 PR136 'Q_RES_0402LF-0,5%,1/16W,CHIP,CS00002JB38':;

SECTION_NUMBER 1
 '@T6G_MB_LIB.T6G(SCH_1):PAGE293_I99@PURE_QUANTA.Q_RES(CHIPS)':
 C_PATH='@t6g_mb_lib.t6g(sch_1):page293_i99@pure_quanta.q_res(chips)';

PART_NAME
 PR135 'Q_RES_0402LF-2.2,1%,1/16W,CHIP,CS-2202FB00':;

SECTION_NUMBER 1
 '@T6G_MB_LIB.T6G(SCH_1):PAGE293_I26@PURE_QUANTA.Q_RES(CHIPS)':
 C_PATH='@t6g_mb_lib.t6g(sch_1):page293_i26@pure_quanta.q_res(chips)';

PART_NAME
 PR134 'Q_RES_0402LF-2.2,1%,1/16W,CHIP,CS-2202FB00':;

SECTION_NUMBER 1
 '@T6G_MB_LIB.T6G(SCH_1):PAGE293_I10@PURE_QUANTA.Q_RES(CHIPS)':
 C_PATH='@t6g_mb_lib.t6g(sch_1):page293_i10@pure_quanta.q_res(chips)';

PART_NAME
 PR133 'Q_RES_0402LF-8.87K,1%,1/16W,EMPTY,CS28872FB01':;

SECTION_NUMBER 1
 '@T6G_MB_LIB.T6G(SCH_1):PAGE293_I13@PURE_QUANTA.Q_RES(CHIPS)':
 C_PATH='@t6g_mb_lib.t6g(sch_1):page293_i13@pure_quanta.q_res(chips)';

PART_NAME
 PR132 'Q_RES_0402LF-8.87K,1%,1/16W,EMPTY,CS28872FB01':;

SECTION_NUMBER 1
 '@T6G_MB_LIB.T6G(SCH_1):PAGE293_I2@PURE_QUANTA.Q_RES(CHIPS)':
 C_PATH='@t6g_mb_lib.t6g(sch_1):page293_i2@pure_quanta.q_res(chips)';

PART_NAME
 PL105 'Q_INDUCTOR_SMLF-120NH/76A,IND,CV+12^0TZ06':;

SECTION_NUMBER 1
 '@T6G_MB_LIB.T6G(SCH_1):PAGE293_I110@PURE_QUANTA.Q_INDUCTOR(CHIPS)':
 C_PATH='@t6g_mb_lib.t6g(sch_1):page293_i110@pure_quanta.q_inductor(chips)';

PART_NAME
 PL8 'Q_INDUCTOR4P_14-150NH,SMLF,IND,CV+15^0TZ01':;

SECTION_NUMBER 1
 '@T6G_MB_LIB.T6G(SCH_1):PAGE293_I81@PURE_QUANTA.Q_INDUCTOR4P_14(CHIPS)':
 C_PATH='@t6g_mb_lib.t6g(sch_1):page293_i81@pure_quanta.q_inductor4p_14(chips)';

PART_NAME
 PL7 'Q_INDUCTOR4P_14-150NH,SMLF,IND,CV+15^0TZ01':;

SECTION_NUMBER 1
 '@T6G_MB_LIB.T6G(SCH_1):PAGE293_I117@PURE_QUANTA.Q_INDUCTOR4P_14(CHIPS)':
 C_PATH='@t6g_mb_lib.t6g(sch_1):page293_i117@pure_quanta.q_inductor4p_14(chips)';

PART_NAME
 PC1345 'Q_CAP_0402-0.1UF,25V,10%,X7R,CH4104K1B00':;

SECTION_NUMBER 1
 '@T6G_MB_LIB.T6G(SCH_1):PAGE293_I28@PURE_QUANTA.Q_CAP(CHIPS)':
 C_PATH='@t6g_mb_lib.t6g(sch_1):page293_i28@pure_quanta.q_cap(chips)',
 CDSVAR_REPCELL_MPS='pure_quanta|Q_cap',
 VAR_0_MPS='VALUE|0.1UF|VOLTAGE|25V|TOLERANCE|10%|PACK_TYPE|0402|MATERIAL|EMPTY|~
PART_NUMBER|CH4104K1B00|STANDARD||LIFECYCLE||ASS_PART||PART_NUMBER|CH4104K1B00|J~
EDEC_TYPE|C0402|ALT_SYMBOLS|(C0402_OCTAGONXA,C0402-0201)|VALUE|NA|RATED_VOLTAGE|~
25V|TOL|10%|CLASS|IO|DESCRIPTION|CAP CHIP 0.1U 25V(+-10%,X7R,0402)|COMPONENT_TYP~
E|CHIP0402|LEAD_LENGTH||LPID||DATE|20160113|VARIANT_DEVICE_TYPE|Q_CAP-0.1UF,25V,~
10%,0402,EMPTY';

PART_NAME
 PC1344 'Q_CAP_0402-0.1UF,25V,10%,X7R,CH4104K1B00':;

SECTION_NUMBER 1
 '@T6G_MB_LIB.T6G(SCH_1):PAGE293_I16@PURE_QUANTA.Q_CAP(CHIPS)':
 C_PATH='@t6g_mb_lib.t6g(sch_1):page293_i16@pure_quanta.q_cap(chips)',
 CDSVAR_REPCELL_MPS='pure_quanta|Q_cap',
 VAR_0_MPS='VALUE|0.1UF|VOLTAGE|25V|TOLERANCE|10%|PACK_TYPE|0402|MATERIAL|EMPTY|~
PART_NUMBER|CH4104K1B00|STANDARD||LIFECYCLE||ASS_PART||PART_NUMBER|CH4104K1B00|J~
EDEC_TYPE|C0402|ALT_SYMBOLS|(C0402_OCTAGONXA,C0402-0201)|VALUE|NA|RATED_VOLTAGE|~
25V|TOL|10%|CLASS|IO|DESCRIPTION|CAP CHIP 0.1U 25V(+-10%,X7R,0402)|COMPONENT_TYP~
E|CHIP0402|LEAD_LENGTH||LPID||DATE|20160113|VARIANT_DEVICE_TYPE|Q_CAP-0.1UF,25V,~
10%,0402,EMPTY';

PART_NAME
 PC247_P0_7 'Q_CAP_0805-22UF,4V,20%,X6S,TMP_QCH622KMEA01':;

SECTION_NUMBER 1
 '@T6G_MB_LIB.T6G(SCH_1):PAGE293_I77@PURE_QUANTA.Q_CAP(CHIPS)':
 C_PATH='@t6g_mb_lib.t6g(sch_1):page293_i77@pure_quanta.q_cap(chips)';

PART_NAME
 PC246_P0_8 'Q_CAP_0805-22UF,4V,20%,X6S,TMP_QCH622KMEA01':;

SECTION_NUMBER 1
 '@T6G_MB_LIB.T6G(SCH_1):PAGE293_I101@PURE_QUANTA.Q_CAP(CHIPS)':
 C_PATH='@t6g_mb_lib.t6g(sch_1):page293_i101@pure_quanta.q_cap(chips)';

PART_NAME
 PC245_P0_7 'Q_CAP_0805-22UF,4V,20%,X6S,TMP_QCH622KMEA01':;

SECTION_NUMBER 1
 '@T6G_MB_LIB.T6G(SCH_1):PAGE293_I78@PURE_QUANTA.Q_CAP(CHIPS)':
 C_PATH='@t6g_mb_lib.t6g(sch_1):page293_i78@pure_quanta.q_cap(chips)';

PART_NAME
 PC244_P0_8 'Q_CAP_0805-22UF,4V,20%,X6S,TMP_QCH622KMEA01':;

SECTION_NUMBER 1
 '@T6G_MB_LIB.T6G(SCH_1):PAGE293_I103@PURE_QUANTA.Q_CAP(CHIPS)':
 C_PATH='@t6g_mb_lib.t6g(sch_1):page293_i103@pure_quanta.q_cap(chips)';

PART_NAME
 PC243_P0_7 'Q_CAP_C0402-1UF,16V,10%,X6S,CH5103KEB01':;

SECTION_NUMBER 1
 '@T6G_MB_LIB.T6G(SCH_1):PAGE293_I79@PURE_QUANTA.Q_CAP(CHIPS)':
 C_PATH='@t6g_mb_lib.t6g(sch_1):page293_i79@pure_quanta.q_cap(chips)';

PART_NAME
 PC242_P0_8 'Q_CAP_C0402-1UF,16V,10%,X6S,CH5103KEB01':;

SECTION_NUMBER 1
 '@T6G_MB_LIB.T6G(SCH_1):PAGE293_I104@PURE_QUANTA.Q_CAP(CHIPS)':
 C_PATH='@t6g_mb_lib.t6g(sch_1):page293_i104@pure_quanta.q_cap(chips)';

PART_NAME
 PC241_P0_7 'Q_CAP_C0805-22UF,16V,20%,X6S,CH6223MEA00':;

SECTION_NUMBER 1
 '@T6G_MB_LIB.T6G(SCH_1):PAGE293_I58@PURE_QUANTA.Q_CAP(CHIPS)':
 C_PATH='@t6g_mb_lib.t6g(sch_1):page293_i58@pure_quanta.q_cap(chips)';

PART_NAME
 PC240_P0_8 'Q_CAP_C0805-22UF,16V,20%,X6S,CH6223MEA00':;

SECTION_NUMBER 1
 '@T6G_MB_LIB.T6G(SCH_1):PAGE293_I40@PURE_QUANTA.Q_CAP(CHIPS)':
 C_PATH='@t6g_mb_lib.t6g(sch_1):page293_i40@pure_quanta.q_cap(chips)';

PART_NAME
 PC239_P0_7 'Q_CAP_C0805-22UF,16V,20%,X6S,CH6223MEA00':;

SECTION_NUMBER 1
 '@T6G_MB_LIB.T6G(SCH_1):PAGE293_I57@PURE_QUANTA.Q_CAP(CHIPS)':
 C_PATH='@t6g_mb_lib.t6g(sch_1):page293_i57@pure_quanta.q_cap(chips)';

PART_NAME
 PC238_P0_8 'Q_CAP_C0805-22UF,16V,20%,X6S,CH6223MEA00':;

SECTION_NUMBER 1
 '@T6G_MB_LIB.T6G(SCH_1):PAGE293_I39@PURE_QUANTA.Q_CAP(CHIPS)':
 C_PATH='@t6g_mb_lib.t6g(sch_1):page293_i39@pure_quanta.q_cap(chips)';

PART_NAME
 PC237_P0_7 'Q_CAP_C0805-22UF,16V,20%,X6S,CH6223MEA00':;

SECTION_NUMBER 1
 '@T6G_MB_LIB.T6G(SCH_1):PAGE293_I52@PURE_QUANTA.Q_CAP(CHIPS)':
 C_PATH='@t6g_mb_lib.t6g(sch_1):page293_i52@pure_quanta.q_cap(chips)';

PART_NAME
 PC236_P0_8 'Q_CAP_C0805-22UF,16V,20%,X6S,CH6223MEA00':;

SECTION_NUMBER 1
 '@T6G_MB_LIB.T6G(SCH_1):PAGE293_I38@PURE_QUANTA.Q_CAP(CHIPS)':
 C_PATH='@t6g_mb_lib.t6g(sch_1):page293_i38@pure_quanta.q_cap(chips)';

PART_NAME
 PC235 'Q_CAP_C0402-100NF,50V,10%,X7R,CH4106K1B01':;

SECTION_NUMBER 1
 '@T6G_MB_LIB.T6G(SCH_1):PAGE293_I55@PURE_QUANTA.Q_CAP(CHIPS)':
 C_PATH='@t6g_mb_lib.t6g(sch_1):page293_i55@pure_quanta.q_cap(chips)';

PART_NAME
 PC234 'Q_CAP_C0402-100NF,50V,10%,X7R,CH4106K1B01':;

SECTION_NUMBER 1
 '@T6G_MB_LIB.T6G(SCH_1):PAGE293_I33@PURE_QUANTA.Q_CAP(CHIPS)':
 C_PATH='@t6g_mb_lib.t6g(sch_1):page293_i33@pure_quanta.q_cap(chips)';

PART_NAME
 PC233_P0_7 'Q_CAP_C0402-1UF,16V,10%,X6S,CH5103KEB01':;

SECTION_NUMBER 1
 '@T6G_MB_LIB.T6G(SCH_1):PAGE293_I51@PURE_QUANTA.Q_CAP(CHIPS)':
 C_PATH='@t6g_mb_lib.t6g(sch_1):page293_i51@pure_quanta.q_cap(chips)';

PART_NAME
 PC232_P0_8 'Q_CAP_C0402-1UF,16V,10%,X6S,CH5103KEB01':;

SECTION_NUMBER 1
 '@T6G_MB_LIB.T6G(SCH_1):PAGE293_I37@PURE_QUANTA.Q_CAP(CHIPS)':
 C_PATH='@t6g_mb_lib.t6g(sch_1):page293_i37@pure_quanta.q_cap(chips)';

PART_NAME
 PC231_P0_7 'Q_CAP_0402-3300PF,50V,10%,X7R,TMP_QCH2336K1B12':;

SECTION_NUMBER 1
 '@T6G_MB_LIB.T6G(SCH_1):PAGE293_I50@PURE_QUANTA.Q_CAP(CHIPS)':
 C_PATH='@t6g_mb_lib.t6g(sch_1):page293_i50@pure_quanta.q_cap(chips)';

PART_NAME
 PC230_P0_8 'Q_CAP_0402-3300PF,50V,10%,X7R,TMP_QCH2336K1B12':;

SECTION_NUMBER 1
 '@T6G_MB_LIB.T6G(SCH_1):PAGE293_I36@PURE_QUANTA.Q_CAP(CHIPS)':
 C_PATH='@t6g_mb_lib.t6g(sch_1):page293_i36@pure_quanta.q_cap(chips)';

PART_NAME
 PC229_P0_7 'Q_CAP_C0402-2.2UF,10V,10%,X6S,CH5222KEB01':;

SECTION_NUMBER 1
 '@T6G_MB_LIB.T6G(SCH_1):PAGE293_I30@PURE_QUANTA.Q_CAP(CHIPS)':
 C_PATH='@t6g_mb_lib.t6g(sch_1):page293_i30@pure_quanta.q_cap(chips)';

PART_NAME
 PC228_P0_8 'Q_CAP_C0402-2.2UF,10V,10%,X6S,CH5222KEB01':;

SECTION_NUMBER 1
 '@T6G_MB_LIB.T6G(SCH_1):PAGE293_I19@PURE_QUANTA.Q_CAP(CHIPS)':
 C_PATH='@t6g_mb_lib.t6g(sch_1):page293_i19@pure_quanta.q_cap(chips)';

PART_NAME
 PC227 'Q_CAP_C0402-2.2UF,10V,10%,X6S,CH5222KEB01':;

SECTION_NUMBER 1
 '@T6G_MB_LIB.T6G(SCH_1):PAGE293_I25@PURE_QUANTA.Q_CAP(CHIPS)':
 C_PATH='@t6g_mb_lib.t6g(sch_1):page293_i25@pure_quanta.q_cap(chips)';

PART_NAME
 PC226 'Q_CAP_C0402-2.2UF,10V,10%,X6S,CH5222KEB01':;

SECTION_NUMBER 1
 '@T6G_MB_LIB.T6G(SCH_1):PAGE293_I9@PURE_QUANTA.Q_CAP(CHIPS)':
 C_PATH='@t6g_mb_lib.t6g(sch_1):page293_i9@pure_quanta.q_cap(chips)';

PART_NAME
 R2322 'Q_RES_0402LF-49.9     ,1%  ,1/16W,EMPTY,CS04992FB31':;

SECTION_NUMBER 1
 '@T6G_MB_LIB.T6G(SCH_1):PAGE297_I22@PURE_QUANTA.Q_RES(CHIPS)':
 C_PATH='@t6g_mb_lib.t6g(sch_1):page297_i22@pure_quanta.q_res(chips)';

PART_NAME
 R561 'Q_RES_0402LF-100,1%,1/16W,EMPTY,TMP_QCS11002FB22':;

SECTION_NUMBER 1
 '@T6G_MB_LIB.T6G(SCH_1):PAGE297_I21@PURE_QUANTA.Q_RES(CHIPS)':
 C_PATH='@t6g_mb_lib.t6g(sch_1):page297_i21@pure_quanta.q_res(chips)';

PART_NAME
 PU5 'ISL69260IRAZT-ISL69260IRAZ-T,SMLF,IC,AL069260000':;

SECTION_NUMBER 1
 '@T6G_MB_LIB.T6G(SCH_1):PAGE297_I51@PURE_QUANTA.ISL69260IRAZT(CHIPS)':
 C_PATH='@t6g_mb_lib.t6g(sch_1):page297_i51@pure_quanta.isl69260irazt(chips)',
 VAR_0_MPS='';

PART_NAME
 PR524 'Q_RES_0402LF-1K,1%,1/16W,CHIP,TMP_QCS21002FB24':;

SECTION_NUMBER 1
 '@T6G_MB_LIB.T6G(SCH_1):PAGE297_I42@PURE_QUANTA.Q_RES(CHIPS)':
 C_PATH='@t6g_mb_lib.t6g(sch_1):page297_i42@pure_quanta.q_res(chips)';

PART_NAME
 PR523 'Q_RES_0402LF-1K,1%,1/16W,CHIP,TMP_QCS21002FB24':;

SECTION_NUMBER 1
 '@T6G_MB_LIB.T6G(SCH_1):PAGE297_I41@PURE_QUANTA.Q_RES(CHIPS)':
 C_PATH='@t6g_mb_lib.t6g(sch_1):page297_i41@pure_quanta.q_res(chips)';

PART_NAME
 PR522 'Q_RES_0402LF-100,1%,1/16W,CHIP,TMP_QCS11002FB22':;

SECTION_NUMBER 1
 '@T6G_MB_LIB.T6G(SCH_1):PAGE297_I10@PURE_QUANTA.Q_RES(CHIPS)':
 C_PATH='@t6g_mb_lib.t6g(sch_1):page297_i10@pure_quanta.q_res(chips)';

PART_NAME
 PR521 'Q_RES_0402LF-100,1%,1/16W,CHIP,TMP_QCS11002FB22':;

SECTION_NUMBER 1
 '@T6G_MB_LIB.T6G(SCH_1):PAGE297_I16@PURE_QUANTA.Q_RES(CHIPS)':
 C_PATH='@t6g_mb_lib.t6g(sch_1):page297_i16@pure_quanta.q_res(chips)';

PART_NAME
 PR520 'Q_RES_0402LF-100,1%,1/16W,CHIP,TMP_QCS11002FB22':;

SECTION_NUMBER 1
 '@T6G_MB_LIB.T6G(SCH_1):PAGE297_I8@PURE_QUANTA.Q_RES(CHIPS)':
 C_PATH='@t6g_mb_lib.t6g(sch_1):page297_i8@pure_quanta.q_res(chips)';

PART_NAME
 PR519 'Q_RES_0402LF-100,1%,1/16W,CHIP,TMP_QCS11002FB22':;

SECTION_NUMBER 1
 '@T6G_MB_LIB.T6G(SCH_1):PAGE297_I11@PURE_QUANTA.Q_RES(CHIPS)':
 C_PATH='@t6g_mb_lib.t6g(sch_1):page297_i11@pure_quanta.q_res(chips)';

PART_NAME
 PR436 'Q_RES_0402LF-10K,1%,1/16W,EMPTY,CS31002FB08':;

SECTION_NUMBER 1
 '@T6G_MB_LIB.T6G(SCH_1):PAGE297_I79@PURE_QUANTA.Q_RES(CHIPS)':
 C_PATH='@t6g_mb_lib.t6g(sch_1):page297_i79@pure_quanta.q_res(chips)',
 CDSVAR_REPCELL_MPS='pure_quanta|Q_res',
 VAR_0_MPS='VALUE|10K|TOLERANCE|1%|WATTAGE|1/16W|PACK_TYPE|0402LF|MATERIAL|CHIP|~
PART_NUMBER|CS31002FB08|STANDARD|End of Design|LIFECYCLE|Comp-Approve|PART_NUMBE~
R|CS31002FB08|JEDEC_TYPE|R0402|ALT_SYMBOLS|(R0402-0201)|VALUE|10K|TOL|1%|WATTAGE~
|1/16W|CLASS|DISCRETE|DESCRIPTION|RES CHIP 10K 1/16W +-1%(0402)EF|COMPONENT_TYPE~
|CHIPR0402|LEAD_LENGTH||DFM_EXCLUSION||DAY|20180208|VARIANT_DEVICE_TYPE|Q_RES-10~
K,1%,1/16W,0402LF,CHIP';

PART_NAME
 PR435 'Q_RES_0402LF-10K,1%,1/16W,EMPTY,CS31002FB08':;

SECTION_NUMBER 1
 '@T6G_MB_LIB.T6G(SCH_1):PAGE297_I73@PURE_QUANTA.Q_RES(CHIPS)':
 C_PATH='@t6g_mb_lib.t6g(sch_1):page297_i73@pure_quanta.q_res(chips)',
 VAR_0_MPS='VALUE|10K|TOLERANCE|1%|WATTAGE|1/16W|PACK_TYPE|0402LF|MATERIAL|CHIP|~
PART_NUMBER|CS31002FB08|STANDARD|End of Design|LIFECYCLE|Comp-Approve|PART_NUMBE~
R|CS31002FB08|JEDEC_TYPE|R0402|ALT_SYMBOLS|(R0402-0201)|VALUE|10K|TOL|1%|WATTAGE~
|1/16W|CLASS|DISCRETE|DESCRIPTION|RES CHIP 10K 1/16W +-1%(0402)EF|COMPONENT_TYPE~
|CHIPR0402|LEAD_LENGTH||DFM_EXCLUSION||DAY|20180208|VARIANT_DEVICE_TYPE|Q_RES-10~
K,1%,1/16W,0402LF,CHIP',
 CDSVAR_REPCELL_MPS='pure_quanta|Q_res';

PART_NAME
 PR131 'Q_RES_0402LF-1K,1%,1/16W,CHIP,TMP_QCS21002FB24':;

SECTION_NUMBER 1
 '@T6G_MB_LIB.T6G(SCH_1):PAGE297_I80@PURE_QUANTA.Q_RES(CHIPS)':
 C_PATH='@t6g_mb_lib.t6g(sch_1):page297_i80@pure_quanta.q_res(chips)';

PART_NAME
 PR130 'Q_RES_0402LF-1,1%,1/16W,CHIP,CS-1002FB23':;

SECTION_NUMBER 1
 '@T6G_MB_LIB.T6G(SCH_1):PAGE297_I95@PURE_QUANTA.Q_RES(CHIPS)':
 C_PATH='@t6g_mb_lib.t6g(sch_1):page297_i95@pure_quanta.q_res(chips)';

PART_NAME
 PR123 'Q_RES_0402LF-1K,1%,1/16W,EMPTY,TMP_QCS21002FB24':;

SECTION_NUMBER 1
 '@T6G_MB_LIB.T6G(SCH_1):PAGE297_I36@PURE_QUANTA.Q_RES(CHIPS)':
 C_PATH='@t6g_mb_lib.t6g(sch_1):page297_i36@pure_quanta.q_res(chips)',
 CDSVAR_REPCELL_MPS='pure_quanta|Q_res',
 VAR_0_MPS='VALUE|1K|TOLERANCE|1%|WATTAGE|1/16W|PACK_TYPE|0402LF|MATERIAL|CHIP|P~
ART_NUMBER|TMP_QCS21002FB24|STANDARD|End of Design|LIFECYCLE|Comp-Approve|PART_N~
UMBER|CS21002FB24|JEDEC_TYPE|R0402|ALT_SYMBOLS|(R0402-0201)|VALUE|1K|TOL|1%|WATT~
AGE|1/16W|CLASS|DISCRETE|DESCRIPTION|RES CHIP 1K 1/16W +-1% (0402)|COMPONENT_TYP~
E|CHIP0402|LEAD_LENGTH||DFM_EXCLUSION||DAY||VARIANT_DEVICE_TYPE|Q_RES-1K,1%,1/16~
W,0402LF,CHIP,';

PART_NAME
 PR122 'Q_RES_0402LF-0,5%,1/16W,CHIP,CS00002JB38':;

SECTION_NUMBER 1
 '@T6G_MB_LIB.T6G(SCH_1):PAGE297_I33@PURE_QUANTA.Q_RES(CHIPS)':
 C_PATH='@t6g_mb_lib.t6g(sch_1):page297_i33@pure_quanta.q_res(chips)',
 VAR_0_MPS='';

PART_NAME
 PR121 'Q_RES_0402LF-0,5%,1/16W,CHIP,CS00002JB38':;

SECTION_NUMBER 1
 '@T6G_MB_LIB.T6G(SCH_1):PAGE297_I45@PURE_QUANTA.Q_RES(CHIPS)':
 C_PATH='@t6g_mb_lib.t6g(sch_1):page297_i45@pure_quanta.q_res(chips)';

PART_NAME
 PR120 'Q_RES_0402LF-0,5%,1/16W,CHIP,CS00002JB38':;

SECTION_NUMBER 1
 '@T6G_MB_LIB.T6G(SCH_1):PAGE297_I58@PURE_QUANTA.Q_RES(CHIPS)':
 C_PATH='@t6g_mb_lib.t6g(sch_1):page297_i58@pure_quanta.q_res(chips)';

PART_NAME
 PR119 'Q_RES_0402LF-0,5%,1/16W,CHIP,CS00002JB38':;

SECTION_NUMBER 1
 '@T6G_MB_LIB.T6G(SCH_1):PAGE297_I32@PURE_QUANTA.Q_RES(CHIPS)':
 C_PATH='@t6g_mb_lib.t6g(sch_1):page297_i32@pure_quanta.q_res(chips)';

PART_NAME
 PR118 'Q_RES_0402LF-0,5%,1/16W,CHIP,CS00002JB38':;

SECTION_NUMBER 1
 '@T6G_MB_LIB.T6G(SCH_1):PAGE297_I30@PURE_QUANTA.Q_RES(CHIPS)':
 C_PATH='@t6g_mb_lib.t6g(sch_1):page297_i30@pure_quanta.q_res(chips)';

PART_NAME
 PR117 'Q_RES_0402LF-1K,1%,1/16W,CHIP,TMP_QCS21002FB24':;

SECTION_NUMBER 1
 '@T6G_MB_LIB.T6G(SCH_1):PAGE297_I31@PURE_QUANTA.Q_RES(CHIPS)':
 C_PATH='@t6g_mb_lib.t6g(sch_1):page297_i31@pure_quanta.q_res(chips)';

PART_NAME
 PR116 'Q_RES_0402LF-0,5%,1/16W,CHIP,CS00002JB38':;

SECTION_NUMBER 1
 '@T6G_MB_LIB.T6G(SCH_1):PAGE297_I59@PURE_QUANTA.Q_RES(CHIPS)':
 C_PATH='@t6g_mb_lib.t6g(sch_1):page297_i59@pure_quanta.q_res(chips)';

PART_NAME
 PR115 'Q_RES_0402LF-0,5%,1/16W,CHIP,CS00002JB38':;

SECTION_NUMBER 1
 '@T6G_MB_LIB.T6G(SCH_1):PAGE297_I60@PURE_QUANTA.Q_RES(CHIPS)':
 C_PATH='@t6g_mb_lib.t6g(sch_1):page297_i60@pure_quanta.q_res(chips)';

PART_NAME
 PR114 'Q_RES_0402LF-0,5%,1/16W,CHIP,CS00002JB38':;

SECTION_NUMBER 1
 '@T6G_MB_LIB.T6G(SCH_1):PAGE297_I61@PURE_QUANTA.Q_RES(CHIPS)':
 C_PATH='@t6g_mb_lib.t6g(sch_1):page297_i61@pure_quanta.q_res(chips)';

PART_NAME
 PR113 'Q_RES_0402LF-0,5%,1/16W,CHIP,CS00002JB38':;

SECTION_NUMBER 1
 '@T6G_MB_LIB.T6G(SCH_1):PAGE297_I62@PURE_QUANTA.Q_RES(CHIPS)':
 C_PATH='@t6g_mb_lib.t6g(sch_1):page297_i62@pure_quanta.q_res(chips)';

PART_NAME
 PR112 'Q_RES_0402LF-150,1%,1/16W,CHIP,TMP_QCS11502FB21':;

SECTION_NUMBER 1
 '@T6G_MB_LIB.T6G(SCH_1):PAGE297_I63@PURE_QUANTA.Q_RES(CHIPS)':
 C_PATH='@t6g_mb_lib.t6g(sch_1):page297_i63@pure_quanta.q_res(chips)';

PART_NAME
 PR111 'Q_RES_0402LF-0,5%,1/16W,CHIP,CS00002JB38':;

SECTION_NUMBER 1
 '@T6G_MB_LIB.T6G(SCH_1):PAGE297_I64@PURE_QUANTA.Q_RES(CHIPS)':
 C_PATH='@t6g_mb_lib.t6g(sch_1):page297_i64@pure_quanta.q_res(chips)';

PART_NAME
 PR110 'Q_RES_0402LF-0,5%,1/16W,CHIP,CS00002JB38':;

SECTION_NUMBER 1
 '@T6G_MB_LIB.T6G(SCH_1):PAGE297_I67@PURE_QUANTA.Q_RES(CHIPS)':
 C_PATH='@t6g_mb_lib.t6g(sch_1):page297_i67@pure_quanta.q_res(chips)';

PART_NAME
 PR109 'Q_RES_0402LF-1K,1%,1/16W,CHIP,TMP_QCS21002FB24':;

SECTION_NUMBER 1
 '@T6G_MB_LIB.T6G(SCH_1):PAGE297_I68@PURE_QUANTA.Q_RES(CHIPS)':
 C_PATH='@t6g_mb_lib.t6g(sch_1):page297_i68@pure_quanta.q_res(chips)';

PART_NAME
 PR108 'Q_RES_0402LF-0,5%,1/16W,CHIP,CS00002JB38':;

SECTION_NUMBER 1
 '@T6G_MB_LIB.T6G(SCH_1):PAGE297_I27@PURE_QUANTA.Q_RES(CHIPS)':
 C_PATH='@t6g_mb_lib.t6g(sch_1):page297_i27@pure_quanta.q_res(chips)',
 CDSVAR_REPCELL_MPS='pure_quanta|Q_res',
 VAR_0_MPS='VALUE|15K|TOLERANCE|1%|WATTAGE|1/16W|PACK_TYPE|0402LF|MATERIAL|CHIP|~
PART_NUMBER|TMP_QCS31502FB24|STANDARD|End of Design|LIFECYCLE|Comp-Approve|PART_~
NUMBER|CS31502FB24|JEDEC_TYPE|R0402|ALT_SYMBOLS|(R0402-0201)|VALUE|15K|TOL|1%|WA~
TTAGE|1/16W |CLASS|DISCRETE|DESCRIPTION|RES CHIP 15K 1/16W +-1% (0402)|COMPONENT~
_TYPE|CHIP0402|LEAD_LENGTH||DFM_EXCLUSION||DAY||VARIANT_DEVICE_TYPE|Q_RES-15K,1%~
,1/16W,0402LF,CHIP';

PART_NAME
 PR107 'Q_RES_0402LF-0,5%,1/16W,EMPTY,CS00002JB38':;

SECTION_NUMBER 1
 '@T6G_MB_LIB.T6G(SCH_1):PAGE297_I28@PURE_QUANTA.Q_RES(CHIPS)':
 C_PATH='@t6g_mb_lib.t6g(sch_1):page297_i28@pure_quanta.q_res(chips)',
 VAR_0_MPS='';

PART_NAME
 PR106 'Q_RES_R0402LF-887,1%,1/16W,CHIP,CS18872FB01':;

SECTION_NUMBER 1
 '@T6G_MB_LIB.T6G(SCH_1):PAGE297_I25@PURE_QUANTA.Q_RES(CHIPS)':
 C_PATH='@t6g_mb_lib.t6g(sch_1):page297_i25@pure_quanta.q_res(chips)',
 CDSVAR_REPCELL_MPS='pure_quanta|Q_res',
 VAR_0_MPS='VALUE|0|TOLERANCE|5%|WATTAGE|1/16W|PACK_TYPE|0402LF|MATERIAL|CHIP|PA~
RT_NUMBER|CS00002JB38|STANDARD|End of Design|LIFECYCLE|Comp-Approve|PART_NUMBER|~
CS00002JB38|JEDEC_TYPE|R0402|ALT_SYMBOLS|(R0402-0201)|VALUE|0|TOL|5%|WATTAGE|1/1~
6W|CLASS|DISCRETE|DESCRIPTION|RESISTOR CHIP 0 1/16W +-5%(0402)|COMPONENT_TYPE|CH~
IP0402|LEAD_LENGTH||DFM_EXCLUSION||DAY|20100618|VARIANT_DEVICE_TYPE|Q_RES-0,5%,1~
/16W,0402LF,CHIP,C';

PART_NAME
 PR105 'Q_RES_0402LF-28K,1%,1/16W,EMPTY,CS32802FB05':;

SECTION_NUMBER 1
 '@T6G_MB_LIB.T6G(SCH_1):PAGE297_I3@PURE_QUANTA.Q_RES(CHIPS)':
 C_PATH='@t6g_mb_lib.t6g(sch_1):page297_i3@pure_quanta.q_res(chips)';

PART_NAME
 PJ46 'Q_SHORT_SM-EMPTY,SHORT6':;

SECTION_NUMBER 1
 '@T6G_MB_LIB.T6G(SCH_1):PAGE297_I9@PURE_QUANTA.Q_SHORT(CHIPS)':
 C_PATH='@t6g_mb_lib.t6g(sch_1):page297_i9@pure_quanta.q_short(chips)';

PART_NAME
 PJ45 'Q_SHORT_SM-EMPTY,SHORT6':;

SECTION_NUMBER 1
 '@T6G_MB_LIB.T6G(SCH_1):PAGE297_I15@PURE_QUANTA.Q_SHORT(CHIPS)':
 C_PATH='@t6g_mb_lib.t6g(sch_1):page297_i15@pure_quanta.q_short(chips)';

PART_NAME
 PC1372 'Q_CAP_C0402-1UF,16V,10%,X6S,CH5103KEB01':;

SECTION_NUMBER 1
 '@T6G_MB_LIB.T6G(SCH_1):PAGE297_I90@PURE_QUANTA.Q_CAP(CHIPS)':
 C_PATH='@t6g_mb_lib.t6g(sch_1):page297_i90@pure_quanta.q_cap(chips)';

PART_NAME
 PC1271 'Q_CAP_0402-470PF,50V,10%,X7R,TMP_QCH14706KB18':;

SECTION_NUMBER 1
 '@T6G_MB_LIB.T6G(SCH_1):PAGE297_I56@PURE_QUANTA.Q_CAP(CHIPS)':
 C_PATH='@t6g_mb_lib.t6g(sch_1):page297_i56@pure_quanta.q_cap(chips)',
 CDSVAR_REPCELL_MPS='pure_quanta|Q_cap',
 VAR_0_MPS='VALUE|0.01UF|VOLTAGE|25V|TOLERANCE|10%|PACK_TYPE|0402|MATERIAL|X7R|P~
ART_NUMBER|TMP_QCH31004KB17|STANDARD|End of Design|LIFECYCLE|Comp-Approve|ASS_PA~
RT||PART_NUMBER|CH31004KB17|JEDEC_TYPE|C0402|ALT_SYMBOLS|(C0402-0201)|VALUE|0.01~
UF|RATED_VOLTAGE|25V|TOL|10%|CLASS|DISCRETE|DESCRIPTION|CAP CHIP 0.01U 25V(+-10%~
,X7R,0402)|COMPONENT_TYPE|CHIP0402|LEAD_LENGTH||LPID||DATE|20100528|VARIANT_DEVI~
CE_TYPE|Q_CAP-0.01UF,25V,10%,0402,X7R,';

PART_NAME
 PC225 'Q_CAP_C0402-1UF,16V,10%,X6S,CH5103KEB01':;

SECTION_NUMBER 1
 '@T6G_MB_LIB.T6G(SCH_1):PAGE297_I92@PURE_QUANTA.Q_CAP(CHIPS)':
 C_PATH='@t6g_mb_lib.t6g(sch_1):page297_i92@pure_quanta.q_cap(chips)';

PART_NAME
 PC224 'Q_CAP_0402-4.7UF,6.3V,20%,X6S,CH5471MEB01':;

SECTION_NUMBER 1
 '@T6G_MB_LIB.T6G(SCH_1):PAGE297_I87@PURE_QUANTA.Q_CAP(CHIPS)':
 C_PATH='@t6g_mb_lib.t6g(sch_1):page297_i87@pure_quanta.q_cap(chips)',
 CDSVAR_REPCELL_MPS='pure_quanta|Q_cap',
 VAR_0_MPS='VALUE|4.7UF|VOLTAGE|6.3V|TOLERANCE|20%|PACK_TYPE|0402|MATERIAL|EMPTY~
|PART_NUMBER|CH5471MEB01|STANDARD||LIFECYCLE||ASS_PART||PART_NUMBER|CH5471MEB01|~
JEDEC_TYPE|C0402|ALT_SYMBOLS|(C0402_OCTAGON,C0402_OCTAGONXA,C0402-0201)|VALUE|NA~
|RATED_VOLTAGE|6.3V|TOL|20%|CLASS|IO|DESCRIPTION|CAP CHIP 4.7UF 6.3V(+-20%,X6S,0~
402)|COMPONENT_TYPE|CHIP0402|LEAD_LENGTH||LPID||DATE|20151211|VARIANT_DEVICE_TYP~
E|Q_CAP-4.7UF,6.3V,20%,0402,EMPT';

PART_NAME
 PC223 'Q_CAP_C0402-100NF,50V,10%,EMPTY,CH4106K1B01':;

SECTION_NUMBER 1
 '@T6G_MB_LIB.T6G(SCH_1):PAGE297_I88@PURE_QUANTA.Q_CAP(CHIPS)':
 C_PATH='@t6g_mb_lib.t6g(sch_1):page297_i88@pure_quanta.q_cap(chips)';

PART_NAME
 PC222 'Q_CAP_0402-470PF,50V,10%,X7R,TMP_QCH14706KB18':;

SECTION_NUMBER 1
 '@T6G_MB_LIB.T6G(SCH_1):PAGE297_I55@PURE_QUANTA.Q_CAP(CHIPS)':
 C_PATH='@t6g_mb_lib.t6g(sch_1):page297_i55@pure_quanta.q_cap(chips)',
 CDSVAR_REPCELL_MPS='pure_quanta|Q_cap',
 VAR_0_MPS='VALUE|0.01UF|VOLTAGE|25V|TOLERANCE|10%|PACK_TYPE|0402|MATERIAL|X7R|P~
ART_NUMBER|TMP_QCH31004KB17|STANDARD|End of Design|LIFECYCLE|Comp-Approve|ASS_PA~
RT||PART_NUMBER|CH31004KB17|JEDEC_TYPE|C0402|ALT_SYMBOLS|(C0402-0201)|VALUE|0.01~
UF|RATED_VOLTAGE|25V|TOL|10%|CLASS|DISCRETE|DESCRIPTION|CAP CHIP 0.01U 25V(+-10%~
,X7R,0402)|COMPONENT_TYPE|CHIP0402|LEAD_LENGTH||LPID||DATE|20100528|VARIANT_DEVI~
CE_TYPE|Q_CAP-0.01UF,25V,10%,0402,X7R,';

PART_NAME
 PC221 'Q_CAP_0402-0.1UF,25V,10%,X7R,CH4104K1B00':;

SECTION_NUMBER 1
 '@T6G_MB_LIB.T6G(SCH_1):PAGE297_I49@PURE_QUANTA.Q_CAP(CHIPS)':
 C_PATH='@t6g_mb_lib.t6g(sch_1):page297_i49@pure_quanta.q_cap(chips)';

PART_NAME
 PC220 'Q_CAP_0402-1000PF,50V,5%,EMPTY,TMP_QCH21006JB10':;

SECTION_NUMBER 1
 '@T6G_MB_LIB.T6G(SCH_1):PAGE297_I38@PURE_QUANTA.Q_CAP(CHIPS)':
 C_PATH='@t6g_mb_lib.t6g(sch_1):page297_i38@pure_quanta.q_cap(chips)';

PART_NAME
 PC219 'Q_CAP_0402-1000PF,50V,5%,X7R,TMP_QCH21006JB10':;

SECTION_NUMBER 1
 '@T6G_MB_LIB.T6G(SCH_1):PAGE297_I37@PURE_QUANTA.Q_CAP(CHIPS)':
 C_PATH='@t6g_mb_lib.t6g(sch_1):page297_i37@pure_quanta.q_cap(chips)';

PART_NAME
 PC218 'Q_CAP_0402-1000PF,50V,5%,EMPTY,TMP_QCH21006JB10':;

SECTION_NUMBER 1
 '@T6G_MB_LIB.T6G(SCH_1):PAGE297_I69@PURE_QUANTA.Q_CAP(CHIPS)':
 C_PATH='@t6g_mb_lib.t6g(sch_1):page297_i69@pure_quanta.q_cap(chips)';

PART_NAME
 PC217 'Q_CAP_0402-1000PF,50V,5%,X7R,TMP_QCH21006JB10':;

SECTION_NUMBER 1
 '@T6G_MB_LIB.T6G(SCH_1):PAGE297_I65@PURE_QUANTA.Q_CAP(CHIPS)':
 C_PATH='@t6g_mb_lib.t6g(sch_1):page297_i65@pure_quanta.q_cap(chips)';

PART_NAME
 PC216 'Q_CAP_0402-3300PF,50V,10%,X7R,TMP_QCH2336K1B12':;

SECTION_NUMBER 1
 '@T6G_MB_LIB.T6G(SCH_1):PAGE297_I46@PURE_QUANTA.Q_CAP(CHIPS)':
 C_PATH='@t6g_mb_lib.t6g(sch_1):page297_i46@pure_quanta.q_cap(chips)',
 CDSVAR_REPCELL_MPS='pure_quanta|Q_cap',
 VAR_0_MPS='VALUE|3300PF|VOLTAGE|50V|TOLERANCE|10%|PACK_TYPE|C0402|MATERIAL|EMPT~
Y|PART_NUMBER|CH2336K1B06|STANDARD||LIFECYCLE||ASS_PART||PART_NUMBER|CH2336K1B06~
|JEDEC_TYPE|C0402|ALT_SYMBOLS|(C0402-0201)|VALUE|NA|RATED_VOLTAGE|50V|TOL|10%|CL~
ASS|IO|DESCRIPTION|CAP CHIP 3300P 50V(+-10%,X7R,0402)MUR|COMPONENT_TYPE|CHIP0402~
|LEAD_LENGTH||LPID||DATE|20150617|VARIANT_DEVICE_TYPE|Q_CAP-3300PF,50V,10%,C0402~
,EMP';

PART_NAME
 PC215 'Q_CAP_0402-3300PF,50V,10%,X7R,TMP_QCH2336K1B12':;

SECTION_NUMBER 1
 '@T6G_MB_LIB.T6G(SCH_1):PAGE297_I47@PURE_QUANTA.Q_CAP(CHIPS)':
 C_PATH='@t6g_mb_lib.t6g(sch_1):page297_i47@pure_quanta.q_cap(chips)',
 CDSVAR_REPCELL_MPS='pure_quanta|Q_cap',
 VAR_0_MPS='VALUE|3300PF|VOLTAGE|50V|TOLERANCE|10%|PACK_TYPE|C0402|MATERIAL|EMPT~
Y|PART_NUMBER|CH2336K1B06|STANDARD||LIFECYCLE||ASS_PART||PART_NUMBER|CH2336K1B06~
|JEDEC_TYPE|C0402|ALT_SYMBOLS|(C0402-0201)|VALUE|NA|RATED_VOLTAGE|50V|TOL|10%|CL~
ASS|IO|DESCRIPTION|CAP CHIP 3300P 50V(+-10%,X7R,0402)MUR|COMPONENT_TYPE|CHIP0402~
|LEAD_LENGTH||LPID||DATE|20150617|VARIANT_DEVICE_TYPE|Q_CAP-3300PF,50V,10%,C0402~
,EMP';

PART_NAME
 PC214 'Q_CAP_0402-0.1UF,25V,10%,EMPTY,CH4104K1B00':;

SECTION_NUMBER 1
 '@T6G_MB_LIB.T6G(SCH_1):PAGE297_I35@PURE_QUANTA.Q_CAP(CHIPS)':
 C_PATH='@t6g_mb_lib.t6g(sch_1):page297_i35@pure_quanta.q_cap(chips)',
 VAR_0_MPS='';

PART_NAME
 PU44_P0_2 'RAA2213404GNPHB0-RAA2213404GNP#HB0,SMLF,IC,AL221340000':;

SECTION_NUMBER 1
 '@T6G_MB_LIB.T6G(SCH_1):PAGE298_I164@PURE_QUANTA.RAA2213404GNPHB0(CHIPS)':
 C_PATH='@s6q_mb_lib.s6q(sch_1):page298_i164@pure_quanta.raa2213404gnphb0(chips)~
',
 CDSVAR_REPCELL_MPS='pure_quanta|mp86950glvtz',
 VAR_0_MPS='VAR_REPLACED|RAA2213404GNPHB0|VAR_PARTNAME|MP86950GLVTZ|VALUE|MP8695~
0GLVT-Z|PART_TYPE|SMLF|MATERIAL|IC|PART_NUMBER|AL086950A00|STANDARD||LIFECYCLE||~
PART_NUMBER|AL086950A00|JEDEC_TYPE|LGA17_5X4|DESCRIPTION|IC OTHER(27P)MP86950GLV~
T-Z(LGA)|MANUFTR|MPS|MANUF_PN|MP86950GLVT-Z|RD_CMPLS_LVL|EP(V1)|CMPLS_LVL||FROM_~
PJ|S69-CARSON|CLASS|IC|DIP_SMD||DATA|MPS_MP86950GLVT-Z.pdf|EE_CHECK_LIST||FP_ECN~
||PSL||CREATOR||STATUS||MSD|Level-3|ESD_CDM|NA|ESD_HBM|NA|ESD_MM|NA|PIN_LENGTH_S~
HORT_PIN|0 MILS|PIN_LENGTH_LONG_PIN|0 MILS|CREATEDAY|20180807|VARIANT_DEVICE_TYP~
E|MP86950GLVTZ-MP86950GLVT-Z,SML';

PART_NAME
 PU43_P0_1 'RAA2213404GNPHB0-RAA2213404GNP#HB0,SMLF,IC,AL221340000':;

SECTION_NUMBER 1
 '@T6G_MB_LIB.T6G(SCH_1):PAGE298_I166@PURE_QUANTA.RAA2213404GNPHB0(CHIPS)':
 C_PATH='@s6q_mb_lib.s6q(sch_1):page298_i166@pure_quanta.raa2213404gnphb0(chips)~
',
 CDSVAR_REPCELL_MPS='pure_quanta|mp86950glvtz',
 VAR_0_MPS='VAR_REPLACED|RAA2213404GNPHB0|VAR_PARTNAME|MP86950GLVTZ|PART_TYPE|SM~
LF|MATERIAL|IC|VALUE|MP86950GLVT-Z|PART_NUMBER|AL086950A00|PIN_LENGTH_LONG_PIN|0~
 MILS|MSD|Level-3|DESCRIPTION|IC OTHER(27P)MP86950GLVT-Z(LGA)|EE_CHECK_LIST||CLA~
SS|IC|MANUFTR|MPS|ESD_MM|NA|ESD_CDM|NA|FROM_PJ|S69-CARSON|DIP_SMD||CREATEDAY|201~
80807|STANDARD||PIN_LENGTH_SHORT_PIN|0 MILS|ESD_HBM|NA|LIFECYCLE||STATUS||PSL||R~
D_CMPLS_LVL|EP(V1)|FP_ECN||MANUF_PN|MP86950GLVT-Z|CMPLS_LVL||JEDEC_TYPE|LGA17_5X~
4|DATA|MPS_MP86950GLVT-Z.pdf|PART_NUMBER|AL086950A00|CREATOR||VARIANT_DEVICE_TYP~
E|MP86950GLVTZ';

PART_NAME
 PR1777 'Q_RES_0402LF-0,5%,1/16W,CHIP,CS00002JB38':;

SECTION_NUMBER 1
 '@T6G_MB_LIB.T6G(SCH_1):PAGE298_I180@PURE_QUANTA.Q_RES(CHIPS)':
 C_PATH='@t6g_mb_lib.t6g(sch_1):page298_i180@pure_quanta.q_res(chips)',
 CDSVAR_REPCELL_MPS='pure_quanta|Q_res',
 VAR_0_MPS='VALUE|0|TOLERANCE|5%|WATTAGE|1/16W|PACK_TYPE|0402LF|MATERIAL|EMPTY|P~
ART_NUMBER|CS00002JB38|STANDARD|End of Design|LIFECYCLE|Comp-Approve|PART_NUMBER~
|CS00002JB38|JEDEC_TYPE|R0402|ALT_SYMBOLS|(R0402-0201)|VALUE|0|TOL|5%|WATTAGE|1/~
16W|CLASS|IO|DESCRIPTION|RESISTOR CHIP 0 1/16W +-5%(0402)|COMPONENT_TYPE|CHIP040~
2|LEAD_LENGTH||DFM_EXCLUSION||DAY|20100618|VARIANT_DEVICE_TYPE|Q_RES-0,5%,1/16W,~
0402LF,EMPTY,';

PART_NAME
 PR1776 'Q_RES_0402LF-0,5%,1/16W,CHIP,CS00002JB38':;

SECTION_NUMBER 1
 '@T6G_MB_LIB.T6G(SCH_1):PAGE298_I188@PURE_QUANTA.Q_RES(CHIPS)':
 C_PATH='@t6g_mb_lib.t6g(sch_1):page298_i188@pure_quanta.q_res(chips)',
 CDSVAR_REPCELL_MPS='pure_quanta|Q_res',
 VAR_0_MPS='VALUE|0|TOLERANCE|5%|WATTAGE|1/16W|PACK_TYPE|0402LF|MATERIAL|EMPTY|P~
ART_NUMBER|CS00002JB38|STANDARD|End of Design|LIFECYCLE|Comp-Approve|PART_NUMBER~
|CS00002JB38|JEDEC_TYPE|R0402|ALT_SYMBOLS|(R0402-0201)|VALUE|0|TOL|5%|WATTAGE|1/~
16W|CLASS|IO|DESCRIPTION|RESISTOR CHIP 0 1/16W +-5%(0402)|COMPONENT_TYPE|CHIP040~
2|LEAD_LENGTH||DFM_EXCLUSION||DAY|20100618|VARIANT_DEVICE_TYPE|Q_RES-0,5%,1/16W,~
0402LF,EMPTY,';

PART_NAME
 PR1775 'Q_RES_0402LF-4.7,1%,1/16W,CHIP,CS-4702FB19':;

SECTION_NUMBER 1
 '@T6G_MB_LIB.T6G(SCH_1):PAGE298_I181@PURE_QUANTA.Q_RES(CHIPS)':
 C_PATH='@t6g_mb_lib.t6g(sch_1):page298_i181@pure_quanta.q_res(chips)',
 CDSVAR_REPCELL_MPS='pure_quanta|Q_res',
 VAR_0_MPS='VALUE|0|TOLERANCE|5%|WATTAGE|1/16W|PACK_TYPE|0402LF|MATERIAL|CHIP|PA~
RT_NUMBER|CS00002JB38|STANDARD|End of Design|LIFECYCLE|Comp-Approve|PART_NUMBER|~
CS00002JB38|JEDEC_TYPE|R0402|ALT_SYMBOLS|(R0402-0201)|VALUE|0|TOL|5%|WATTAGE|1/1~
6W|CLASS|DISCRETE|DESCRIPTION|RESISTOR CHIP 0 1/16W +-5%(0402)|COMPONENT_TYPE|CH~
IP0402|LEAD_LENGTH||DFM_EXCLUSION||DAY|20100618|VARIANT_DEVICE_TYPE|Q_RES-0,5%,1~
/16W,0402LF,CHIP,C';

PART_NAME
 PR1774 'Q_RES_0402LF-4.7,1%,1/16W,CHIP,CS-4702FB19':;

SECTION_NUMBER 1
 '@T6G_MB_LIB.T6G(SCH_1):PAGE298_I203@PURE_QUANTA.Q_RES(CHIPS)':
 C_PATH='@t6g_mb_lib.t6g(sch_1):page298_i203@pure_quanta.q_res(chips)',
 CDSVAR_REPCELL_MPS='pure_quanta|Q_res',
 VAR_0_MPS='VALUE|0|TOLERANCE|5%|WATTAGE|1/16W|PACK_TYPE|0402LF|MATERIAL|CHIP|PA~
RT_NUMBER|CS00002JB38|STANDARD|End of Design|LIFECYCLE|Comp-Approve|PART_NUMBER|~
CS00002JB38|JEDEC_TYPE|R0402|ALT_SYMBOLS|(R0402-0201)|VALUE|0|TOL|5%|WATTAGE|1/1~
6W|CLASS|DISCRETE|DESCRIPTION|RESISTOR CHIP 0 1/16W +-5%(0402)|COMPONENT_TYPE|CH~
IP0402|LEAD_LENGTH||DFM_EXCLUSION||DAY|20100618|VARIANT_DEVICE_TYPE|Q_RES-0,5%,1~
/16W,0402LF,CHIP,C';

PART_NAME
 PR1708 'Q_RES_0402LF-8.87K,1%,1/16W,EMPTY,CS28872FB01':;

SECTION_NUMBER 1
 '@T6G_MB_LIB.T6G(SCH_1):PAGE298_I156@PURE_QUANTA.Q_RES(CHIPS)':
 C_PATH='@t6g_mb_lib.t6g(sch_1):page298_i156@pure_quanta.q_res(chips)';

PART_NAME
 PR1707 'Q_RES_0402LF-8.87K,1%,1/16W,EMPTY,CS28872FB01':;

SECTION_NUMBER 1
 '@T6G_MB_LIB.T6G(SCH_1):PAGE298_I146@PURE_QUANTA.Q_RES(CHIPS)':
 C_PATH='@t6g_mb_lib.t6g(sch_1):page298_i146@pure_quanta.q_res(chips)';

PART_NAME
 PR441 'Q_RES_0402LF-0,5%,1/16W,EMPTY,CS00002JB38':;

SECTION_NUMBER 1
 '@T6G_MB_LIB.T6G(SCH_1):PAGE298_I176@PURE_QUANTA.Q_RES(CHIPS)':
 C_PATH='@t6g_mb_lib.t6g(sch_1):page298_i176@pure_quanta.q_res(chips)',
 CDSVAR_REPCELL_MPS='pure_quanta|Q_res',
 VAR_0_MPS='VALUE|0|TOLERANCE|5%|WATTAGE|1/16W|PACK_TYPE|0402LF|MATERIAL|CHIP|PA~
RT_NUMBER|CS00002JB38|STANDARD|End of Design|LIFECYCLE|Comp-Approve|PART_NUMBER|~
CS00002JB38|JEDEC_TYPE|R0402|ALT_SYMBOLS|(R0402-0201)|VALUE|0|TOL|5%|WATTAGE|1/1~
6W|CLASS|DISCRETE|DESCRIPTION|RESISTOR CHIP 0 1/16W +-5%(0402)|COMPONENT_TYPE|CH~
IP0402|LEAD_LENGTH||DFM_EXCLUSION||DAY|20100618|VARIANT_DEVICE_TYPE|Q_RES-0,5%,1~
/16W,0402LF,CHIP,C';

PART_NAME
 PR437 'Q_RES_0402LF-0,5%,1/16W,CHIP,CS00002JB38':;

SECTION_NUMBER 1
 '@T6G_MB_LIB.T6G(SCH_1):PAGE298_I170@PURE_QUANTA.Q_RES(CHIPS)':
 C_PATH='@t6g_mb_lib.t6g(sch_1):page298_i170@pure_quanta.q_res(chips)',
 CDSVAR_REPCELL_MPS='pure_quanta|Q_res',
 VAR_0_MPS='VALUE|0|TOLERANCE|5%|WATTAGE|1/16W|PACK_TYPE|0402LF|MATERIAL|EMPTY|P~
ART_NUMBER|CS00002JB38|STANDARD|End of Design|LIFECYCLE|Comp-Approve|PART_NUMBER~
|CS00002JB38|JEDEC_TYPE|R0402|ALT_SYMBOLS|(R0402-0201)|VALUE|0|TOL|5%|WATTAGE|1/~
16W|CLASS|IO|DESCRIPTION|RESISTOR CHIP 0 1/16W +-5%(0402)|COMPONENT_TYPE|CHIP040~
2|LEAD_LENGTH||DFM_EXCLUSION||DAY|20100618|VARIANT_DEVICE_TYPE|Q_RES-0,5%,1/16W,~
0402LF,EMPTY,';

PART_NAME
 PR102 'Q_RES_0402LF-2.2,1%,1/16W,CHIP,CS-2202FB00':;

SECTION_NUMBER 1
 '@T6G_MB_LIB.T6G(SCH_1):PAGE298_I158@PURE_QUANTA.Q_RES(CHIPS)':
 C_PATH='@t6g_mb_lib.t6g(sch_1):page298_i158@pure_quanta.q_res(chips)';

PART_NAME
 PR101 'Q_RES_0402LF-2.2,1%,1/16W,CHIP,CS-2202FB00':;

SECTION_NUMBER 1
 '@T6G_MB_LIB.T6G(SCH_1):PAGE298_I175@PURE_QUANTA.Q_RES(CHIPS)':
 C_PATH='@t6g_mb_lib.t6g(sch_1):page298_i175@pure_quanta.q_res(chips)';

PART_NAME
 PL6 'Q_INDUCTOR_SMLF-100NH/16A,IND,CV+10G0MZ04':;

SECTION_NUMBER 1
 '@T6G_MB_LIB.T6G(SCH_1):PAGE298_I211@PURE_QUANTA.Q_INDUCTOR(CHIPS)':
 C_PATH='@t6g_mb_lib.t6g(sch_1):page298_i211@pure_quanta.q_inductor(chips)';

PART_NAME
 PL5 'Q_INDUCTOR_SMLF-120NH/94A,IND,CV+12^0KZ16':;

SECTION_NUMBER 1
 '@T6G_MB_LIB.T6G(SCH_1):PAGE298_I184@PURE_QUANTA.Q_INDUCTOR(CHIPS)':
 C_PATH='@t6g_mb_lib.t6g(sch_1):page298_i184@pure_quanta.q_inductor(chips)';

PART_NAME
 PL4 'Q_INDUCTOR_SMLF-120NH/94A,IND,CV+12^0KZ16':;

SECTION_NUMBER 1
 '@T6G_MB_LIB.T6G(SCH_1):PAGE298_I207@PURE_QUANTA.Q_INDUCTOR(CHIPS)':
 C_PATH='@t6g_mb_lib.t6g(sch_1):page298_i207@pure_quanta.q_inductor(chips)';

PART_NAME
 PC1579 'Q_CAPP_THLF-560UF,2.5V,20%,OSCON,CC7560JMD18':;

SECTION_NUMBER 1
 '@T6G_MB_LIB.T6G(SCH_1):PAGE298_I215@PURE_QUANTA.Q_CAPP(CHIPS)':
 C_PATH='@t6g_mb_lib.t6g(sch_1):page298_i215@pure_quanta.q_capp(chips)';

PART_NAME
 PC1576 'Q_CAPP_THLF-560UF,2.5V,20%,OSCON,CC7560JMD18':;

SECTION_NUMBER 1
 '@T6G_MB_LIB.T6G(SCH_1):PAGE298_I200@PURE_QUANTA.Q_CAPP(CHIPS)':
 C_PATH='@t6g_mb_lib.t6g(sch_1):page298_i200@pure_quanta.q_capp(chips)';

PART_NAME
 PC1575 'Q_CAPP_SMLF-330UF,2V,35%,SPCAP,CH733RY8807':;

SECTION_NUMBER 1
 '@T6G_MB_LIB.T6G(SCH_1):PAGE298_I202@PURE_QUANTA.Q_CAPP(CHIPS)':
 C_PATH='@t6g_mb_lib.t6g(sch_1):page298_i202@pure_quanta.q_capp(chips)';

PART_NAME
 PC1574 'Q_CAPP_THLF-560UF,2.5V,20%,OSCON,CC7560JMD18':;

SECTION_NUMBER 1
 '@T6G_MB_LIB.T6G(SCH_1):PAGE298_I199@PURE_QUANTA.Q_CAPP(CHIPS)':
 C_PATH='@t6g_mb_lib.t6g(sch_1):page298_i199@pure_quanta.q_capp(chips)';

PART_NAME
 PC1573 'Q_CAPP_SMLF-330UF,2V,35%,SPCAP,CH733RY8807':;

SECTION_NUMBER 1
 '@T6G_MB_LIB.T6G(SCH_1):PAGE298_I201@PURE_QUANTA.Q_CAPP(CHIPS)':
 C_PATH='@t6g_mb_lib.t6g(sch_1):page298_i201@pure_quanta.q_capp(chips)';

PART_NAME
 PC1347 'Q_CAP_0402-0.1UF,25V,10%,X7R,CH4104K1B00':;

SECTION_NUMBER 1
 '@T6G_MB_LIB.T6G(SCH_1):PAGE298_I163@PURE_QUANTA.Q_CAP(CHIPS)':
 C_PATH='@t6g_mb_lib.t6g(sch_1):page298_i163@pure_quanta.q_cap(chips)',
 CDSVAR_REPCELL_MPS='pure_quanta|Q_cap',
 VAR_0_MPS='VALUE|0.1UF|VOLTAGE|25V|TOLERANCE|10%|PACK_TYPE|0402|MATERIAL|EMPTY|~
PART_NUMBER|CH4104K1B00|STANDARD||LIFECYCLE||ASS_PART||PART_NUMBER|CH4104K1B00|J~
EDEC_TYPE|C0402|ALT_SYMBOLS|(C0402_OCTAGONXA,C0402-0201)|VALUE|NA|RATED_VOLTAGE|~
25V|TOL|10%|CLASS|IO|DESCRIPTION|CAP CHIP 0.1U 25V(+-10%,X7R,0402)|COMPONENT_TYP~
E|CHIP0402|LEAD_LENGTH||LPID||DATE|20160113|VARIANT_DEVICE_TYPE|Q_CAP-0.1UF,25V,~
10%,0402,EMPTY';

PART_NAME
 PC1346 'Q_CAP_0402-0.1UF,25V,10%,X7R,CH4104K1B00':;

SECTION_NUMBER 1
 '@T6G_MB_LIB.T6G(SCH_1):PAGE298_I152@PURE_QUANTA.Q_CAP(CHIPS)':
 C_PATH='@t6g_mb_lib.t6g(sch_1):page298_i152@pure_quanta.q_cap(chips)',
 CDSVAR_REPCELL_MPS='pure_quanta|Q_cap',
 VAR_0_MPS='VALUE|0.1UF|VOLTAGE|25V|TOLERANCE|10%|PACK_TYPE|0402|MATERIAL|EMPTY|~
PART_NUMBER|CH4104K1B00|STANDARD||LIFECYCLE||ASS_PART||PART_NUMBER|CH4104K1B00|J~
EDEC_TYPE|C0402|ALT_SYMBOLS|(C0402_OCTAGONXA,C0402-0201)|VALUE|NA|RATED_VOLTAGE|~
25V|TOL|10%|CLASS|IO|DESCRIPTION|CAP CHIP 0.1U 25V(+-10%,X7R,0402)|COMPONENT_TYP~
E|CHIP0402|LEAD_LENGTH||LPID||DATE|20160113|VARIANT_DEVICE_TYPE|Q_CAP-0.1UF,25V,~
10%,0402,EMPTY';

PART_NAME
 PC208 'Q_CAPP_THLF-270UF,16V,20%,OSCON,CC72703MD33':;

SECTION_NUMBER 1
 '@T6G_MB_LIB.T6G(SCH_1):PAGE298_I214@PURE_QUANTA.Q_CAPP(CHIPS)':
 C_PATH='@t6g_mb_lib.t6g(sch_1):page298_i214@pure_quanta.q_capp(chips)';

PART_NAME
 PC207 'Q_CAPP_THLF-270UF,16V,20%,OSCON,CC72703MD33':;

SECTION_NUMBER 1
 '@T6G_MB_LIB.T6G(SCH_1):PAGE298_I213@PURE_QUANTA.Q_CAPP(CHIPS)':
 C_PATH='@t6g_mb_lib.t6g(sch_1):page298_i213@pure_quanta.q_capp(chips)';

PART_NAME
 PC205_P0_2 'Q_CAP_0805-22UF,4V,20%,X6S,TMP_QCH622KMEA01':;

SECTION_NUMBER 1
 '@T6G_MB_LIB.T6G(SCH_1):PAGE298_I195@PURE_QUANTA.Q_CAP(CHIPS)':
 C_PATH='@t6g_mb_lib.t6g(sch_1):page298_i195@pure_quanta.q_cap(chips)';

PART_NAME
 PC204_P0_1 'Q_CAP_0805-22UF,4V,20%,X6S,TMP_QCH622KMEA01':;

SECTION_NUMBER 1
 '@T6G_MB_LIB.T6G(SCH_1):PAGE298_I197@PURE_QUANTA.Q_CAP(CHIPS)':
 C_PATH='@t6g_mb_lib.t6g(sch_1):page298_i197@pure_quanta.q_cap(chips)';

PART_NAME
 PC203_P0_2 'Q_CAP_0805-22UF,4V,20%,X6S,TMP_QCH622KMEA01':;

SECTION_NUMBER 1
 '@T6G_MB_LIB.T6G(SCH_1):PAGE298_I194@PURE_QUANTA.Q_CAP(CHIPS)':
 C_PATH='@t6g_mb_lib.t6g(sch_1):page298_i194@pure_quanta.q_cap(chips)';

PART_NAME
 PC202_P0_1 'Q_CAP_0805-22UF,4V,20%,X6S,TMP_QCH622KMEA01':;

SECTION_NUMBER 1
 '@T6G_MB_LIB.T6G(SCH_1):PAGE298_I192@PURE_QUANTA.Q_CAP(CHIPS)':
 C_PATH='@t6g_mb_lib.t6g(sch_1):page298_i192@pure_quanta.q_cap(chips)';

PART_NAME
 PC199_P0_1 'Q_CAP_C0402-100NF,50V,10%,X7R,CH4106K1B01':;

SECTION_NUMBER 1
 '@T6G_MB_LIB.T6G(SCH_1):PAGE298_I191@PURE_QUANTA.Q_CAP(CHIPS)':
 C_PATH='@t6g_mb_lib.t6g(sch_1):page298_i191@pure_quanta.q_cap(chips)';

PART_NAME
 PC198_P0_2 'Q_CAP_C0805-22UF,16V,20%,X6S,CH6223MEA00':;

SECTION_NUMBER 1
 '@T6G_MB_LIB.T6G(SCH_1):PAGE298_I187@PURE_QUANTA.Q_CAP(CHIPS)':
 C_PATH='@t6g_mb_lib.t6g(sch_1):page298_i187@pure_quanta.q_cap(chips)';

PART_NAME
 PC197_P0_1 'Q_CAP_C0805-22UF,16V,20%,X6S,CH6223MEA00':;

SECTION_NUMBER 1
 '@T6G_MB_LIB.T6G(SCH_1):PAGE298_I206@PURE_QUANTA.Q_CAP(CHIPS)':
 C_PATH='@t6g_mb_lib.t6g(sch_1):page298_i206@pure_quanta.q_cap(chips)';

PART_NAME
 PC196_P0_2 'Q_CAP_C0805-22UF,16V,20%,X6S,CH6223MEA00':;

SECTION_NUMBER 1
 '@T6G_MB_LIB.T6G(SCH_1):PAGE298_I186@PURE_QUANTA.Q_CAP(CHIPS)':
 C_PATH='@t6g_mb_lib.t6g(sch_1):page298_i186@pure_quanta.q_cap(chips)';

PART_NAME
 PC195_P0_1 'Q_CAP_C0805-22UF,16V,20%,X6S,CH6223MEA00':;

SECTION_NUMBER 1
 '@T6G_MB_LIB.T6G(SCH_1):PAGE298_I204@PURE_QUANTA.Q_CAP(CHIPS)':
 C_PATH='@t6g_mb_lib.t6g(sch_1):page298_i204@pure_quanta.q_cap(chips)';

PART_NAME
 PC194 'Q_CAP_C0402-100NF,50V,10%,X7R,CH4106K1B01':;

SECTION_NUMBER 1
 '@T6G_MB_LIB.T6G(SCH_1):PAGE298_I183@PURE_QUANTA.Q_CAP(CHIPS)':
 C_PATH='@t6g_mb_lib.t6g(sch_1):page298_i183@pure_quanta.q_cap(chips)';

PART_NAME
 PC193 'Q_CAP_C0402-100NF,50V,10%,X7R,CH4106K1B01':;

SECTION_NUMBER 1
 '@T6G_MB_LIB.T6G(SCH_1):PAGE298_I205@PURE_QUANTA.Q_CAP(CHIPS)':
 C_PATH='@t6g_mb_lib.t6g(sch_1):page298_i205@pure_quanta.q_cap(chips)';

PART_NAME
 PC192_P0_2 'Q_CAP_C0402-1UF,16V,10%,X6S,CH5103KEB01':;

SECTION_NUMBER 1
 '@T6G_MB_LIB.T6G(SCH_1):PAGE298_I168@PURE_QUANTA.Q_CAP(CHIPS)':
 C_PATH='@t6g_mb_lib.t6g(sch_1):page298_i168@pure_quanta.q_cap(chips)';

PART_NAME
 PC191_P0_1 'Q_CAP_C0402-1UF,16V,10%,X6S,CH5103KEB01':;

SECTION_NUMBER 1
 '@T6G_MB_LIB.T6G(SCH_1):PAGE298_I179@PURE_QUANTA.Q_CAP(CHIPS)':
 C_PATH='@t6g_mb_lib.t6g(sch_1):page298_i179@pure_quanta.q_cap(chips)';

PART_NAME
 PC190_P0_2 'Q_CAP_0402-3300PF,50V,10%,X7R,TMP_QCH2336K1B12':;

SECTION_NUMBER 1
 '@T6G_MB_LIB.T6G(SCH_1):PAGE298_I167@PURE_QUANTA.Q_CAP(CHIPS)':
 C_PATH='@t6g_mb_lib.t6g(sch_1):page298_i167@pure_quanta.q_cap(chips)';

PART_NAME
 PC189_P0_1 'Q_CAP_0402-3300PF,50V,10%,X7R,TMP_QCH2336K1B12':;

SECTION_NUMBER 1
 '@T6G_MB_LIB.T6G(SCH_1):PAGE298_I178@PURE_QUANTA.Q_CAP(CHIPS)':
 C_PATH='@t6g_mb_lib.t6g(sch_1):page298_i178@pure_quanta.q_cap(chips)';

PART_NAME
 PC188 'Q_CAP_C0402-2.2UF,10V,10%,X6S,CH5222KEB01':;

SECTION_NUMBER 1
 '@T6G_MB_LIB.T6G(SCH_1):PAGE298_I153@PURE_QUANTA.Q_CAP(CHIPS)':
 C_PATH='@t6g_mb_lib.t6g(sch_1):page298_i153@pure_quanta.q_cap(chips)';

PART_NAME
 PC187 'Q_CAP_C0402-2.2UF,10V,10%,X6S,CH5222KEB01':;

SECTION_NUMBER 1
 '@T6G_MB_LIB.T6G(SCH_1):PAGE298_I174@PURE_QUANTA.Q_CAP(CHIPS)':
 C_PATH='@t6g_mb_lib.t6g(sch_1):page298_i174@pure_quanta.q_cap(chips)';

PART_NAME
 PU42 'RAA2213404GNPHB0-RAA2213404GNP#HB0,SMLF,IC,AL221340000':;

SECTION_NUMBER 1
 '@T6G_MB_LIB.T6G(SCH_1):PAGE299_I11@PURE_QUANTA.RAA2213404GNPHB0(CHIPS)':
 C_PATH='@t6g_mb_lib.t6g(sch_1):page299_i11@pure_quanta.raa2213404gnphb0(chips)',
 CDSVAR_REPCELL_MPS='pure_quanta|mp86950glvtz',
 VAR_0_MPS='VAR_REPLACED|RAA2213404GNPHB0|VAR_PARTNAME|MP86950GLVTZ|VALUE|MP8695~
0GLVT-Z|PART_TYPE|SMLF|MATERIAL|IC|PART_NUMBER|AL086950A00|STANDARD||LIFECYCLE||~
PART_NUMBER|AL086950A00|JEDEC_TYPE|LGA17_5X4|DESCRIPTION|IC OTHER(27P)MP86950GLV~
T-Z(LGA)|MANUFTR|MPS|MANUF_PN|MP86950GLVT-Z|RD_CMPLS_LVL|EP(V1)|CMPLS_LVL||FROM_~
PJ|S69-CARSON|CLASS|IC|DIP_SMD||DATA|MPS_MP86950GLVT-Z.pdf|EE_CHECK_LIST||FP_ECN~
||PSL||CREATOR||STATUS||MSD|Level-3|ESD_CDM|NA|ESD_HBM|NA|ESD_MM|NA|PIN_LENGTH_S~
HORT_PIN|0 MILS|PIN_LENGTH_LONG_PIN|0 MILS|CREATEDAY|20180807|VARIANT_DEVICE_TYP~
E|MP86950GLVTZ-MP86950GLVT-Z,SML';

PART_NAME
 PR1779 'Q_RES_0402LF-0,5%,1/16W,CHIP,CS00002JB38':;

SECTION_NUMBER 1
 '@T6G_MB_LIB.T6G(SCH_1):PAGE299_I19@PURE_QUANTA.Q_RES(CHIPS)':
 C_PATH='@t6g_mb_lib.t6g(sch_1):page299_i19@pure_quanta.q_res(chips)',
 CDSVAR_REPCELL_MPS='pure_quanta|Q_res',
 VAR_0_MPS='VALUE|0|TOLERANCE|5%|WATTAGE|1/16W|PACK_TYPE|0402LF|MATERIAL|EMPTY|P~
ART_NUMBER|CS00002JB38|STANDARD|End of Design|LIFECYCLE|Comp-Approve|PART_NUMBER~
|CS00002JB38|JEDEC_TYPE|R0402|ALT_SYMBOLS|(R0402-0201)|VALUE|0|TOL|5%|WATTAGE|1/~
16W|CLASS|IO|DESCRIPTION|RESISTOR CHIP 0 1/16W +-5%(0402)|COMPONENT_TYPE|CHIP040~
2|LEAD_LENGTH||DFM_EXCLUSION||DAY|20100618|VARIANT_DEVICE_TYPE|Q_RES-0,5%,1/16W,~
0402LF,EMPTY,';

PART_NAME
 PR1778 'Q_RES_0402LF-4.7,1%,1/16W,CHIP,CS-4702FB19':;

SECTION_NUMBER 1
 '@T6G_MB_LIB.T6G(SCH_1):PAGE299_I30@PURE_QUANTA.Q_RES(CHIPS)':
 C_PATH='@t6g_mb_lib.t6g(sch_1):page299_i30@pure_quanta.q_res(chips)',
 CDSVAR_REPCELL_MPS='pure_quanta|Q_res',
 VAR_0_MPS='VALUE|0|TOLERANCE|5%|WATTAGE|1/16W|PACK_TYPE|0402LF|MATERIAL|CHIP|PA~
RT_NUMBER|CS00002JB38|STANDARD|End of Design|LIFECYCLE|Comp-Approve|PART_NUMBER|~
CS00002JB38|JEDEC_TYPE|R0402|ALT_SYMBOLS|(R0402-0201)|VALUE|0|TOL|5%|WATTAGE|1/1~
6W|CLASS|DISCRETE|DESCRIPTION|RESISTOR CHIP 0 1/16W +-5%(0402)|COMPONENT_TYPE|CH~
IP0402|LEAD_LENGTH||DFM_EXCLUSION||DAY|20100618|VARIANT_DEVICE_TYPE|Q_RES-0,5%,1~
/16W,0402LF,CHIP,C';

PART_NAME
 PR1709 'Q_RES_0402LF-8.87K,1%,1/16W,EMPTY,CS28872FB01':;

SECTION_NUMBER 1
 '@T6G_MB_LIB.T6G(SCH_1):PAGE299_I2@PURE_QUANTA.Q_RES(CHIPS)':
 C_PATH='@t6g_mb_lib.t6g(sch_1):page299_i2@pure_quanta.q_res(chips)';

PART_NAME
 PR443 'Q_RES_0402LF-0,5%,1/16W,EMPTY,CS00002JB38':;

SECTION_NUMBER 1
 '@T6G_MB_LIB.T6G(SCH_1):PAGE299_I15@PURE_QUANTA.Q_RES(CHIPS)':
 C_PATH='@t6g_mb_lib.t6g(sch_1):page299_i15@pure_quanta.q_res(chips)',
 CDSVAR_REPCELL_MPS='pure_quanta|Q_res',
 VAR_0_MPS='VALUE|0|TOLERANCE|5%|WATTAGE|1/16W|PACK_TYPE|0402LF|MATERIAL|CHIP|PA~
RT_NUMBER|CS00002JB38|STANDARD|End of Design|LIFECYCLE|Comp-Approve|PART_NUMBER|~
CS00002JB38|JEDEC_TYPE|R0402|ALT_SYMBOLS|(R0402-0201)|VALUE|0|TOL|5%|WATTAGE|1/1~
6W|CLASS|DISCRETE|DESCRIPTION|RESISTOR CHIP 0 1/16W +-5%(0402)|COMPONENT_TYPE|CH~
IP0402|LEAD_LENGTH||DFM_EXCLUSION||DAY|20100618|VARIANT_DEVICE_TYPE|Q_RES-0,5%,1~
/16W,0402LF,CHIP,C';

PART_NAME
 PR442 'Q_RES_0402LF-0,5%,1/16W,CHIP,CS00002JB38':;

SECTION_NUMBER 1
 '@T6G_MB_LIB.T6G(SCH_1):PAGE299_I13@PURE_QUANTA.Q_RES(CHIPS)':
 C_PATH='@t6g_mb_lib.t6g(sch_1):page299_i13@pure_quanta.q_res(chips)',
 CDSVAR_REPCELL_MPS='pure_quanta|Q_res',
 VAR_0_MPS='VALUE|0|TOLERANCE|5%|WATTAGE|1/16W|PACK_TYPE|0402LF|MATERIAL|EMPTY|P~
ART_NUMBER|CS00002JB38|STANDARD|End of Design|LIFECYCLE|Comp-Approve|PART_NUMBER~
|CS00002JB38|JEDEC_TYPE|R0402|ALT_SYMBOLS|(R0402-0201)|VALUE|0|TOL|5%|WATTAGE|1/~
16W|CLASS|IO|DESCRIPTION|RESISTOR CHIP 0 1/16W +-5%(0402)|COMPONENT_TYPE|CHIP040~
2|LEAD_LENGTH||DFM_EXCLUSION||DAY|20100618|VARIANT_DEVICE_TYPE|Q_RES-0,5%,1/16W,~
0402LF,EMPTY,';

PART_NAME
 PR97 'Q_RES_0402LF-2.2,1%,1/16W,CHIP,CS-2202FB00':;

SECTION_NUMBER 1
 '@T6G_MB_LIB.T6G(SCH_1):PAGE299_I14@PURE_QUANTA.Q_RES(CHIPS)':
 C_PATH='@t6g_mb_lib.t6g(sch_1):page299_i14@pure_quanta.q_res(chips)';

PART_NAME
 PL3 'Q_INDUCTOR_SMLF-300NH/33A,IND,CV+30Y0KZ05':;

SECTION_NUMBER 1
 '@T6G_MB_LIB.T6G(SCH_1):PAGE299_I23@PURE_QUANTA.Q_INDUCTOR(CHIPS)':
 C_PATH='@t6g_mb_lib.t6g(sch_1):page299_i23@pure_quanta.q_inductor(chips)';

PART_NAME
 PC2180 'Q_CAPP_THLF-560UF,2.5V,20%,OSCON,CC7560JMD18':;

SECTION_NUMBER 1
 '@T6G_MB_LIB.T6G(SCH_1):PAGE299_I27@PURE_QUANTA.Q_CAPP(CHIPS)':
 C_PATH='@t6g_mb_lib.t6g(sch_1):page299_i27@pure_quanta.q_capp(chips)';

PART_NAME
 PC1900 'Q_CAPP_SMLF-470UF,2.5V,20%,POSCAP,CH747LM8816':;

SECTION_NUMBER 1
 '@T6G_MB_LIB.T6G(SCH_1):PAGE299_I28@PURE_QUANTA.Q_CAPP(CHIPS)':
 C_PATH='@t6g_mb_lib.t6g(sch_1):page299_i28@pure_quanta.q_capp(chips)';

PART_NAME
 PC1348 'Q_CAP_0402-0.1UF,25V,10%,X7R,CH4104K1B00':;

SECTION_NUMBER 1
 '@T6G_MB_LIB.T6G(SCH_1):PAGE299_I7@PURE_QUANTA.Q_CAP(CHIPS)':
 C_PATH='@t6g_mb_lib.t6g(sch_1):page299_i7@pure_quanta.q_cap(chips)',
 CDSVAR_REPCELL_MPS='pure_quanta|Q_cap',
 VAR_0_MPS='VALUE|0.1UF|VOLTAGE|25V|TOLERANCE|10%|PACK_TYPE|0402|MATERIAL|EMPTY|~
PART_NUMBER|CH4104K1B00|STANDARD||LIFECYCLE||ASS_PART||PART_NUMBER|CH4104K1B00|J~
EDEC_TYPE|C0402|ALT_SYMBOLS|(C0402_OCTAGONXA,C0402-0201)|VALUE|NA|RATED_VOLTAGE|~
25V|TOL|10%|CLASS|IO|DESCRIPTION|CAP CHIP 0.1U 25V(+-10%,X7R,0402)|COMPONENT_TYP~
E|CHIP0402|LEAD_LENGTH||LPID||DATE|20160113|VARIANT_DEVICE_TYPE|Q_CAP-0.1UF,25V,~
10%,0402,EMPTY';

PART_NAME
 PC186 'Q_CAP_0805-22UF,4V,20%,X6S,TMP_QCH622KMEA01':;

SECTION_NUMBER 1
 '@T6G_MB_LIB.T6G(SCH_1):PAGE299_I25@PURE_QUANTA.Q_CAP(CHIPS)':
 C_PATH='@t6g_mb_lib.t6g(sch_1):page299_i25@pure_quanta.q_cap(chips)';

PART_NAME
 PC184 'Q_CAP_0805-22UF,4V,20%,X6S,TMP_QCH622KMEA01':;

SECTION_NUMBER 1
 '@T6G_MB_LIB.T6G(SCH_1):PAGE299_I24@PURE_QUANTA.Q_CAP(CHIPS)':
 C_PATH='@t6g_mb_lib.t6g(sch_1):page299_i24@pure_quanta.q_cap(chips)';

PART_NAME
 PC181 'Q_CAP_C0402-100NF,50V,10%,X7R,CH4106K1B01':;

SECTION_NUMBER 1
 '@T6G_MB_LIB.T6G(SCH_1):PAGE299_I22@PURE_QUANTA.Q_CAP(CHIPS)':
 C_PATH='@t6g_mb_lib.t6g(sch_1):page299_i22@pure_quanta.q_cap(chips)';

PART_NAME
 PC180 'Q_CAP_C0805-22UF,16V,20%,X6S,CH6223MEA00':;

SECTION_NUMBER 1
 '@T6G_MB_LIB.T6G(SCH_1):PAGE299_I32@PURE_QUANTA.Q_CAP(CHIPS)':
 C_PATH='@t6g_mb_lib.t6g(sch_1):page299_i32@pure_quanta.q_cap(chips)';

PART_NAME
 PC179 'Q_CAP_C0805-22UF,16V,20%,X6S,CH6223MEA00':;

SECTION_NUMBER 1
 '@T6G_MB_LIB.T6G(SCH_1):PAGE299_I35@PURE_QUANTA.Q_CAP(CHIPS)':
 C_PATH='@t6g_mb_lib.t6g(sch_1):page299_i35@pure_quanta.q_cap(chips)';

PART_NAME
 PC178 'Q_CAP_C0402-100NF,50V,10%,X7R,CH4106K1B01':;

SECTION_NUMBER 1
 '@T6G_MB_LIB.T6G(SCH_1):PAGE299_I21@PURE_QUANTA.Q_CAP(CHIPS)':
 C_PATH='@t6g_mb_lib.t6g(sch_1):page299_i21@pure_quanta.q_cap(chips)';

PART_NAME
 PC177 'Q_CAP_C0402-1UF,16V,10%,X6S,CH5103KEB01':;

SECTION_NUMBER 1
 '@T6G_MB_LIB.T6G(SCH_1):PAGE299_I31@PURE_QUANTA.Q_CAP(CHIPS)':
 C_PATH='@t6g_mb_lib.t6g(sch_1):page299_i31@pure_quanta.q_cap(chips)';

PART_NAME
 PC176 'Q_CAP_0402-3300PF,50V,10%,X7R,TMP_QCH2336K1B12':;

SECTION_NUMBER 1
 '@T6G_MB_LIB.T6G(SCH_1):PAGE299_I18@PURE_QUANTA.Q_CAP(CHIPS)':
 C_PATH='@t6g_mb_lib.t6g(sch_1):page299_i18@pure_quanta.q_cap(chips)';

PART_NAME
 PC175 'Q_CAP_C0402-2.2UF,10V,10%,X6S,CH5222KEB01':;

SECTION_NUMBER 1
 '@T6G_MB_LIB.T6G(SCH_1):PAGE299_I10@PURE_QUANTA.Q_CAP(CHIPS)':
 C_PATH='@t6g_mb_lib.t6g(sch_1):page299_i10@pure_quanta.q_cap(chips)';

PART_NAME
 PU31_P1_1 'ISL99390FRZTR5935-ISL99390FRZ-TR5935,SMLF,IC,AL099390004':;

SECTION_NUMBER 1
 '@T6G_MB_LIB.T6G(SCH_1):PAGE308_I20@PURE_QUANTA.ISL99390FRZTR5935(CHIPS)':
 C_PATH='@s6q_mb_lib.s6q(sch_1):page308_i20@pure_quanta.isl99390frztr5935(chips)~
';

PART_NAME
 PU30_P1_2 'ISL99390FRZTR5935-ISL99390FRZ-TR5935,SMLF,IC,AL099390004':;

SECTION_NUMBER 1
 '@T6G_MB_LIB.T6G(SCH_1):PAGE308_I18@PURE_QUANTA.ISL99390FRZTR5935(CHIPS)':
 C_PATH='@s6q_mb_lib.s6q(sch_1):page308_i18@pure_quanta.isl99390frztr5935(chips)~
';

PART_NAME
 PR1767 'Q_RES_0402LF-3.3,1%,1/16W,CHIP,CS-3302FB00':;

SECTION_NUMBER 1
 '@T6G_MB_LIB.T6G(SCH_1):PAGE308_I37@PURE_QUANTA.Q_RES(CHIPS)':
 C_PATH='@t6g_mb_lib.t6g(sch_1):page308_i37@pure_quanta.q_res(chips)',
 CDSVAR_REPCELL_MPS='pure_quanta|Q_res',
 VAR_0_MPS='VALUE|0|TOLERANCE|5%|WATTAGE|1/16W|PACK_TYPE|0402LF|MATERIAL|CHIP|PA~
RT_NUMBER|CS00002JB38|STANDARD|End of Design|LIFECYCLE|Comp-Approve|PART_NUMBER|~
CS00002JB38|JEDEC_TYPE|R0402|ALT_SYMBOLS|(R0402-0201)|VALUE|0|TOL|5%|WATTAGE|1/1~
6W|CLASS|DISCRETE|DESCRIPTION|RESISTOR CHIP 0 1/16W +-5%(0402)|COMPONENT_TYPE|CH~
IP0402|LEAD_LENGTH||DFM_EXCLUSION||DAY|20100618|VARIANT_DEVICE_TYPE|Q_RES-0,5%,1~
/16W,0402LF,CHIP,C';

PART_NAME
 PR1766 'Q_RES_0402LF-3.3,1%,1/16W,CHIP,CS-3302FB00':;

SECTION_NUMBER 1
 '@T6G_MB_LIB.T6G(SCH_1):PAGE308_I22@PURE_QUANTA.Q_RES(CHIPS)':
 C_PATH='@t6g_mb_lib.t6g(sch_1):page308_i22@pure_quanta.q_res(chips)',
 CDSVAR_REPCELL_MPS='pure_quanta|Q_res',
 VAR_0_MPS='VALUE|0|TOLERANCE|5%|WATTAGE|1/16W|PACK_TYPE|0402LF|MATERIAL|CHIP|PA~
RT_NUMBER|CS00002JB38|STANDARD|End of Design|LIFECYCLE|Comp-Approve|PART_NUMBER|~
CS00002JB38|JEDEC_TYPE|R0402|ALT_SYMBOLS|(R0402-0201)|VALUE|0|TOL|5%|WATTAGE|1/1~
6W|CLASS|DISCRETE|DESCRIPTION|RESISTOR CHIP 0 1/16W +-5%(0402)|COMPONENT_TYPE|CH~
IP0402|LEAD_LENGTH||DFM_EXCLUSION||DAY|20100618|VARIANT_DEVICE_TYPE|Q_RES-0,5%,1~
/16W,0402LF,CHIP,C';

PART_NAME
 PR640 'Q_RES_0402LF-0,5%,1/16W,EMPTY,CS00002JB38':;

SECTION_NUMBER 1
 '@T6G_MB_LIB.T6G(SCH_1):PAGE308_I34@PURE_QUANTA.Q_RES(CHIPS)':
 C_PATH='@t6g_mb_lib.t6g(sch_1):page308_i34@pure_quanta.q_res(chips)',
 CDSVAR_REPCELL_MPS='pure_quanta|Q_res',
 VAR_0_MPS='VALUE|0|TOLERANCE|5%|WATTAGE|1/16W|PACK_TYPE|0402LF|MATERIAL|CHIP|PA~
RT_NUMBER|CS00002JB38|STANDARD|End of Design|LIFECYCLE|Comp-Approve|PART_NUMBER|~
CS00002JB38|JEDEC_TYPE|R0402|ALT_SYMBOLS|(R0402-0201)|VALUE|0|TOL|5%|WATTAGE|1/1~
6W|CLASS|DISCRETE|DESCRIPTION|RESISTOR CHIP 0 1/16W +-5%(0402)|COMPONENT_TYPE|CH~
IP0402|LEAD_LENGTH||DFM_EXCLUSION||DAY|20100618|VARIANT_DEVICE_TYPE|Q_RES-0,5%,1~
/16W,0402LF,CHIP,C';

PART_NAME
 PR639 'Q_RES_0402LF-0,5%,1/16W,CHIP,CS00002JB38':;

SECTION_NUMBER 1
 '@T6G_MB_LIB.T6G(SCH_1):PAGE308_I25@PURE_QUANTA.Q_RES(CHIPS)':
 C_PATH='@t6g_mb_lib.t6g(sch_1):page308_i25@pure_quanta.q_res(chips)',
 CDSVAR_REPCELL_MPS='pure_quanta|Q_res',
 VAR_0_MPS='VALUE|0|TOLERANCE|5%|WATTAGE|1/16W|PACK_TYPE|0402LF|MATERIAL|EMPTY|P~
ART_NUMBER|CS00002JB38|STANDARD|End of Design|LIFECYCLE|Comp-Approve|PART_NUMBER~
|CS00002JB38|JEDEC_TYPE|R0402|ALT_SYMBOLS|(R0402-0201)|VALUE|0|TOL|5%|WATTAGE|1/~
16W|CLASS|IO|DESCRIPTION|RESISTOR CHIP 0 1/16W +-5%(0402)|COMPONENT_TYPE|CHIP040~
2|LEAD_LENGTH||DFM_EXCLUSION||DAY|20100618|VARIANT_DEVICE_TYPE|Q_RES-0,5%,1/16W,~
0402LF,EMPTY,';

PART_NAME
 PR330 'Q_RES_0402LF-0,5%,1/16W,CHIP,CS00002JB38':;

SECTION_NUMBER 1
 '@T6G_MB_LIB.T6G(SCH_1):PAGE308_I90@PURE_QUANTA.Q_RES(CHIPS)':
 C_PATH='@t6g_mb_lib.t6g(sch_1):page308_i90@pure_quanta.q_res(chips)';

PART_NAME
 PR329 'Q_RES_0402LF-0,5%,1/16W,CHIP,CS00002JB38':;

SECTION_NUMBER 1
 '@T6G_MB_LIB.T6G(SCH_1):PAGE308_I102@PURE_QUANTA.Q_RES(CHIPS)':
 C_PATH='@t6g_mb_lib.t6g(sch_1):page308_i102@pure_quanta.q_res(chips)';

PART_NAME
 PR328 'Q_RES_0402LF-2.2,1%,1/16W,CHIP,CS-2202FB00':;

SECTION_NUMBER 1
 '@T6G_MB_LIB.T6G(SCH_1):PAGE308_I31@PURE_QUANTA.Q_RES(CHIPS)':
 C_PATH='@t6g_mb_lib.t6g(sch_1):page308_i31@pure_quanta.q_res(chips)';

PART_NAME
 PR327 'Q_RES_0402LF-2.2,1%,1/16W,CHIP,CS-2202FB00':;

SECTION_NUMBER 1
 '@T6G_MB_LIB.T6G(SCH_1):PAGE308_I13@PURE_QUANTA.Q_RES(CHIPS)':
 C_PATH='@t6g_mb_lib.t6g(sch_1):page308_i13@pure_quanta.q_res(chips)';

PART_NAME
 PR326 'Q_RES_0402LF-8.87K,1%,1/16W,EMPTY,CS28872FB01':;

SECTION_NUMBER 1
 '@T6G_MB_LIB.T6G(SCH_1):PAGE308_I12@PURE_QUANTA.Q_RES(CHIPS)':
 C_PATH='@t6g_mb_lib.t6g(sch_1):page308_i12@pure_quanta.q_res(chips)';

PART_NAME
 PR325 'Q_RES_0402LF-8.87K,1%,1/16W,EMPTY,CS28872FB01':;

SECTION_NUMBER 1
 '@T6G_MB_LIB.T6G(SCH_1):PAGE308_I2@PURE_QUANTA.Q_RES(CHIPS)':
 C_PATH='@t6g_mb_lib.t6g(sch_1):page308_i2@pure_quanta.q_res(chips)';

PART_NAME
 PL32 'Q_INDUCTOR_SMLF-50NH/148A,IND,CVA50^0EZ01':;

SECTION_NUMBER 1
 '@T6G_MB_LIB.T6G(SCH_1):PAGE308_I71@PURE_QUANTA.Q_INDUCTOR(CHIPS)':
 C_PATH='@t6g_mb_lib.t6g(sch_1):page308_i71@pure_quanta.q_inductor(chips)';

PART_NAME
 PL31 'Q_INDUCTOR4P_14-150NH,SMLF,IND,CV+15^0TZ01':;

SECTION_NUMBER 1
 '@T6G_MB_LIB.T6G(SCH_1):PAGE308_I89@PURE_QUANTA.Q_INDUCTOR4P_14(CHIPS)':
 C_PATH='@t6g_mb_lib.t6g(sch_1):page308_i89@pure_quanta.q_inductor4p_14(chips)';

PART_NAME
 PL30 'Q_INDUCTOR4P_14-150NH,SMLF,IND,CV+15^0TZ01':;

SECTION_NUMBER 1
 '@T6G_MB_LIB.T6G(SCH_1):PAGE308_I103@PURE_QUANTA.Q_INDUCTOR4P_14(CHIPS)':
 C_PATH='@t6g_mb_lib.t6g(sch_1):page308_i103@pure_quanta.q_inductor4p_14(chips)';

PART_NAME
 PC1990 'Q_CAPP_SMLF-470UF,2.5V,20%,EMPTY,CH747LM8816':;

SECTION_NUMBER 1
 '@T6G_MB_LIB.T6G(SCH_1):PAGE308_I53@PURE_QUANTA.Q_CAPP(CHIPS)':
 C_PATH='@t6g_mb_lib.t6g(sch_1):page308_i53@pure_quanta.q_capp(chips)';

PART_NAME
 PC1339 'Q_CAP_0402-0.1UF,25V,10%,X7R,CH4104K1B00':;

SECTION_NUMBER 1
 '@T6G_MB_LIB.T6G(SCH_1):PAGE308_I30@PURE_QUANTA.Q_CAP(CHIPS)':
 C_PATH='@t6g_mb_lib.t6g(sch_1):page308_i30@pure_quanta.q_cap(chips)',
 CDSVAR_REPCELL_MPS='pure_quanta|Q_cap',
 VAR_0_MPS='VALUE|0.1UF|VOLTAGE|25V|TOLERANCE|10%|PACK_TYPE|0402|MATERIAL|EMPTY|~
PART_NUMBER|CH4104K1B00|STANDARD||LIFECYCLE||ASS_PART||PART_NUMBER|CH4104K1B00|J~
EDEC_TYPE|C0402|ALT_SYMBOLS|(C0402_OCTAGONXA,C0402-0201)|VALUE|NA|RATED_VOLTAGE|~
25V|TOL|10%|CLASS|IO|DESCRIPTION|CAP CHIP 0.1U 25V(+-10%,X7R,0402)|COMPONENT_TYP~
E|CHIP0402|LEAD_LENGTH||LPID||DATE|20160113|VARIANT_DEVICE_TYPE|Q_CAP-0.1UF,25V,~
10%,0402,EMPTY';

PART_NAME
 PC1338 'Q_CAP_0402-0.1UF,25V,10%,X7R,CH4104K1B00':;

SECTION_NUMBER 1
 '@T6G_MB_LIB.T6G(SCH_1):PAGE308_I10@PURE_QUANTA.Q_CAP(CHIPS)':
 C_PATH='@t6g_mb_lib.t6g(sch_1):page308_i10@pure_quanta.q_cap(chips)',
 CDSVAR_REPCELL_MPS='pure_quanta|Q_cap',
 VAR_0_MPS='VALUE|0.1UF|VOLTAGE|25V|TOLERANCE|10%|PACK_TYPE|0402|MATERIAL|EMPTY|~
PART_NUMBER|CH4104K1B00|STANDARD||LIFECYCLE||ASS_PART||PART_NUMBER|CH4104K1B00|J~
EDEC_TYPE|C0402|ALT_SYMBOLS|(C0402_OCTAGONXA,C0402-0201)|VALUE|NA|RATED_VOLTAGE|~
25V|TOL|10%|CLASS|IO|DESCRIPTION|CAP CHIP 0.1U 25V(+-10%,X7R,0402)|COMPONENT_TYP~
E|CHIP0402|LEAD_LENGTH||LPID||DATE|20160113|VARIANT_DEVICE_TYPE|Q_CAP-0.1UF,25V,~
10%,0402,EMPTY';

PART_NAME
 PC590 'Q_CAPP_SMLF-470UF,2.5V,20%,POSCAP,CH747LM8816':;

SECTION_NUMBER 1
 '@T6G_MB_LIB.T6G(SCH_1):PAGE308_I77@PURE_QUANTA.Q_CAPP(CHIPS)':
 C_PATH='@t6g_mb_lib.t6g(sch_1):page308_i77@pure_quanta.q_capp(chips)';

PART_NAME
 PC589 'Q_CAPP_THLF-560UF,2.5V,20%,OSCON,CC7560JMD18':;

SECTION_NUMBER 1
 '@T6G_MB_LIB.T6G(SCH_1):PAGE308_I81@PURE_QUANTA.Q_CAPP(CHIPS)':
 C_PATH='@t6g_mb_lib.t6g(sch_1):page308_i81@pure_quanta.q_capp(chips)';

PART_NAME
 PC588 'Q_CAPP_THLF-270UF,16V,20%,OSCON,CC72703MD33':;

SECTION_NUMBER 1
 '@T6G_MB_LIB.T6G(SCH_1):PAGE308_I84@PURE_QUANTA.Q_CAPP(CHIPS)':
 C_PATH='@t6g_mb_lib.t6g(sch_1):page308_i84@pure_quanta.q_capp(chips)';

PART_NAME
 PC587 'Q_CAPP_SMLF-470UF,2.5V,20%,EMPTY,CH747LM8816':;

SECTION_NUMBER 1
 '@T6G_MB_LIB.T6G(SCH_1):PAGE308_I75@PURE_QUANTA.Q_CAPP(CHIPS)':
 C_PATH='@t6g_mb_lib.t6g(sch_1):page308_i75@pure_quanta.q_capp(chips)';

PART_NAME
 PC586 'Q_CAPP_THLF-560UF,2.5V,20%,OSCON,CC7560JMD18':;

SECTION_NUMBER 1
 '@T6G_MB_LIB.T6G(SCH_1):PAGE308_I79@PURE_QUANTA.Q_CAPP(CHIPS)':
 C_PATH='@t6g_mb_lib.t6g(sch_1):page308_i79@pure_quanta.q_capp(chips)';

PART_NAME
 PC585 'Q_CAPP_THLF-270UF,16V,20%,OSCON,CC72703MD33':;

SECTION_NUMBER 1
 '@T6G_MB_LIB.T6G(SCH_1):PAGE308_I83@PURE_QUANTA.Q_CAPP(CHIPS)':
 C_PATH='@t6g_mb_lib.t6g(sch_1):page308_i83@pure_quanta.q_capp(chips)';

PART_NAME
 PC583 'Q_CAPP_THLF-560UF,2.5V,20%,OSCON,CC7560JMD18':;

SECTION_NUMBER 1
 '@T6G_MB_LIB.T6G(SCH_1):PAGE308_I56@PURE_QUANTA.Q_CAPP(CHIPS)':
 C_PATH='@t6g_mb_lib.t6g(sch_1):page308_i56@pure_quanta.q_capp(chips)';

PART_NAME
 PC582 'Q_CAPP_THLF-270UF,16V,20%,OSCON,CC72703MD33':;

SECTION_NUMBER 1
 '@T6G_MB_LIB.T6G(SCH_1):PAGE308_I74@PURE_QUANTA.Q_CAPP(CHIPS)':
 C_PATH='@t6g_mb_lib.t6g(sch_1):page308_i74@pure_quanta.q_capp(chips)';

PART_NAME
 PC580 'Q_CAPP_THLF-560UF,2.5V,20%,OSCON,CC7560JMD18':;

SECTION_NUMBER 1
 '@T6G_MB_LIB.T6G(SCH_1):PAGE308_I55@PURE_QUANTA.Q_CAPP(CHIPS)':
 C_PATH='@t6g_mb_lib.t6g(sch_1):page308_i55@pure_quanta.q_capp(chips)';

PART_NAME
 PC579 'Q_CAPP_THLF-270UF,16V,20%,OSCON,CC72703MD33':;

SECTION_NUMBER 1
 '@T6G_MB_LIB.T6G(SCH_1):PAGE308_I73@PURE_QUANTA.Q_CAPP(CHIPS)':
 C_PATH='@t6g_mb_lib.t6g(sch_1):page308_i73@pure_quanta.q_capp(chips)';

PART_NAME
 PC578_P1_1 'Q_CAP_0805-22UF,4V,20%,X6S,TMP_QCH622KMEA01':;

SECTION_NUMBER 1
 '@T6G_MB_LIB.T6G(SCH_1):PAGE308_I69@PURE_QUANTA.Q_CAP(CHIPS)':
 C_PATH='@t6g_mb_lib.t6g(sch_1):page308_i69@pure_quanta.q_cap(chips)';

PART_NAME
 PC577_P1_2 'Q_CAP_0805-22UF,4V,20%,X6S,TMP_QCH622KMEA01':;

SECTION_NUMBER 1
 '@T6G_MB_LIB.T6G(SCH_1):PAGE308_I99@PURE_QUANTA.Q_CAP(CHIPS)':
 C_PATH='@t6g_mb_lib.t6g(sch_1):page308_i99@pure_quanta.q_cap(chips)';

PART_NAME
 PC576_P1_1 'Q_CAP_0805-22UF,4V,20%,X6S,TMP_QCH622KMEA01':;

SECTION_NUMBER 1
 '@T6G_MB_LIB.T6G(SCH_1):PAGE308_I68@PURE_QUANTA.Q_CAP(CHIPS)':
 C_PATH='@t6g_mb_lib.t6g(sch_1):page308_i68@pure_quanta.q_cap(chips)';

PART_NAME
 PC575_P1_2 'Q_CAP_0805-22UF,4V,20%,X6S,TMP_QCH622KMEA01':;

SECTION_NUMBER 1
 '@T6G_MB_LIB.T6G(SCH_1):PAGE308_I100@PURE_QUANTA.Q_CAP(CHIPS)':
 C_PATH='@t6g_mb_lib.t6g(sch_1):page308_i100@pure_quanta.q_cap(chips)';

PART_NAME
 PC574_P1_1 'Q_CAP_C0402-1UF,16V,10%,X6S,CH5103KEB01':;

SECTION_NUMBER 1
 '@T6G_MB_LIB.T6G(SCH_1):PAGE308_I65@PURE_QUANTA.Q_CAP(CHIPS)':
 C_PATH='@t6g_mb_lib.t6g(sch_1):page308_i65@pure_quanta.q_cap(chips)';

PART_NAME
 PC572_P1_1 'Q_CAP_C0402-100NF,50V,10%,X7R,CH4106K1B01':;

SECTION_NUMBER 1
 '@T6G_MB_LIB.T6G(SCH_1):PAGE308_I64@PURE_QUANTA.Q_CAP(CHIPS)':
 C_PATH='@t6g_mb_lib.t6g(sch_1):page308_i64@pure_quanta.q_cap(chips)';

PART_NAME
 PC571_P1_1 'Q_CAP_C0805-22UF,16V,20%,X6S,CH6223MEA00':;

SECTION_NUMBER 1
 '@T6G_MB_LIB.T6G(SCH_1):PAGE308_I66@PURE_QUANTA.Q_CAP(CHIPS)':
 C_PATH='@t6g_mb_lib.t6g(sch_1):page308_i66@pure_quanta.q_cap(chips)';

PART_NAME
 PC570_P1_2 'Q_CAP_C0805-22UF,16V,20%,X6S,CH6223MEA00':;

SECTION_NUMBER 1
 '@T6G_MB_LIB.T6G(SCH_1):PAGE308_I46@PURE_QUANTA.Q_CAP(CHIPS)':
 C_PATH='@t6g_mb_lib.t6g(sch_1):page308_i46@pure_quanta.q_cap(chips)';

PART_NAME
 PC569_P1_1 'Q_CAP_C0805-22UF,16V,20%,X6S,CH6223MEA00':;

SECTION_NUMBER 1
 '@T6G_MB_LIB.T6G(SCH_1):PAGE308_I62@PURE_QUANTA.Q_CAP(CHIPS)':
 C_PATH='@t6g_mb_lib.t6g(sch_1):page308_i62@pure_quanta.q_cap(chips)';

PART_NAME
 PC568_P1_2 'Q_CAP_C0805-22UF,16V,20%,X6S,CH6223MEA00':;

SECTION_NUMBER 1
 '@T6G_MB_LIB.T6G(SCH_1):PAGE308_I45@PURE_QUANTA.Q_CAP(CHIPS)':
 C_PATH='@t6g_mb_lib.t6g(sch_1):page308_i45@pure_quanta.q_cap(chips)';

PART_NAME
 PC567_P1_1 'Q_CAP_C0805-22UF,16V,20%,X6S,CH6223MEA00':;

SECTION_NUMBER 1
 '@T6G_MB_LIB.T6G(SCH_1):PAGE308_I61@PURE_QUANTA.Q_CAP(CHIPS)':
 C_PATH='@t6g_mb_lib.t6g(sch_1):page308_i61@pure_quanta.q_cap(chips)';

PART_NAME
 PC566_P1_2 'Q_CAP_C0805-22UF,16V,20%,X6S,CH6223MEA00':;

SECTION_NUMBER 1
 '@T6G_MB_LIB.T6G(SCH_1):PAGE308_I44@PURE_QUANTA.Q_CAP(CHIPS)':
 C_PATH='@t6g_mb_lib.t6g(sch_1):page308_i44@pure_quanta.q_cap(chips)';

PART_NAME
 PC565 'Q_CAP_C0402-100NF,50V,10%,X7R,CH4106K1B01':;

SECTION_NUMBER 1
 '@T6G_MB_LIB.T6G(SCH_1):PAGE308_I60@PURE_QUANTA.Q_CAP(CHIPS)':
 C_PATH='@t6g_mb_lib.t6g(sch_1):page308_i60@pure_quanta.q_cap(chips)';

PART_NAME
 PC564 'Q_CAP_C0402-100NF,50V,10%,X7R,CH4106K1B01':;

SECTION_NUMBER 1
 '@T6G_MB_LIB.T6G(SCH_1):PAGE308_I42@PURE_QUANTA.Q_CAP(CHIPS)':
 C_PATH='@t6g_mb_lib.t6g(sch_1):page308_i42@pure_quanta.q_cap(chips)';

PART_NAME
 PC563_P1_1 'Q_CAP_C0402-1UF,16V,10%,X6S,CH5103KEB01':;

SECTION_NUMBER 1
 '@T6G_MB_LIB.T6G(SCH_1):PAGE308_I40@PURE_QUANTA.Q_CAP(CHIPS)':
 C_PATH='@t6g_mb_lib.t6g(sch_1):page308_i40@pure_quanta.q_cap(chips)';

PART_NAME
 PC562_P1_2 'Q_CAP_C0402-1UF,16V,10%,X6S,CH5103KEB01':;

SECTION_NUMBER 1
 '@T6G_MB_LIB.T6G(SCH_1):PAGE308_I39@PURE_QUANTA.Q_CAP(CHIPS)':
 C_PATH='@t6g_mb_lib.t6g(sch_1):page308_i39@pure_quanta.q_cap(chips)';

PART_NAME
 PC561_P1_1 'Q_CAP_0402-3300PF,50V,10%,X7R,TMP_QCH2336K1B12':;

SECTION_NUMBER 1
 '@T6G_MB_LIB.T6G(SCH_1):PAGE308_I38@PURE_QUANTA.Q_CAP(CHIPS)':
 C_PATH='@t6g_mb_lib.t6g(sch_1):page308_i38@pure_quanta.q_cap(chips)';

PART_NAME
 PC560_P1_2 'Q_CAP_0402-3300PF,50V,10%,X7R,TMP_QCH2336K1B12':;

SECTION_NUMBER 1
 '@T6G_MB_LIB.T6G(SCH_1):PAGE308_I21@PURE_QUANTA.Q_CAP(CHIPS)':
 C_PATH='@t6g_mb_lib.t6g(sch_1):page308_i21@pure_quanta.q_cap(chips)';

PART_NAME
 PC559_P1_1 'Q_CAP_C0402-2.2UF,10V,10%,X6S,CH5222KEB01':;

SECTION_NUMBER 1
 '@T6G_MB_LIB.T6G(SCH_1):PAGE308_I32@PURE_QUANTA.Q_CAP(CHIPS)':
 C_PATH='@t6g_mb_lib.t6g(sch_1):page308_i32@pure_quanta.q_cap(chips)';

PART_NAME
 PC558_P1_2 'Q_CAP_C0402-2.2UF,10V,10%,X6S,CH5222KEB01':;

SECTION_NUMBER 1
 '@T6G_MB_LIB.T6G(SCH_1):PAGE308_I16@PURE_QUANTA.Q_CAP(CHIPS)':
 C_PATH='@t6g_mb_lib.t6g(sch_1):page308_i16@pure_quanta.q_cap(chips)';

PART_NAME
 PC557 'Q_CAP_C0402-2.2UF,10V,10%,X6S,CH5222KEB01':;

SECTION_NUMBER 1
 '@T6G_MB_LIB.T6G(SCH_1):PAGE308_I29@PURE_QUANTA.Q_CAP(CHIPS)':
 C_PATH='@t6g_mb_lib.t6g(sch_1):page308_i29@pure_quanta.q_cap(chips)';

PART_NAME
 PC556 'Q_CAP_C0402-2.2UF,10V,10%,X6S,CH5222KEB01':;

SECTION_NUMBER 1
 '@T6G_MB_LIB.T6G(SCH_1):PAGE308_I8@PURE_QUANTA.Q_CAP(CHIPS)':
 C_PATH='@t6g_mb_lib.t6g(sch_1):page308_i8@pure_quanta.q_cap(chips)';

PART_NAME
 PC189 'Q_CAPP_SMLF-470UF,2.5V,20%,POSCAP,CH747LM8816':;

SECTION_NUMBER 1
 '@T6G_MB_LIB.T6G(SCH_1):PAGE308_I54@PURE_QUANTA.Q_CAPP(CHIPS)':
 C_PATH='@t6g_mb_lib.t6g(sch_1):page308_i54@pure_quanta.q_capp(chips)';

PART_NAME
 PC83 'Q_CAPP_THLF-560UF,2.5V,20%,OSCON,CC7560JMD18':;

SECTION_NUMBER 1
 '@T6G_MB_LIB.T6G(SCH_1):PAGE308_I105@PURE_QUANTA.Q_CAPP(CHIPS)':
 C_PATH='@t6g_mb_lib.t6g(sch_1):page308_i105@pure_quanta.q_capp(chips)';

PART_NAME
 PU100 'MPQ8626GDZ-MPQ8626GD-Z,SMLF,IC,AL008626000':;

SECTION_NUMBER 1
 '@T6G_MB_LIB.T6G(SCH_1):PAGE330_I29@PURE_QUANTA.MPQ8626GDZ(CHIPS)':
 C_PATH='@t6g_mb_lib.t6g(sch_1):page330_i29@pure_quanta.mpq8626gdz(chips)';

PART_NAME
 PR1037 'Q_RES_0402LF-75K,1%,1/16W,CHIP,CS37502FB12':;

SECTION_NUMBER 1
 '@T6G_MB_LIB.T6G(SCH_1):PAGE330_I42@PURE_QUANTA.Q_RES(CHIPS)':
 C_PATH='@t6g_mb_lib.t6g(sch_1):page330_i42@pure_quanta.q_res(chips)';

PART_NAME
 PR1036 'Q_RES_0402LF-150K,5%,1/16W,CHIP,CS41502JB10':;

SECTION_NUMBER 1
 '@T6G_MB_LIB.T6G(SCH_1):PAGE330_I39@PURE_QUANTA.Q_RES(CHIPS)':
 C_PATH='@t6g_mb_lib.t6g(sch_1):page330_i39@pure_quanta.q_res(chips)';

PART_NAME
 PR534 'Q_RES_0402LF-10K,1%,1/16W,CHIP,TMP_QCS31002FB26':;

SECTION_NUMBER 1
 '@T6G_MB_LIB.T6G(SCH_1):PAGE330_I24@PURE_QUANTA.Q_RES(CHIPS)':
 C_PATH='@t6g_mb_lib.t6g(sch_1):page330_i24@pure_quanta.q_res(chips)';

PART_NAME
 PR533 'Q_RES_0402LF-73.2K,1%,1/16W,CHIP,CS37322FB14':;

SECTION_NUMBER 1
 '@T6G_MB_LIB.T6G(SCH_1):PAGE330_I22@PURE_QUANTA.Q_RES(CHIPS)':
 C_PATH='@t6g_mb_lib.t6g(sch_1):page330_i22@pure_quanta.q_res(chips)';

PART_NAME
 PR532 'Q_RES_0402LF-60.4K,1%,1/16W,CHIP,CS36042FB10':;

SECTION_NUMBER 1
 '@T6G_MB_LIB.T6G(SCH_1):PAGE330_I34@PURE_QUANTA.Q_RES(CHIPS)':
 C_PATH='@t6g_mb_lib.t6g(sch_1):page330_i34@pure_quanta.q_res(chips)';

PART_NAME
 PR27 'Q_RES_0402LF-17.8K,1%,1/16W,CHIP,TMP_QCS31782FB10':;

SECTION_NUMBER 1
 '@T6G_MB_LIB.T6G(SCH_1):PAGE330_I44@PURE_QUANTA.Q_RES(CHIPS)':
 C_PATH='@t6g_mb_lib.t6g(sch_1):page330_i44@pure_quanta.q_res(chips)';

PART_NAME
 PR24 'Q_RES_0402LF-10K,5%,1/16W,CHIP,TMP_QCS31002JB28':;

SECTION_NUMBER 1
 '@T6G_MB_LIB.T6G(SCH_1):PAGE330_I6@PURE_QUANTA.Q_RES(CHIPS)':
 C_PATH='@t6g_mb_lib.t6g(sch_1):page330_i6@pure_quanta.q_res(chips)';

PART_NAME
 PL200 'Q_INDUCTOR_SMLF-BLM18SN220TN1D/8000MA,IND,CX220TN1001':;

SECTION_NUMBER 1
 '@T6G_MB_LIB.T6G(SCH_1):PAGE330_I37@PURE_QUANTA.Q_INDUCTOR(CHIPS)':
 C_PATH='@t6g_mb_lib.t6g(sch_1):page330_i37@pure_quanta.q_inductor(chips)';

PART_NAME
 PL1 'Q_INDUCTOR_SMLF-3.3UH/6A,IND,CV-3360MZ07':;

SECTION_NUMBER 1
 '@T6G_MB_LIB.T6G(SCH_1):PAGE330_I3@PURE_QUANTA.Q_INDUCTOR(CHIPS)':
 C_PATH='@t6g_mb_lib.t6g(sch_1):page330_i3@pure_quanta.q_inductor(chips)';

PART_NAME
 PC693 'Q_CAP_0402-0.1UF,25V,10%,EMPTY,CH4104K1B00':
;

SECTION_NUMBER 1
 '@T6G_MB_LIB.T6G(SCH_1):PAGE330_I40@PURE_QUANTA.Q_CAP(CHIPS)':
 C_PATH='@t6g_mb_lib.t6g(sch_1):page330_i40@pure_quanta.q_cap(chips)';

PART_NAME
 PC273 'Q_CAP_0402-3300PF,50V,10%,X7R,TMP_QCH2336K1B12':;

SECTION_NUMBER 1
 '@T6G_MB_LIB.T6G(SCH_1):PAGE330_I26@PURE_QUANTA.Q_CAP(CHIPS)':
 C_PATH='@t6g_mb_lib.t6g(sch_1):page330_i26@pure_quanta.q_cap(chips)';

PART_NAME
 PC272 'Q_CAP_C0402-1UF,25V,10%,X6S,CH5104KEB02':;

SECTION_NUMBER 1
 '@T6G_MB_LIB.T6G(SCH_1):PAGE330_I31@PURE_QUANTA.Q_CAP(CHIPS)':
 C_PATH='@t6g_mb_lib.t6g(sch_1):page330_i31@pure_quanta.q_cap(chips)';

PART_NAME
 PC239 'Q_CAP_0402-100PF,50V,5%,NPO,CH11006JB00':;

SECTION_NUMBER 1
 '@T6G_MB_LIB.T6G(SCH_1):PAGE330_I23@PURE_QUANTA.Q_CAP(CHIPS)':
 C_PATH='@t6g_mb_lib.t6g(sch_1):page330_i23@pure_quanta.q_cap(chips)';

PART_NAME
 PC39 'Q_CAP_C0805-22UF,10V,20%,EMPTY,CH6222MEA00':;

SECTION_NUMBER 1
 '@T6G_MB_LIB.T6G(SCH_1):PAGE330_I13@PURE_QUANTA.Q_CAP(CHIPS)':
 C_PATH='@t6g_mb_lib.t6g(sch_1):page330_i13@pure_quanta.q_cap(chips)';

PART_NAME
 PC38 'Q_CAP_C0805-22UF,10V,20%,EMPTY,CH6222MEA00':;

SECTION_NUMBER 1
 '@T6G_MB_LIB.T6G(SCH_1):PAGE330_I14@PURE_QUANTA.Q_CAP(CHIPS)':
 C_PATH='@t6g_mb_lib.t6g(sch_1):page330_i14@pure_quanta.q_cap(chips)';

PART_NAME
 PC37 'Q_CAP_C0805-22UF,10V,20%,EMPTY,CH6222MEA00':;

SECTION_NUMBER 1
 '@T6G_MB_LIB.T6G(SCH_1):PAGE330_I16@PURE_QUANTA.Q_CAP(CHIPS)':
 C_PATH='@t6g_mb_lib.t6g(sch_1):page330_i16@pure_quanta.q_cap(chips)';

PART_NAME
 PC36 'Q_CAP_C0805-22UF,10V,20%,EMPTY,CH6222MEA00':;

SECTION_NUMBER 1
 '@T6G_MB_LIB.T6G(SCH_1):PAGE330_I18@PURE_QUANTA.Q_CAP(CHIPS)':
 C_PATH='@t6g_mb_lib.t6g(sch_1):page330_i18@pure_quanta.q_cap(chips)';

PART_NAME
 PC35 'Q_CAP_C0805-22UF,10V,20%,X6S,CH6222MEA00':;

SECTION_NUMBER 1
 '@T6G_MB_LIB.T6G(SCH_1):PAGE330_I11@PURE_QUANTA.Q_CAP(CHIPS)':
 C_PATH='@t6g_mb_lib.t6g(sch_1):page330_i11@pure_quanta.q_cap(chips)';

PART_NAME
 PC34 'Q_CAP_C0805-22UF,10V,20%,X6S,CH6222MEA00':;

SECTION_NUMBER 1
 '@T6G_MB_LIB.T6G(SCH_1):PAGE330_I12@PURE_QUANTA.Q_CAP(CHIPS)':
 C_PATH='@t6g_mb_lib.t6g(sch_1):page330_i12@pure_quanta.q_cap(chips)';

PART_NAME
 PC33 'Q_CAP_C0805-22UF,10V,20%,X6S,CH6222MEA00':;

SECTION_NUMBER 1
 '@T6G_MB_LIB.T6G(SCH_1):PAGE330_I15@PURE_QUANTA.Q_CAP(CHIPS)':
 C_PATH='@t6g_mb_lib.t6g(sch_1):page330_i15@pure_quanta.q_cap(chips)';

PART_NAME
 PC32 'Q_CAP_C0805-22UF,10V,20%,X6S,CH6222MEA00':;

SECTION_NUMBER 1
 '@T6G_MB_LIB.T6G(SCH_1):PAGE330_I17@PURE_QUANTA.Q_CAP(CHIPS)':
 C_PATH='@t6g_mb_lib.t6g(sch_1):page330_i17@pure_quanta.q_cap(chips)';

PART_NAME
 PC31 'Q_CAP_0402-0.1UF,25V,10%,X7R,CH4104K1B00':;

SECTION_NUMBER 1
 '@T6G_MB_LIB.T6G(SCH_1):PAGE330_I20@PURE_QUANTA.Q_CAP(CHIPS)':
 C_PATH='@t6g_mb_lib.t6g(sch_1):page330_i20@pure_quanta.q_cap(chips)';

PART_NAME
 PC29 'Q_CAP_C0805-10UF,25V,10%,X6S,CH6104KEA00':;

SECTION_NUMBER 1
 '@T6G_MB_LIB.T6G(SCH_1):PAGE330_I9@PURE_QUANTA.Q_CAP(CHIPS)':
 C_PATH='@t6g_mb_lib.t6g(sch_1):page330_i9@pure_quanta.q_cap(chips)';

PART_NAME
 PC23 'Q_CAP_0402-0.1UF,25V,10%,X7R,CH4104K1B00':;

SECTION_NUMBER 1
 '@T6G_MB_LIB.T6G(SCH_1):PAGE330_I7@PURE_QUANTA.Q_CAP(CHIPS)':
 C_PATH='@t6g_mb_lib.t6g(sch_1):page330_i7@pure_quanta.q_cap(chips)';

PART_NAME
 PC22 'Q_CAP_0402-0.22UF,16V,10%,X7R,CH4223K1B00':;

SECTION_NUMBER 1
 '@T6G_MB_LIB.T6G(SCH_1):PAGE330_I5@PURE_QUANTA.Q_CAP(CHIPS)':
 C_PATH='@t6g_mb_lib.t6g(sch_1):page330_i5@pure_quanta.q_cap(chips)';

PART_NAME
 PC21 'Q_CAP_C0805-10UF,25V,10%,X6S,CH6104KEA00':;

SECTION_NUMBER 1
 '@T6G_MB_LIB.T6G(SCH_1):PAGE330_I8@PURE_QUANTA.Q_CAP(CHIPS)':
 C_PATH='@t6g_mb_lib.t6g(sch_1):page330_i8@pure_quanta.q_cap(chips)';

PART_NAME
 PU13_P0_1 'ISL99390FRZTR5935-ISL99390FRZ-TR5935,SMLF,IC,AL099390004':;

SECTION_NUMBER 1
 '@T6G_MB_LIB.T6G(SCH_1):PAGE290_I21@PURE_QUANTA.ISL99390FRZTR5935(CHIPS)':
 C_PATH='@s6q_mb_lib.s6q(sch_1):page290_i21@pure_quanta.isl99390frztr5935(chips)~
';

PART_NAME
 PU12_P0_2 'ISL99390FRZTR5935-ISL99390FRZ-TR5935,SMLF,IC,AL099390004':;

SECTION_NUMBER 1
 '@T6G_MB_LIB.T6G(SCH_1):PAGE290_I87@PURE_QUANTA.ISL99390FRZTR5935(CHIPS)':
 C_PATH='@s6q_mb_lib.s6q(sch_1):page290_i87@pure_quanta.isl99390frztr5935(chips)~
';

PART_NAME
 PR1787 'Q_RES_0402LF-3.3,1%,1/16W,CHIP,CS-3302FB00':;

SECTION_NUMBER 1
 '@T6G_MB_LIB.T6G(SCH_1):PAGE290_I39@PURE_QUANTA.Q_RES(CHIPS)':
 C_PATH='@t6g_mb_lib.t6g(sch_1):page290_i39@pure_quanta.q_res(chips)',
 CDSVAR_REPCELL_MPS='pure_quanta|Q_res',
 VAR_0_MPS='VALUE|0|TOLERANCE|5%|WATTAGE|1/16W|PACK_TYPE|0402LF|MATERIAL|CHIP|PA~
RT_NUMBER|CS00002JB38|STANDARD|End of Design|LIFECYCLE|Comp-Approve|PART_NUMBER|~
CS00002JB38|JEDEC_TYPE|R0402|ALT_SYMBOLS|(R0402-0201)|VALUE|0|TOL|5%|WATTAGE|1/1~
6W|CLASS|DISCRETE|DESCRIPTION|RESISTOR CHIP 0 1/16W +-5%(0402)|COMPONENT_TYPE|CH~
IP0402|LEAD_LENGTH||DFM_EXCLUSION||DAY|20100618|VARIANT_DEVICE_TYPE|Q_RES-0,5%,1~
/16W,0402LF,CHIP,C';

PART_NAME
 PR1786 'Q_RES_0402LF-3.3,1%,1/16W,CHIP,CS-3302FB00':;

SECTION_NUMBER 1
 '@T6G_MB_LIB.T6G(SCH_1):PAGE290_I20@PURE_QUANTA.Q_RES(CHIPS)':
 C_PATH='@t6g_mb_lib.t6g(sch_1):page290_i20@pure_quanta.q_res(chips)',
 CDSVAR_REPCELL_MPS='pure_quanta|Q_res',
 VAR_0_MPS='VALUE|0|TOLERANCE|5%|WATTAGE|1/16W|PACK_TYPE|0402LF|MATERIAL|CHIP|PA~
RT_NUMBER|CS00002JB38|STANDARD|End of Design|LIFECYCLE|Comp-Approve|PART_NUMBER|~
CS00002JB38|JEDEC_TYPE|R0402|ALT_SYMBOLS|(R0402-0201)|VALUE|0|TOL|5%|WATTAGE|1/1~
6W|CLASS|DISCRETE|DESCRIPTION|RESISTOR CHIP 0 1/16W +-5%(0402)|COMPONENT_TYPE|CH~
IP0402|LEAD_LENGTH||DFM_EXCLUSION||DAY|20100618|VARIANT_DEVICE_TYPE|Q_RES-0,5%,1~
/16W,0402LF,CHIP,C';

PART_NAME
 PR403 'Q_RES_0402LF-0,5%,1/16W,EMPTY,CS00002JB38':;

SECTION_NUMBER 1
 '@T6G_MB_LIB.T6G(SCH_1):PAGE290_I36@PURE_QUANTA.Q_RES(CHIPS)':
 C_PATH='@t6g_mb_lib.t6g(sch_1):page290_i36@pure_quanta.q_res(chips)',
 CDSVAR_REPCELL_MPS='pure_quanta|Q_res',
 VAR_0_MPS='VALUE|0|TOLERANCE|5%|WATTAGE|1/16W|PACK_TYPE|0402LF|MATERIAL|CHIP|PA~
RT_NUMBER|CS00002JB38|STANDARD|End of Design|LIFECYCLE|Comp-Approve|PART_NUMBER|~
CS00002JB38|JEDEC_TYPE|R0402|ALT_SYMBOLS|(R0402-0201)|VALUE|0|TOL|5%|WATTAGE|1/1~
6W|CLASS|DISCRETE|DESCRIPTION|RESISTOR CHIP 0 1/16W +-5%(0402)|COMPONENT_TYPE|CH~
IP0402|LEAD_LENGTH||DFM_EXCLUSION||DAY|20100618|VARIANT_DEVICE_TYPE|Q_RES-0,5%,1~
/16W,0402LF,CHIP,C';

PART_NAME
 PR402 'Q_RES_0402LF-0,5%,1/16W,CHIP,CS00002JB38':;

SECTION_NUMBER 1
 '@T6G_MB_LIB.T6G(SCH_1):PAGE290_I31@PURE_QUANTA.Q_RES(CHIPS)':
 C_PATH='@t6g_mb_lib.t6g(sch_1):page290_i31@pure_quanta.q_res(chips)',
 CDSVAR_REPCELL_MPS='pure_quanta|Q_res',
 VAR_0_MPS='VALUE|0|TOLERANCE|5%|WATTAGE|1/16W|PACK_TYPE|0402LF|MATERIAL|EMPTY|P~
ART_NUMBER|CS00002JB38|STANDARD|End of Design|LIFECYCLE|Comp-Approve|PART_NUMBER~
|CS00002JB38|JEDEC_TYPE|R0402|ALT_SYMBOLS|(R0402-0201)|VALUE|0|TOL|5%|WATTAGE|1/~
16W|CLASS|IO|DESCRIPTION|RESISTOR CHIP 0 1/16W +-5%(0402)|COMPONENT_TYPE|CHIP040~
2|LEAD_LENGTH||DFM_EXCLUSION||DAY|20100618|VARIANT_DEVICE_TYPE|Q_RES-0,5%,1/16W,~
0402LF,EMPTY,';

PART_NAME
 PR155 'Q_RES_0402LF-0,5%,1/16W,CHIP,CS00002JB38':;

SECTION_NUMBER 1
 '@T6G_MB_LIB.T6G(SCH_1):PAGE290_I112@PURE_QUANTA.Q_RES(CHIPS)':
 C_PATH='@t6g_mb_lib.t6g(sch_1):page290_i112@pure_quanta.q_res(chips)';

PART_NAME
 PR154 'Q_RES_0402LF-0,5%,1/16W,CHIP,CS00002JB38':;

SECTION_NUMBER 1
 '@T6G_MB_LIB.T6G(SCH_1):PAGE290_I124@PURE_QUANTA.Q_RES(CHIPS)':
 C_PATH='@t6g_mb_lib.t6g(sch_1):page290_i124@pure_quanta.q_res(chips)';

PART_NAME
 PR153 'Q_RES_0402LF-2.2,1%,1/16W,CHIP,CS-2202FB00':;

SECTION_NUMBER 1
 '@T6G_MB_LIB.T6G(SCH_1):PAGE290_I32@PURE_QUANTA.Q_RES(CHIPS)':
 C_PATH='@t6g_mb_lib.t6g(sch_1):page290_i32@pure_quanta.q_res(chips)';

PART_NAME
 PR152 'Q_RES_0402LF-2.2,1%,1/16W,CHIP,CS-2202FB00':;

SECTION_NUMBER 1
 '@T6G_MB_LIB.T6G(SCH_1):PAGE290_I11@PURE_QUANTA.Q_RES(CHIPS)':
 C_PATH='@t6g_mb_lib.t6g(sch_1):page290_i11@pure_quanta.q_res(chips)';

PART_NAME
 PR151 'Q_RES_0402LF-8.87K,1%,1/16W,EMPTY,CS28872FB01':;

SECTION_NUMBER 1
 '@T6G_MB_LIB.T6G(SCH_1):PAGE290_I14@PURE_QUANTA.Q_RES(CHIPS)':
 C_PATH='@t6g_mb_lib.t6g(sch_1):page290_i14@pure_quanta.q_res(chips)';

PART_NAME
 PR150 'Q_RES_0402LF-8.87K,1%,1/16W,EMPTY,CS28872FB01':;

SECTION_NUMBER 1
 '@T6G_MB_LIB.T6G(SCH_1):PAGE290_I2@PURE_QUANTA.Q_RES(CHIPS)':
 C_PATH='@t6g_mb_lib.t6g(sch_1):page290_i2@pure_quanta.q_res(chips)';

PART_NAME
 PL114 'Q_INDUCTOR4P_14-150NH,SMLF,IND,CV+15^0TZ01':;

SECTION_NUMBER 1
 '@T6G_MB_LIB.T6G(SCH_1):PAGE290_I104@PURE_QUANTA.Q_INDUCTOR4P_14(CHIPS)':
 C_PATH='@t6g_mb_lib.t6g(sch_1):page290_i104@pure_quanta.q_inductor4p_14(chips)';

PART_NAME
 PL15 'Q_INDUCTOR_SMLF-50NH/148A,IND,CVA50^0EZ01':;

SECTION_NUMBER 1
 '@T6G_MB_LIB.T6G(SCH_1):PAGE290_I75@PURE_QUANTA.Q_INDUCTOR(CHIPS)':
 C_PATH='@t6g_mb_lib.t6g(sch_1):page290_i75@pure_quanta.q_inductor(chips)';

PART_NAME
 PL13 'Q_INDUCTOR4P_14-150NH,SMLF,IND,CV+15^0TZ01':;

SECTION_NUMBER 1
 '@T6G_MB_LIB.T6G(SCH_1):PAGE290_I122@PURE_QUANTA.Q_INDUCTOR4P_14(CHIPS)':
 C_PATH='@t6g_mb_lib.t6g(sch_1):page290_i122@pure_quanta.q_inductor4p_14(chips)';

PART_NAME
 PC2336 'Q_CAPP_SMLF-470UF,2.5V,20%,EMPTY,CH747LM8816':;

SECTION_NUMBER 1
 '@T6G_MB_LIB.T6G(SCH_1):PAGE290_I53@PURE_QUANTA.Q_CAPP(CHIPS)':
 C_PATH='@t6g_mb_lib.t6g(sch_1):page290_i53@pure_quanta.q_capp(chips)';

PART_NAME
 PC1920 'Q_CAPP_SMLF-470UF,2.5V,20%,POSCAP,CH747LM8816':;

SECTION_NUMBER 1
 '@T6G_MB_LIB.T6G(SCH_1):PAGE290_I54@PURE_QUANTA.Q_CAPP(CHIPS)':
 C_PATH='@t6g_mb_lib.t6g(sch_1):page290_i54@pure_quanta.q_capp(chips)';

PART_NAME
 PC1356 'Q_CAP_0402-0.1UF,25V,10%,X7R,CH4104K1B00':;

SECTION_NUMBER 1
 '@T6G_MB_LIB.T6G(SCH_1):PAGE290_I33@PURE_QUANTA.Q_CAP(CHIPS)':
 C_PATH='@t6g_mb_lib.t6g(sch_1):page290_i33@pure_quanta.q_cap(chips)',
 CDSVAR_REPCELL_MPS='pure_quanta|Q_cap',
 VAR_0_MPS='VALUE|0.1UF|VOLTAGE|25V|TOLERANCE|10%|PACK_TYPE|0402|MATERIAL|EMPTY|~
PART_NUMBER|CH4104K1B00|STANDARD||LIFECYCLE||ASS_PART||PART_NUMBER|CH4104K1B00|J~
EDEC_TYPE|C0402|ALT_SYMBOLS|(C0402_OCTAGONXA,C0402-0201)|VALUE|NA|RATED_VOLTAGE|~
25V|TOL|10%|CLASS|IO|DESCRIPTION|CAP CHIP 0.1U 25V(+-10%,X7R,0402)|COMPONENT_TYP~
E|CHIP0402|LEAD_LENGTH||LPID||DATE|20160113|VARIANT_DEVICE_TYPE|Q_CAP-0.1UF,25V,~
10%,0402,EMPTY';

PART_NAME
 PC1355 'Q_CAP_0402-0.1UF,25V,10%,X7R,CH4104K1B00':;

SECTION_NUMBER 1
 '@T6G_MB_LIB.T6G(SCH_1):PAGE290_I10@PURE_QUANTA.Q_CAP(CHIPS)':
 C_PATH='@t6g_mb_lib.t6g(sch_1):page290_i10@pure_quanta.q_cap(chips)',
 CDSVAR_REPCELL_MPS='pure_quanta|Q_cap',
 VAR_0_MPS='VALUE|0.1UF|VOLTAGE|25V|TOLERANCE|10%|PACK_TYPE|0402|MATERIAL|EMPTY|~
PART_NUMBER|CH4104K1B00|STANDARD||LIFECYCLE||ASS_PART||PART_NUMBER|CH4104K1B00|J~
EDEC_TYPE|C0402|ALT_SYMBOLS|(C0402_OCTAGONXA,C0402-0201)|VALUE|NA|RATED_VOLTAGE|~
25V|TOL|10%|CLASS|IO|DESCRIPTION|CAP CHIP 0.1U 25V(+-10%,X7R,0402)|COMPONENT_TYP~
E|CHIP0402|LEAD_LENGTH||LPID||DATE|20160113|VARIANT_DEVICE_TYPE|Q_CAP-0.1UF,25V,~
10%,0402,EMPTY';

PART_NAME
 PC326 'Q_CAPP_SMLF-470UF,2.5V,20%,POSCAP,CH747LM8816':;

SECTION_NUMBER 1
 '@T6G_MB_LIB.T6G(SCH_1):PAGE290_I79@PURE_QUANTA.Q_CAPP(CHIPS)':
 C_PATH='@t6g_mb_lib.t6g(sch_1):page290_i79@pure_quanta.q_capp(chips)';

PART_NAME
 PC325 'Q_CAPP_THLF-560UF,2.5V,20%,OSCON,CC7560JMD18':;

SECTION_NUMBER 1
 '@T6G_MB_LIB.T6G(SCH_1):PAGE290_I81@PURE_QUANTA.Q_CAPP(CHIPS)':
 C_PATH='@t6g_mb_lib.t6g(sch_1):page290_i81@pure_quanta.q_capp(chips)';

PART_NAME
 PC324 'Q_CAPP_THLF-270UF,16V,20%,OSCON,CC72703MD33':;

SECTION_NUMBER 1
 '@T6G_MB_LIB.T6G(SCH_1):PAGE290_I84@PURE_QUANTA.Q_CAPP(CHIPS)':
 C_PATH='@t6g_mb_lib.t6g(sch_1):page290_i84@pure_quanta.q_capp(chips)';

PART_NAME
 PC323 'Q_CAPP_SMLF-470UF,2.5V,20%,EMPTY,CH747LM8816':;

SECTION_NUMBER 1
 '@T6G_MB_LIB.T6G(SCH_1):PAGE290_I55@PURE_QUANTA.Q_CAPP(CHIPS)':
 C_PATH='@t6g_mb_lib.t6g(sch_1):page290_i55@pure_quanta.q_capp(chips)';

PART_NAME
 PC322 'Q_CAPP_THLF-560UF,2.5V,20%,OSCON,CC7560JMD18':;

SECTION_NUMBER 1
 '@T6G_MB_LIB.T6G(SCH_1):PAGE290_I59@PURE_QUANTA.Q_CAPP(CHIPS)':
 C_PATH='@t6g_mb_lib.t6g(sch_1):page290_i59@pure_quanta.q_capp(chips)';

PART_NAME
 PC321 'Q_CAPP_THLF-270UF,16V,20%,OSCON,CC72703MD33':;

SECTION_NUMBER 1
 '@T6G_MB_LIB.T6G(SCH_1):PAGE290_I77@PURE_QUANTA.Q_CAPP(CHIPS)':
 C_PATH='@t6g_mb_lib.t6g(sch_1):page290_i77@pure_quanta.q_capp(chips)';

PART_NAME
 PC319 'Q_CAPP_THLF-560UF,2.5V,20%,OSCON,CC7560JMD18':;

SECTION_NUMBER 1
 '@T6G_MB_LIB.T6G(SCH_1):PAGE290_I58@PURE_QUANTA.Q_CAPP(CHIPS)':
 C_PATH='@t6g_mb_lib.t6g(sch_1):page290_i58@pure_quanta.q_capp(chips)';

PART_NAME
 PC318 'Q_CAPP_THLF-270UF,16V,20%,OSCON,CC72703MD33':;

SECTION_NUMBER 1
 '@T6G_MB_LIB.T6G(SCH_1):PAGE290_I76@PURE_QUANTA.Q_CAPP(CHIPS)':
 C_PATH='@t6g_mb_lib.t6g(sch_1):page290_i76@pure_quanta.q_capp(chips)';

PART_NAME
 PC316 'Q_CAPP_THLF-560UF,2.5V,20%,OSCON,CC7560JMD18':;

SECTION_NUMBER 1
 '@T6G_MB_LIB.T6G(SCH_1):PAGE290_I56@PURE_QUANTA.Q_CAPP(CHIPS)':
 C_PATH='@t6g_mb_lib.t6g(sch_1):page290_i56@pure_quanta.q_capp(chips)';

PART_NAME
 PC315 'Q_CAPP_THLF-270UF,16V,20%,OSCON,CC72703MD33':;

SECTION_NUMBER 1
 '@T6G_MB_LIB.T6G(SCH_1):PAGE290_I74@PURE_QUANTA.Q_CAPP(CHIPS)':
 C_PATH='@t6g_mb_lib.t6g(sch_1):page290_i74@pure_quanta.q_capp(chips)';

PART_NAME
 PC314_P0_1 'Q_CAP_0805-22UF,4V,20%,X6S,TMP_QCH622KMEA01':;

SECTION_NUMBER 1
 '@T6G_MB_LIB.T6G(SCH_1):PAGE290_I108@PURE_QUANTA.Q_CAP(CHIPS)':
 C_PATH='@t6g_mb_lib.t6g(sch_1):page290_i108@pure_quanta.q_cap(chips)';

PART_NAME
 PC313_P0_2 'Q_CAP_0805-22UF,4V,20%,X6S,TMP_QCH622KMEA01':;

SECTION_NUMBER 1
 '@T6G_MB_LIB.T6G(SCH_1):PAGE290_I127@PURE_QUANTA.Q_CAP(CHIPS)':
 C_PATH='@t6g_mb_lib.t6g(sch_1):page290_i127@pure_quanta.q_cap(chips)';

PART_NAME
 PC312_P0_1 'Q_CAP_0805-22UF,4V,20%,X6S,TMP_QCH622KMEA01':;

SECTION_NUMBER 1
 '@T6G_MB_LIB.T6G(SCH_1):PAGE290_I109@PURE_QUANTA.Q_CAP(CHIPS)':
 C_PATH='@t6g_mb_lib.t6g(sch_1):page290_i109@pure_quanta.q_cap(chips)';

PART_NAME
 PC311_P0_2 'Q_CAP_0805-22UF,4V,20%,X6S,TMP_QCH622KMEA01':;

SECTION_NUMBER 1
 '@T6G_MB_LIB.T6G(SCH_1):PAGE290_I128@PURE_QUANTA.Q_CAP(CHIPS)':
 C_PATH='@t6g_mb_lib.t6g(sch_1):page290_i128@pure_quanta.q_cap(chips)';

PART_NAME
 PC310_P0_1 'Q_CAP_C0402-1UF,16V,10%,X6S,CH5103KEB01':;

SECTION_NUMBER 1
 '@T6G_MB_LIB.T6G(SCH_1):PAGE290_I110@PURE_QUANTA.Q_CAP(CHIPS)':
 C_PATH='@t6g_mb_lib.t6g(sch_1):page290_i110@pure_quanta.q_cap(chips)';

PART_NAME
 PC308_P0_1 'Q_CAP_C0402-100NF,50V,10%,X7R,CH4106K1B01':;

SECTION_NUMBER 1
 '@T6G_MB_LIB.T6G(SCH_1):PAGE290_I111@PURE_QUANTA.Q_CAP(CHIPS)':
 C_PATH='@t6g_mb_lib.t6g(sch_1):page290_i111@pure_quanta.q_cap(chips)';

PART_NAME
 PC307_P0_1 'Q_CAP_C0805-22UF,16V,20%,X6S,CH6223MEA00':;

SECTION_NUMBER 1
 '@T6G_MB_LIB.T6G(SCH_1):PAGE290_I67@PURE_QUANTA.Q_CAP(CHIPS)':
 C_PATH='@t6g_mb_lib.t6g(sch_1):page290_i67@pure_quanta.q_cap(chips)';

PART_NAME
 PC306_P0_2 'Q_CAP_C0805-22UF,16V,20%,X6S,CH6223MEA00':;

SECTION_NUMBER 1
 '@T6G_MB_LIB.T6G(SCH_1):PAGE290_I47@PURE_QUANTA.Q_CAP(CHIPS)':
 C_PATH='@t6g_mb_lib.t6g(sch_1):page290_i47@pure_quanta.q_cap(chips)';

PART_NAME
 PC305_P0_1 'Q_CAP_C0805-22UF,16V,20%,X6S,CH6223MEA00':;

SECTION_NUMBER 1
 '@T6G_MB_LIB.T6G(SCH_1):PAGE290_I66@PURE_QUANTA.Q_CAP(CHIPS)':
 C_PATH='@t6g_mb_lib.t6g(sch_1):page290_i66@pure_quanta.q_cap(chips)';

PART_NAME
 PC304_P0_2 'Q_CAP_C0805-22UF,16V,20%,X6S,CH6223MEA00':;

SECTION_NUMBER 1
 '@T6G_MB_LIB.T6G(SCH_1):PAGE290_I46@PURE_QUANTA.Q_CAP(CHIPS)':
 C_PATH='@t6g_mb_lib.t6g(sch_1):page290_i46@pure_quanta.q_cap(chips)';

PART_NAME
 PC303_P0_1 'Q_CAP_C0805-22UF,16V,20%,X6S,CH6223MEA00':;

SECTION_NUMBER 1
 '@T6G_MB_LIB.T6G(SCH_1):PAGE290_I65@PURE_QUANTA.Q_CAP(CHIPS)':
 C_PATH='@t6g_mb_lib.t6g(sch_1):page290_i65@pure_quanta.q_cap(chips)';

PART_NAME
 PC302_P0_2 'Q_CAP_C0805-22UF,16V,20%,X6S,CH6223MEA00':;

SECTION_NUMBER 1
 '@T6G_MB_LIB.T6G(SCH_1):PAGE290_I24@PURE_QUANTA.Q_CAP(CHIPS)':
 C_PATH='@t6g_mb_lib.t6g(sch_1):page290_i24@pure_quanta.q_cap(chips)';

PART_NAME
 PC301 'Q_CAP_C0402-100NF,50V,10%,X7R,CH4106K1B01':;

SECTION_NUMBER 1
 '@T6G_MB_LIB.T6G(SCH_1):PAGE290_I62@PURE_QUANTA.Q_CAP(CHIPS)':
 C_PATH='@t6g_mb_lib.t6g(sch_1):page290_i62@pure_quanta.q_cap(chips)';

PART_NAME
 PC300 'Q_CAP_C0402-100NF,50V,10%,X7R,CH4106K1B01':;

SECTION_NUMBER 1
 '@T6G_MB_LIB.T6G(SCH_1):PAGE290_I44@PURE_QUANTA.Q_CAP(CHIPS)':
 C_PATH='@t6g_mb_lib.t6g(sch_1):page290_i44@pure_quanta.q_cap(chips)';

PART_NAME
 PC299_P0_1 'Q_CAP_C0402-1UF,16V,10%,X6S,CH5103KEB01':;

SECTION_NUMBER 1
 '@T6G_MB_LIB.T6G(SCH_1):PAGE290_I41@PURE_QUANTA.Q_CAP(CHIPS)':
 C_PATH='@t6g_mb_lib.t6g(sch_1):page290_i41@pure_quanta.q_cap(chips)';

PART_NAME
 PC298_P0_2 'Q_CAP_C0402-1UF,16V,10%,X6S,CH5103KEB01':;

SECTION_NUMBER 1
 '@T6G_MB_LIB.T6G(SCH_1):PAGE290_I23@PURE_QUANTA.Q_CAP(CHIPS)':
 C_PATH='@t6g_mb_lib.t6g(sch_1):page290_i23@pure_quanta.q_cap(chips)';

PART_NAME
 PC297_P0_1 'Q_CAP_0402-3300PF,50V,10%,X7R,TMP_QCH2336K1B12':;

SECTION_NUMBER 1
 '@T6G_MB_LIB.T6G(SCH_1):PAGE290_I40@PURE_QUANTA.Q_CAP(CHIPS)':
 C_PATH='@t6g_mb_lib.t6g(sch_1):page290_i40@pure_quanta.q_cap(chips)';

PART_NAME
 PC296_P0_2 'Q_CAP_0402-3300PF,50V,10%,X7R,TMP_QCH2336K1B12':;

SECTION_NUMBER 1
 '@T6G_MB_LIB.T6G(SCH_1):PAGE290_I22@PURE_QUANTA.Q_CAP(CHIPS)':
 C_PATH='@t6g_mb_lib.t6g(sch_1):page290_i22@pure_quanta.q_cap(chips)';

PART_NAME
 PC295_P0_1 'Q_CAP_C0402-2.2UF,10V,10%,X6S,CH5222KEB01':;

SECTION_NUMBER 1
 '@T6G_MB_LIB.T6G(SCH_1):PAGE290_I35@PURE_QUANTA.Q_CAP(CHIPS)':
 C_PATH='@t6g_mb_lib.t6g(sch_1):page290_i35@pure_quanta.q_cap(chips)';

PART_NAME
 PC294_P0_2 'Q_CAP_C0402-2.2UF,10V,10%,X6S,CH5222KEB01':;

SECTION_NUMBER 1
 '@T6G_MB_LIB.T6G(SCH_1):PAGE290_I18@PURE_QUANTA.Q_CAP(CHIPS)':
 C_PATH='@t6g_mb_lib.t6g(sch_1):page290_i18@pure_quanta.q_cap(chips)';

PART_NAME
 PC293 'Q_CAP_C0402-2.2UF,10V,10%,X6S,CH5222KEB01':;

SECTION_NUMBER 1
 '@T6G_MB_LIB.T6G(SCH_1):PAGE290_I30@PURE_QUANTA.Q_CAP(CHIPS)':
 C_PATH='@t6g_mb_lib.t6g(sch_1):page290_i30@pure_quanta.q_cap(chips)';

PART_NAME
 PC292 'Q_CAP_C0402-2.2UF,10V,10%,X6S,CH5222KEB01':;

SECTION_NUMBER 1
 '@T6G_MB_LIB.T6G(SCH_1):PAGE290_I8@PURE_QUANTA.Q_CAP(CHIPS)':
 C_PATH='@t6g_mb_lib.t6g(sch_1):page290_i8@pure_quanta.q_cap(chips)';

PART_NAME
 PC16 'Q_CAPP_THLF-560UF,2.5V,20%,OSCON,CC7560JMD18':;

SECTION_NUMBER 1
 '@T6G_MB_LIB.T6G(SCH_1):PAGE290_I130@PURE_QUANTA.Q_CAPP(CHIPS)':
 C_PATH='@t6g_mb_lib.t6g(sch_1):page290_i130@pure_quanta.q_capp(chips)';

PART_NAME
 U162 'TPD2EUSB30DRTR_SMLF-TPD2EUSB30DRTR,IC,AL2EUSB3000':;

SECTION_NUMBER 1
 '@T6G_MB_LIB.T6G(SCH_1):PAGE265_I22@PURE_QUANTA.TPD2EUSB30DRTR(CHIPS)':
 C_PATH='@t6g_mb_lib.t6g(sch_1):page265_i22@pure_quanta.tpd2eusb30drtr(chips)';

PART_NAME
 U113 'TPD2EUSB30DRTR_SMLF-TPD2EUSB30DRTR,IC,AL2EUSB3000':;

SECTION_NUMBER 1
 '@T6G_MB_LIB.T6G(SCH_1):PAGE265_I18@PURE_QUANTA.TPD2EUSB30DRTR(CHIPS)':
 C_PATH='@t6g_mb_lib.t6g(sch_1):page265_i18@pure_quanta.tpd2eusb30drtr(chips)';

PART_NAME
 U86 'TPD2EUSB30DRTR_SMLF-TPD2EUSB30DRTR,IC,AL2EUSB3000':;

SECTION_NUMBER 1
 '@T6G_MB_LIB.T6G(SCH_1):PAGE265_I44@PURE_QUANTA.TPD2EUSB30DRTR(CHIPS)':
 C_PATH='@t6g_mb_lib.t6g(sch_1):page265_i44@pure_quanta.tpd2eusb30drtr(chips)';

PART_NAME
 U85 'TPD2EUSB30DRTR_SMLF-TPD2EUSB30DRTR,IC,AL2EUSB3000':;

SECTION_NUMBER 1
 '@T6G_MB_LIB.T6G(SCH_1):PAGE265_I35@PURE_QUANTA.TPD2EUSB30DRTR(CHIPS)':
 C_PATH='@t6g_mb_lib.t6g(sch_1):page265_i35@pure_quanta.tpd2eusb30drtr(chips)';

PART_NAME
 R1206 'Q_RES_0402LF-0,5%,1/16W,CHIP,CS00002JB38':;

SECTION_NUMBER 1
 '@T6G_MB_LIB.T6G(SCH_1):PAGE265_I3@PURE_QUANTA.Q_RES(CHIPS)':
 C_PATH='@t6g_mb_lib.t6g(sch_1):page265_i3@pure_quanta.q_res(chips)';

PART_NAME
 R1203 'Q_RES_0402LF-0,5%,1/16W,CHIP,CS00002JB38':;

SECTION_NUMBER 1
 '@T6G_MB_LIB.T6G(SCH_1):PAGE265_I10@PURE_QUANTA.Q_RES(CHIPS)':
 C_PATH='@t6g_mb_lib.t6g(sch_1):page265_i10@pure_quanta.q_res(chips)';

PART_NAME
 R1198 'Q_RES_0402LF-0,5%,1/16W,CHIP,CS00002JB38':;

SECTION_NUMBER 1
 '@T6G_MB_LIB.T6G(SCH_1):PAGE265_I11@PURE_QUANTA.Q_RES(CHIPS)':
 C_PATH='@t6g_mb_lib.t6g(sch_1):page265_i11@pure_quanta.q_res(chips)';

PART_NAME
 R1197 'Q_RES_0402LF-0,5%,1/16W,CHIP,CS00002JB38':;

SECTION_NUMBER 1
 '@T6G_MB_LIB.T6G(SCH_1):PAGE265_I9@PURE_QUANTA.Q_RES(CHIPS)':
 C_PATH='@t6g_mb_lib.t6g(sch_1):page265_i9@pure_quanta.q_res(chips)';

PART_NAME
 R1141 'Q_RES_0402LF-0,5%,1/16W,CHIP,CS00002JB38':;

SECTION_NUMBER 1
 '@T6G_MB_LIB.T6G(SCH_1):PAGE265_I43@PURE_QUANTA.Q_RES(CHIPS)':
 C_PATH='@t6g_mb_lib.t6g(sch_1):page265_i43@pure_quanta.q_res(chips)';

PART_NAME
 R1140 'Q_RES_0402LF-0,5%,1/16W,CHIP,CS00002JB38':;

SECTION_NUMBER 1
 '@T6G_MB_LIB.T6G(SCH_1):PAGE265_I45@PURE_QUANTA.Q_RES(CHIPS)':
 C_PATH='@t6g_mb_lib.t6g(sch_1):page265_i45@pure_quanta.q_res(chips)';

PART_NAME
 R1139 'Q_RES_0402LF-0,5%,1/16W,CHIP,CS00002JB38':;

SECTION_NUMBER 1
 '@T6G_MB_LIB.T6G(SCH_1):PAGE265_I40@PURE_QUANTA.Q_RES(CHIPS)':
 C_PATH='@t6g_mb_lib.t6g(sch_1):page265_i40@pure_quanta.q_res(chips)';

PART_NAME
 R1138 'Q_RES_0402LF-0,5%,1/16W,CHIP,CS00002JB38':;

SECTION_NUMBER 1
 '@T6G_MB_LIB.T6G(SCH_1):PAGE265_I41@PURE_QUANTA.Q_RES(CHIPS)':
 C_PATH='@t6g_mb_lib.t6g(sch_1):page265_i41@pure_quanta.q_res(chips)';

PART_NAME
 L104 'Q_INDUCTOR4P_12-67/320MA,320MA,SMLF,EMPTY,CX21SN67000':;

SECTION_NUMBER 1
 '@T6G_MB_LIB.T6G(SCH_1):PAGE265_I31@PURE_QUANTA.Q_INDUCTOR4P_12(CHIPS)':
 C_PATH='@t6g_mb_lib.t6g(sch_1):page265_i31@pure_quanta.q_inductor4p_12(chips)';

PART_NAME
 L76 'Q_INDUCTOR4P_12-67/320MA,320MA,SMLF,EMPTY,CX21SN67000':;

SECTION_NUMBER 1
 '@T6G_MB_LIB.T6G(SCH_1):PAGE265_I32@PURE_QUANTA.Q_INDUCTOR4P_12(CHIPS)':
 C_PATH='@t6g_mb_lib.t6g(sch_1):page265_i32@pure_quanta.q_inductor4p_12(chips)';

PART_NAME
 L75 'Q_INDUCTOR4P_12-67/320MA,320MA,SMLF,EMPTY,CX21SN67000':;

SECTION_NUMBER 1
 '@T6G_MB_LIB.T6G(SCH_1):PAGE265_I4@PURE_QUANTA.Q_INDUCTOR4P_12(CHIPS)':
 C_PATH='@t6g_mb_lib.t6g(sch_1):page265_i4@pure_quanta.q_inductor4p_12(chips)';

PART_NAME
 L74 'Q_INDUCTOR4P_12-67/320MA,320MA,SMLF,EMPTY,CX21SN67000':;

SECTION_NUMBER 1
 '@T6G_MB_LIB.T6G(SCH_1):PAGE265_I42@PURE_QUANTA.Q_INDUCTOR4P_12(CHIPS)':
 C_PATH='@t6g_mb_lib.t6g(sch_1):page265_i42@pure_quanta.q_inductor4p_12(chips)';

PART_NAME
 R3553 'Q_RES_0402LF-0,5%,1/16W,CHIP,CS00002JB38':;

SECTION_NUMBER 1
 '@T6G_MB_LIB.T6G(SCH_1):PAGE273_I347@PURE_QUANTA.Q_RES(CHIPS)':
 C_PATH='@t6g_mb_lib.t6g(sch_1):page273_i347@pure_quanta.q_res(chips)';

PART_NAME
 R3552 'Q_RES_0402LF-33,5%,1/16W,CHIP,CS03302JB29':;

SECTION_NUMBER 1
 '@T6G_MB_LIB.T6G(SCH_1):PAGE273_I346@PURE_QUANTA.Q_RES(CHIPS)':
 C_PATH='@t6g_mb_lib.t6g(sch_1):page273_i346@pure_quanta.q_res(chips)';

PART_NAME
 R3551 'Q_RES_0402LF-0,5%,1/16W,CHIP,CS00002JB38':;

SECTION_NUMBER 1
 '@T6G_MB_LIB.T6G(SCH_1):PAGE273_I340@PURE_QUANTA.Q_RES(CHIPS)':
 C_PATH='@t6g_mb_lib.t6g(sch_1):page273_i340@pure_quanta.q_res(chips)';

PART_NAME
 R3550 'Q_RES_0402LF-0,5%,1/16W,CHIP,CS00002JB38':;

SECTION_NUMBER 1
 '@T6G_MB_LIB.T6G(SCH_1):PAGE273_I341@PURE_QUANTA.Q_RES(CHIPS)':
 C_PATH='@t6g_mb_lib.t6g(sch_1):page273_i341@pure_quanta.q_res(chips)';

PART_NAME
 R3545 'Q_RES_0402LF-33,5%,1/16W,CHIP,CS03302JB29':;

SECTION_NUMBER 1
 '@T6G_MB_LIB.T6G(SCH_1):PAGE273_I335@PURE_QUANTA.Q_RES(CHIPS)':
 C_PATH='@t6g_mb_lib.t6g(sch_1):page273_i335@pure_quanta.q_res(chips)';

PART_NAME
 R3544 'Q_RES_0402LF-33,5%,1/16W,CHIP,CS03302JB29':;

SECTION_NUMBER 1
 '@T6G_MB_LIB.T6G(SCH_1):PAGE273_I336@PURE_QUANTA.Q_RES(CHIPS)':
 C_PATH='@t6g_mb_lib.t6g(sch_1):page273_i336@pure_quanta.q_res(chips)';

PART_NAME
 R2846 'Q_RES_0402LF-4.7K,5%,1/16W,CHIP,TMP_QCS24702JB38':;

SECTION_NUMBER 1
 '@T6G_MB_LIB.T6G(SCH_1):PAGE273_I315@PURE_QUANTA.Q_RES(CHIPS)':
 C_PATH='@t6g_mb_lib.t6g(sch_1):page273_i315@pure_quanta.q_res(chips)';

PART_NAME
 R2845 'Q_RES_0402LF-4.7K,5%,1/16W,CHIP,TMP_QCS24702JB38':;

SECTION_NUMBER 1
 '@T6G_MB_LIB.T6G(SCH_1):PAGE273_I316@PURE_QUANTA.Q_RES(CHIPS)':
 C_PATH='@t6g_mb_lib.t6g(sch_1):page273_i316@pure_quanta.q_res(chips)';

PART_NAME
 R2844 'Q_RES_0402LF-4.7K,5%,1/16W,CHIP,TMP_QCS24702JB38':;

SECTION_NUMBER 1
 '@T6G_MB_LIB.T6G(SCH_1):PAGE273_I318@PURE_QUANTA.Q_RES(CHIPS)':
 C_PATH='@t6g_mb_lib.t6g(sch_1):page273_i318@pure_quanta.q_res(chips)';

PART_NAME
 R2843 'Q_RES_0402LF-4.7K,5%,1/16W,CHIP,TMP_QCS24702JB38':;

SECTION_NUMBER 1
 '@T6G_MB_LIB.T6G(SCH_1):PAGE273_I317@PURE_QUANTA.Q_RES(CHIPS)':
 C_PATH='@t6g_mb_lib.t6g(sch_1):page273_i317@pure_quanta.q_res(chips)';

PART_NAME
 R2842 'Q_RES_0402LF-4.7K,5%,1/16W,CHIP,TMP_QCS24702JB38':;

SECTION_NUMBER 1
 '@T6G_MB_LIB.T6G(SCH_1):PAGE273_I319@PURE_QUANTA.Q_RES(CHIPS)':
 C_PATH='@t6g_mb_lib.t6g(sch_1):page273_i319@pure_quanta.q_res(chips)';

PART_NAME
 R2841 'Q_RES_0402LF-4.7K,5%,1/16W,CHIP,TMP_QCS24702JB38':;

SECTION_NUMBER 1
 '@T6G_MB_LIB.T6G(SCH_1):PAGE273_I321@PURE_QUANTA.Q_RES(CHIPS)':
 C_PATH='@t6g_mb_lib.t6g(sch_1):page273_i321@pure_quanta.q_res(chips)';

PART_NAME
 R2840 'Q_RES_0402LF-4.7K,5%,1/16W,CHIP,TMP_QCS24702JB38':;

SECTION_NUMBER 1
 '@T6G_MB_LIB.T6G(SCH_1):PAGE273_I322@PURE_QUANTA.Q_RES(CHIPS)':
 C_PATH='@t6g_mb_lib.t6g(sch_1):page273_i322@pure_quanta.q_res(chips)';

PART_NAME
 R2833 'Q_RES_0402LF-4.7K,5%,1/16W,CHIP,TMP_QCS24702JB38':;

SECTION_NUMBER 1
 '@T6G_MB_LIB.T6G(SCH_1):PAGE273_I323@PURE_QUANTA.Q_RES(CHIPS)':
 C_PATH='@t6g_mb_lib.t6g(sch_1):page273_i323@pure_quanta.q_res(chips)';

PART_NAME
 R2830 'Q_RES_0402LF-4.7K,5%,1/16W,CHIP,TMP_QCS24702JB38':;

SECTION_NUMBER 1
 '@T6G_MB_LIB.T6G(SCH_1):PAGE273_I324@PURE_QUANTA.Q_RES(CHIPS)':
 C_PATH='@t6g_mb_lib.t6g(sch_1):page273_i324@pure_quanta.q_res(chips)';

PART_NAME
 R2829 'Q_RES_0402LF-33,5%,1/16W,CHIP,CS03302JB29':;

SECTION_NUMBER 1
 '@T6G_MB_LIB.T6G(SCH_1):PAGE273_I278@PURE_QUANTA.Q_RES(CHIPS)':
 C_PATH='@t6g_mb_lib.t6g(sch_1):page273_i278@pure_quanta.q_res(chips)';

PART_NAME
 R2828 'Q_RES_0402LF-33,5%,1/16W,CHIP,CS03302JB29':;

SECTION_NUMBER 1
 '@T6G_MB_LIB.T6G(SCH_1):PAGE273_I277@PURE_QUANTA.Q_RES(CHIPS)':
 C_PATH='@t6g_mb_lib.t6g(sch_1):page273_i277@pure_quanta.q_res(chips)';

PART_NAME
 R2827 'Q_RES_0402LF-33,5%,1/16W,CHIP,CS03302JB29':;

SECTION_NUMBER 1
 '@T6G_MB_LIB.T6G(SCH_1):PAGE273_I279@PURE_QUANTA.Q_RES(CHIPS)':
 C_PATH='@t6g_mb_lib.t6g(sch_1):page273_i279@pure_quanta.q_res(chips)';

PART_NAME
 R2826 'Q_RES_0402LF-33,5%,1/16W,CHIP,CS03302JB29':;

SECTION_NUMBER 1
 '@T6G_MB_LIB.T6G(SCH_1):PAGE273_I280@PURE_QUANTA.Q_RES(CHIPS)':
 C_PATH='@t6g_mb_lib.t6g(sch_1):page273_i280@pure_quanta.q_res(chips)';

PART_NAME
 R2825 'Q_RES_0402LF-33,5%,1/16W,CHIP,CS03302JB29':;

SECTION_NUMBER 1
 '@T6G_MB_LIB.T6G(SCH_1):PAGE273_I281@PURE_QUANTA.Q_RES(CHIPS)':
 C_PATH='@t6g_mb_lib.t6g(sch_1):page273_i281@pure_quanta.q_res(chips)';

PART_NAME
 R2824 'Q_RES_0402LF-33,5%,1/16W,CHIP,CS03302JB29':;

SECTION_NUMBER 1
 '@T6G_MB_LIB.T6G(SCH_1):PAGE273_I282@PURE_QUANTA.Q_RES(CHIPS)':
 C_PATH='@t6g_mb_lib.t6g(sch_1):page273_i282@pure_quanta.q_res(chips)';

PART_NAME
 R2823 'Q_RES_0402LF-33,5%,1/16W,CHIP,CS03302JB29':;

SECTION_NUMBER 1
 '@T6G_MB_LIB.T6G(SCH_1):PAGE273_I283@PURE_QUANTA.Q_RES(CHIPS)':
 C_PATH='@t6g_mb_lib.t6g(sch_1):page273_i283@pure_quanta.q_res(chips)';

PART_NAME
 R2822 'Q_RES_0402LF-33,5%,1/16W,CHIP,CS03302JB29':;

SECTION_NUMBER 1
 '@T6G_MB_LIB.T6G(SCH_1):PAGE273_I284@PURE_QUANTA.Q_RES(CHIPS)':
 C_PATH='@t6g_mb_lib.t6g(sch_1):page273_i284@pure_quanta.q_res(chips)';

PART_NAME
 R2821 'Q_RES_0402LF-33,5%,1/16W,CHIP,CS03302JB29':;

SECTION_NUMBER 1
 '@T6G_MB_LIB.T6G(SCH_1):PAGE273_I234@PURE_QUANTA.Q_RES(CHIPS)':
 C_PATH='@t6g_mb_lib.t6g(sch_1):page273_i234@pure_quanta.q_res(chips)';

PART_NAME
 R2820 'Q_RES_0402LF-33,5%,1/16W,CHIP,CS03302JB29':;

SECTION_NUMBER 1
 '@T6G_MB_LIB.T6G(SCH_1):PAGE273_I235@PURE_QUANTA.Q_RES(CHIPS)':
 C_PATH='@t6g_mb_lib.t6g(sch_1):page273_i235@pure_quanta.q_res(chips)';

PART_NAME
 R2819 'Q_RES_0402LF-33,5%,1/16W,EMPTY,CS03302JB29':;

SECTION_NUMBER 1
 '@T6G_MB_LIB.T6G(SCH_1):PAGE273_I239@PURE_QUANTA.Q_RES(CHIPS)':
 C_PATH='@t6g_mb_lib.t6g(sch_1):page273_i239@pure_quanta.q_res(chips)';

PART_NAME
 R2818 'Q_RES_0402LF-33,5%,1/16W,EMPTY,CS03302JB29':;

SECTION_NUMBER 1
 '@T6G_MB_LIB.T6G(SCH_1):PAGE273_I238@PURE_QUANTA.Q_RES(CHIPS)':
 C_PATH='@t6g_mb_lib.t6g(sch_1):page273_i238@pure_quanta.q_res(chips)';

PART_NAME
 R2786 'Q_RES_0402LF-33,5%,1/16W,CHIP,CS03302JB29':;

SECTION_NUMBER 1
 '@T6G_MB_LIB.T6G(SCH_1):PAGE273_I246@PURE_QUANTA.Q_RES(CHIPS)':
 C_PATH='@t6g_mb_lib.t6g(sch_1):page273_i246@pure_quanta.q_res(chips)';

PART_NAME
 R2785 'Q_RES_0402LF-33,5%,1/16W,CHIP,CS03302JB29':;

SECTION_NUMBER 1
 '@T6G_MB_LIB.T6G(SCH_1):PAGE273_I252@PURE_QUANTA.Q_RES(CHIPS)':
 C_PATH='@t6g_mb_lib.t6g(sch_1):page273_i252@pure_quanta.q_res(chips)';

PART_NAME
 R2784 'Q_RES_0402LF-33,5%,1/16W,CHIP,CS03302JB29':;

SECTION_NUMBER 1
 '@T6G_MB_LIB.T6G(SCH_1):PAGE273_I328@PURE_QUANTA.Q_RES(CHIPS)':
 C_PATH='@t6g_mb_lib.t6g(sch_1):page273_i328@pure_quanta.q_res(chips)';

PART_NAME
 R2782 'Q_RES_0402LF-33,5%,1/16W,CHIP,CS03302JB29':;

SECTION_NUMBER 1
 '@T6G_MB_LIB.T6G(SCH_1):PAGE273_I254@PURE_QUANTA.Q_RES(CHIPS)':
 C_PATH='@t6g_mb_lib.t6g(sch_1):page273_i254@pure_quanta.q_res(chips)';

PART_NAME
 R2781 'Q_RES_0402LF-33,5%,1/16W,CHIP,CS03302JB29':;

SECTION_NUMBER 1
 '@T6G_MB_LIB.T6G(SCH_1):PAGE273_I253@PURE_QUANTA.Q_RES(CHIPS)':
 C_PATH='@t6g_mb_lib.t6g(sch_1):page273_i253@pure_quanta.q_res(chips)';

PART_NAME
 R1762 'Q_RES_0402LF-33,5%,1/16W,CHIP,CS03302JB29':;

SECTION_NUMBER 1
 '@T6G_MB_LIB.T6G(SCH_1):PAGE273_I227@PURE_QUANTA.Q_RES(CHIPS)':
 C_PATH='@t6g_mb_lib.t6g(sch_1):page273_i227@pure_quanta.q_res(chips)';

PART_NAME
 R1761 'Q_RES_0402LF-33,5%,1/16W,CHIP,CS03302JB29':;

SECTION_NUMBER 1
 '@T6G_MB_LIB.T6G(SCH_1):PAGE273_I226@PURE_QUANTA.Q_RES(CHIPS)':
 C_PATH='@t6g_mb_lib.t6g(sch_1):page273_i226@pure_quanta.q_res(chips)';

PART_NAME
 R1731 'Q_RES_0402LF-4.7K,5%,1/16W,CHIP,TMP_QCS24702JB38':;

SECTION_NUMBER 1
 '@T6G_MB_LIB.T6G(SCH_1):PAGE273_I320@PURE_QUANTA.Q_RES(CHIPS)':
 C_PATH='@t6g_mb_lib.t6g(sch_1):page273_i320@pure_quanta.q_res(chips)';

PART_NAME
 R1730 'Q_RES_0402LF-33,5%,1/16W,CHIP,CS03302JB29':;

SECTION_NUMBER 1
 '@T6G_MB_LIB.T6G(SCH_1):PAGE273_I236@PURE_QUANTA.Q_RES(CHIPS)':
 C_PATH='@t6g_mb_lib.t6g(sch_1):page273_i236@pure_quanta.q_res(chips)';

PART_NAME
 R1670 'Q_RES_0402LF-33,5%,1/16W,CHIP,CS03302JB29':;

SECTION_NUMBER 1
 '@T6G_MB_LIB.T6G(SCH_1):PAGE273_I237@PURE_QUANTA.Q_RES(CHIPS)':
 C_PATH='@t6g_mb_lib.t6g(sch_1):page273_i237@pure_quanta.q_res(chips)';

PART_NAME
 R1669 'Q_RES_0402LF-33,5%,1/16W,CHIP,CS03302JB29':;

SECTION_NUMBER 1
 '@T6G_MB_LIB.T6G(SCH_1):PAGE273_I230@PURE_QUANTA.Q_RES(CHIPS)':
 C_PATH='@t6g_mb_lib.t6g(sch_1):page273_i230@pure_quanta.q_res(chips)';

PART_NAME
 R1668 'Q_RES_0402LF-33,5%,1/16W,CHIP,CS03302JB29':;

SECTION_NUMBER 1
 '@T6G_MB_LIB.T6G(SCH_1):PAGE273_I231@PURE_QUANTA.Q_RES(CHIPS)':
 C_PATH='@t6g_mb_lib.t6g(sch_1):page273_i231@pure_quanta.q_res(chips)';

PART_NAME
 R1664 'Q_RES_0402LF-33,5%,1/16W,CHIP,CS03302JB29':;

SECTION_NUMBER 1
 '@T6G_MB_LIB.T6G(SCH_1):PAGE273_I229@PURE_QUANTA.Q_RES(CHIPS)':
 C_PATH='@t6g_mb_lib.t6g(sch_1):page273_i229@pure_quanta.q_res(chips)';

PART_NAME
 R1663 'Q_RES_0402LF-33,5%,1/16W,CHIP,CS03302JB29':;

SECTION_NUMBER 1
 '@T6G_MB_LIB.T6G(SCH_1):PAGE273_I228@PURE_QUANTA.Q_RES(CHIPS)':
 C_PATH='@t6g_mb_lib.t6g(sch_1):page273_i228@pure_quanta.q_res(chips)';

PART_NAME
 R1662 'Q_RES_0402LF-33,5%,1/16W,EMPTY,CS03302JB29':;

SECTION_NUMBER 1
 '@T6G_MB_LIB.T6G(SCH_1):PAGE273_I232@PURE_QUANTA.Q_RES(CHIPS)':
 C_PATH='@t6g_mb_lib.t6g(sch_1):page273_i232@pure_quanta.q_res(chips)';

PART_NAME
 R1661 'Q_RES_0402LF-33,5%,1/16W,EMPTY,CS03302JB29':;

SECTION_NUMBER 1
 '@T6G_MB_LIB.T6G(SCH_1):PAGE273_I233@PURE_QUANTA.Q_RES(CHIPS)':
 C_PATH='@t6g_mb_lib.t6g(sch_1):page273_i233@pure_quanta.q_res(chips)';

PART_NAME
 R1526 'Q_RES_0402LF-33,5%,1/16W,CHIP,CS03302JB29':;

SECTION_NUMBER 1
 '@T6G_MB_LIB.T6G(SCH_1):PAGE273_I251@PURE_QUANTA.Q_RES(CHIPS)':
 C_PATH='@t6g_mb_lib.t6g(sch_1):page273_i251@pure_quanta.q_res(chips)';

PART_NAME
 R1525 'Q_RES_0402LF-0,5%,1/16W,CHIP,CS00002JB38':;

SECTION_NUMBER 1
 '@T6G_MB_LIB.T6G(SCH_1):PAGE273_I250@PURE_QUANTA.Q_RES(CHIPS)':
 C_PATH='@t6g_mb_lib.t6g(sch_1):page273_i250@pure_quanta.q_res(chips)';

PART_NAME
 R1321 'Q_RES_0402LF-4.7K,5%,1/16W,CHIP,TMP_QCS24702JB38':;

SECTION_NUMBER 1
 '@T6G_MB_LIB.T6G(SCH_1):PAGE273_I325@PURE_QUANTA.Q_RES(CHIPS)':
 C_PATH='@t6g_mb_lib.t6g(sch_1):page273_i325@pure_quanta.q_res(chips)';

PART_NAME
 R1319 'Q_RES_0402LF-4.7K,5%,1/16W,CHIP,TMP_QCS24702JB38':;

SECTION_NUMBER 1
 '@T6G_MB_LIB.T6G(SCH_1):PAGE273_I326@PURE_QUANTA.Q_RES(CHIPS)':
 C_PATH='@t6g_mb_lib.t6g(sch_1):page273_i326@pure_quanta.q_res(chips)';

PART_NAME
 R582 'Q_RES_0402LF-33,5%,1/16W,CHIP,CS03302JB29':;

SECTION_NUMBER 1
 '@T6G_MB_LIB.T6G(SCH_1):PAGE273_I247@PURE_QUANTA.Q_RES(CHIPS)':
 C_PATH='@t6g_mb_lib.t6g(sch_1):page273_i247@pure_quanta.q_res(chips)';

PART_NAME
 R108 'Q_RES_0402LF-0,5%,1/16W,CHIP,CS00002JB38':;

SECTION_NUMBER 1
 '@T6G_MB_LIB.T6G(SCH_1):PAGE273_I249@PURE_QUANTA.Q_RES(CHIPS)':
 C_PATH='@t6g_mb_lib.t6g(sch_1):page273_i249@pure_quanta.q_res(chips)';

PART_NAME
 R107 'Q_RES_0402LF-0,5%,1/16W,CHIP,CS00002JB38':;

SECTION_NUMBER 1
 '@T6G_MB_LIB.T6G(SCH_1):PAGE273_I248@PURE_QUANTA.Q_RES(CHIPS)':
 C_PATH='@t6g_mb_lib.t6g(sch_1):page273_i248@pure_quanta.q_res(chips)';

PART_NAME
 JP29 'CONN3_210HP1030BR1-CONN3_210-HP1-030BR1,THLF,IO,DFHD03MS213':;

SECTION_NUMBER 1
 '@T6G_MB_LIB.T6G(SCH_1):PAGE273_I333@PURE_QUANTA.CONN3_210HP1030BR1(CHIPS)':
 C_PATH='@t6g_mb_lib.t6g(sch_1):page273_i333@pure_quanta.conn3_210hp1030br1(chip~
s)';

PART_NAME
 R3740 'Q_RES_0402LF-4.7K,5%,1/16W,CHIP,TMP_QCS24702JB38':;

SECTION_NUMBER 1
 '@T6G_MB_LIB.T6G(SCH_1):PAGE99_I130@PURE_QUANTA.Q_RES(CHIPS)':
 C_PATH='@t6g_mb_lib.t6g(sch_1):page99_i130@pure_quanta.q_res(chips)';

PART_NAME
 R3739 'Q_RES_0402LF-4.7K,5%,1/16W,CHIP,TMP_QCS24702JB38':;

SECTION_NUMBER 1
 '@T6G_MB_LIB.T6G(SCH_1):PAGE99_I128@PURE_QUANTA.Q_RES(CHIPS)':
 C_PATH='@t6g_mb_lib.t6g(sch_1):page99_i128@pure_quanta.q_res(chips)';

PART_NAME
 R3548 'Q_RES_0402LF-4.7K,5%,1/16W,CHIP,TMP_QCS24702JB38':;

SECTION_NUMBER 1
 '@T6G_MB_LIB.T6G(SCH_1):PAGE99_I116@PURE_QUANTA.Q_RES(CHIPS)':
 C_PATH='@t6g_mb_lib.t6g(sch_1):page99_i116@pure_quanta.q_res(chips)';

PART_NAME
 R1007 'Q_RES_0402LF-4.7K,5%,1/16W,CHIP,TMP_QCS24702JB38':;

SECTION_NUMBER 1
 '@T6G_MB_LIB.T6G(SCH_1):PAGE99_I28@PURE_QUANTA.Q_RES(CHIPS)':
 C_PATH='@t6g_mb_lib.t6g(sch_1):page99_i28@pure_quanta.q_res(chips)';

PART_NAME
 R1006 'Q_RES_0402LF-4.7K,5%,1/16W,CHIP,TMP_QCS24702JB38':;

SECTION_NUMBER 1
 '@T6G_MB_LIB.T6G(SCH_1):PAGE99_I7@PURE_QUANTA.Q_RES(CHIPS)':
 C_PATH='@t6g_mb_lib.t6g(sch_1):page99_i7@pure_quanta.q_res(chips)';

PART_NAME
 R1005 'Q_RES_0402LF-10K,1%,1/16W,EMPTY,TMP_QCS31002FB26':;

SECTION_NUMBER 1
 '@T6G_MB_LIB.T6G(SCH_1):PAGE99_I20@PURE_QUANTA.Q_RES(CHIPS)':
 C_PATH='@t6g_mb_lib.t6g(sch_1):page99_i20@pure_quanta.q_res(chips)';

PART_NAME
 R1004 'Q_RES_0402LF-1K,1%,1/16W,CHIP,TMP_QCS21002FB24':;

SECTION_NUMBER 1
 '@T6G_MB_LIB.T6G(SCH_1):PAGE99_I19@PURE_QUANTA.Q_RES(CHIPS)':
 C_PATH='@t6g_mb_lib.t6g(sch_1):page99_i19@pure_quanta.q_res(chips)';

PART_NAME
 R1003 'Q_RES_0402LF-4.7K,5%,1/16W,CHIP,TMP_QCS24702JB38':;

SECTION_NUMBER 1
 '@T6G_MB_LIB.T6G(SCH_1):PAGE99_I32@PURE_QUANTA.Q_RES(CHIPS)':
 C_PATH='@t6g_mb_lib.t6g(sch_1):page99_i32@pure_quanta.q_res(chips)';

PART_NAME
 R1002 'Q_RES_0402LF-4.7K,5%,1/16W,CHIP,TMP_QCS24702JB38':;

SECTION_NUMBER 1
 '@T6G_MB_LIB.T6G(SCH_1):PAGE99_I23@PURE_QUANTA.Q_RES(CHIPS)':
 C_PATH='@t6g_mb_lib.t6g(sch_1):page99_i23@pure_quanta.q_res(chips)';

PART_NAME
 R1001 'Q_RES_0402LF-4.7K,5%,1/16W,CHIP,TMP_QCS24702JB38':;

SECTION_NUMBER 1
 '@T6G_MB_LIB.T6G(SCH_1):PAGE99_I59@PURE_QUANTA.Q_RES(CHIPS)':
 C_PATH='@t6g_mb_lib.t6g(sch_1):page99_i59@pure_quanta.q_res(chips)';

PART_NAME
 R1000 'Q_RES_0402LF-4.7K,5%,1/16W,CHIP,TMP_QCS24702JB38':;

SECTION_NUMBER 1
 '@T6G_MB_LIB.T6G(SCH_1):PAGE99_I48@PURE_QUANTA.Q_RES(CHIPS)':
 C_PATH='@t6g_mb_lib.t6g(sch_1):page99_i48@pure_quanta.q_res(chips)';

PART_NAME
 R999 'Q_RES_0402LF-0,5%,1/16W,CHIP,CS00002JB38':;

SECTION_NUMBER 1
 '@T6G_MB_LIB.T6G(SCH_1):PAGE99_I62@PURE_QUANTA.Q_RES(CHIPS)':
 C_PATH='@t6g_mb_lib.t6g(sch_1):page99_i62@pure_quanta.q_res(chips)';

PART_NAME
 R998 'Q_RES_0402LF-0,5%,1/16W,CHIP,CS00002JB38':;

SECTION_NUMBER 1
 '@T6G_MB_LIB.T6G(SCH_1):PAGE99_I57@PURE_QUANTA.Q_RES(CHIPS)':
 C_PATH='@t6g_mb_lib.t6g(sch_1):page99_i57@pure_quanta.q_res(chips)';

PART_NAME
 R997 'Q_RES_0402LF-10K,1%,1/16W,EMPTY,TMP_QCS31002FB26':;

SECTION_NUMBER 1
 '@T6G_MB_LIB.T6G(SCH_1):PAGE99_I111@PURE_QUANTA.Q_RES(CHIPS)':
 C_PATH='@t6g_mb_lib.t6g(sch_1):page99_i111@pure_quanta.q_res(chips)';

PART_NAME
 R650 'Q_RES_0402LF-1K,1%,1/16W,CHIP,TMP_QCS21002FB24':;

SECTION_NUMBER 1
 '@T6G_MB_LIB.T6G(SCH_1):PAGE99_I110@PURE_QUANTA.Q_RES(CHIPS)':
 C_PATH='@t6g_mb_lib.t6g(sch_1):page99_i110@pure_quanta.q_res(chips)';

PART_NAME
 R630 'Q_RES_0402LF-10K,1%,1/16W,EMPTY,TMP_QCS31002FB26':;

SECTION_NUMBER 1
 '@T6G_MB_LIB.T6G(SCH_1):PAGE99_I12@PURE_QUANTA.Q_RES(CHIPS)':
 C_PATH='@t6g_mb_lib.t6g(sch_1):page99_i12@pure_quanta.q_res(chips)';

PART_NAME
 R629 'Q_RES_0402LF-1K,1%,1/16W,CHIP,TMP_QCS21002FB24':;

SECTION_NUMBER 1
 '@T6G_MB_LIB.T6G(SCH_1):PAGE99_I8@PURE_QUANTA.Q_RES(CHIPS)':
 C_PATH='@t6g_mb_lib.t6g(sch_1):page99_i8@pure_quanta.q_res(chips)';

PART_NAME
 R628 'Q_RES_0402LF-10K,1%,1/16W,CHIP,TMP_QCS31002FB26':;

SECTION_NUMBER 1
 '@T6G_MB_LIB.T6G(SCH_1):PAGE99_I14@PURE_QUANTA.Q_RES(CHIPS)':
 C_PATH='@t6g_mb_lib.t6g(sch_1):page99_i14@pure_quanta.q_res(chips)';

PART_NAME
 R627 'Q_RES_0402LF-1K,1%,1/16W,EMPTY,TMP_QCS21002FB24':;

SECTION_NUMBER 1
 '@T6G_MB_LIB.T6G(SCH_1):PAGE99_I10@PURE_QUANTA.Q_RES(CHIPS)':
 C_PATH='@t6g_mb_lib.t6g(sch_1):page99_i10@pure_quanta.q_res(chips)';

PART_NAME
 R626 'Q_RES_0402LF-10K,1%,1/16W,CHIP,TMP_QCS31002FB26':;

SECTION_NUMBER 1
 '@T6G_MB_LIB.T6G(SCH_1):PAGE99_I16@PURE_QUANTA.Q_RES(CHIPS)':
 C_PATH='@t6g_mb_lib.t6g(sch_1):page99_i16@pure_quanta.q_res(chips)';

PART_NAME
 R625 'Q_RES_0402LF-1K,1%,1/16W,EMPTY,TMP_QCS21002FB24':;

SECTION_NUMBER 1
 '@T6G_MB_LIB.T6G(SCH_1):PAGE99_I11@PURE_QUANTA.Q_RES(CHIPS)':
 C_PATH='@t6g_mb_lib.t6g(sch_1):page99_i11@pure_quanta.q_res(chips)';

PART_NAME
 R515 'Q_RES_0402LF-10K,1%,1/16W,CHIP,TMP_QCS31002FB26':;

SECTION_NUMBER 1
 '@T6G_MB_LIB.T6G(SCH_1):PAGE99_I42@PURE_QUANTA.Q_RES(CHIPS)':
 C_PATH='@t6g_mb_lib.t6g(sch_1):page99_i42@pure_quanta.q_res(chips)';

PART_NAME
 R335 'Q_RES_0402LF-1K,1%,1/16W,EMPTY,TMP_QCS21002FB24':;

SECTION_NUMBER 1
 '@T6G_MB_LIB.T6G(SCH_1):PAGE99_I40@PURE_QUANTA.Q_RES(CHIPS)':
 C_PATH='@t6g_mb_lib.t6g(sch_1):page99_i40@pure_quanta.q_res(chips)';

PART_NAME
 R334 'Q_RES_0402LF-10K,1%,1/16W,CHIP,TMP_QCS31002FB26':;

SECTION_NUMBER 1
 '@T6G_MB_LIB.T6G(SCH_1):PAGE99_I44@PURE_QUANTA.Q_RES(CHIPS)':
 C_PATH='@t6g_mb_lib.t6g(sch_1):page99_i44@pure_quanta.q_res(chips)';

PART_NAME
 R333 'Q_RES_0402LF-1K,1%,1/16W,EMPTY,TMP_QCS21002FB24':;

SECTION_NUMBER 1
 '@T6G_MB_LIB.T6G(SCH_1):PAGE99_I41@PURE_QUANTA.Q_RES(CHIPS)':
 C_PATH='@t6g_mb_lib.t6g(sch_1):page99_i41@pure_quanta.q_res(chips)';

PART_NAME
 R332 'Q_RES_0402LF-10K,1%,1/16W,CHIP,TMP_QCS31002FB26':;

SECTION_NUMBER 1
 '@T6G_MB_LIB.T6G(SCH_1):PAGE99_I51@PURE_QUANTA.Q_RES(CHIPS)':
 C_PATH='@t6g_mb_lib.t6g(sch_1):page99_i51@pure_quanta.q_res(chips)';

PART_NAME
 R331 'Q_RES_0402LF-1K,1%,1/16W,EMPTY,TMP_QCS21002FB24':;

SECTION_NUMBER 1
 '@T6G_MB_LIB.T6G(SCH_1):PAGE99_I50@PURE_QUANTA.Q_RES(CHIPS)':
 C_PATH='@t6g_mb_lib.t6g(sch_1):page99_i50@pure_quanta.q_res(chips)';

PART_NAME
 Q232 'MOSFET_NCH_DUAL-2N7002KDW,SMLF,IC,BAM70020047':;

SECTION_NUMBER 1
 '@T6G_MB_LIB.T6G(SCH_1):PAGE99_I125@PURE_QUANTA.MOSFET_NCH_DUAL(CHIPS)':
 C_PATH='@t6g_mb_lib.t6g(sch_1):page99_i125@pure_quanta.mosfet_nch_dual(chips)';

SECTION_NUMBER 2
 '@T6G_MB_LIB.T6G(SCH_1):PAGE99_I122@PURE_QUANTA.MOSFET_NCH_DUAL(CHIPS)':
 C_PATH='@t6g_mb_lib.t6g(sch_1):page99_i122@pure_quanta.mosfet_nch_dual(chips)';

PART_NAME
 Q23 'MOSFET_NCH_DUAL-2N7002KDW,SMLF,IC,BAM70020047':;

SECTION_NUMBER 1
 '@T6G_MB_LIB.T6G(SCH_1):PAGE99_I113@PURE_QUANTA.MOSFET_NCH_DUAL(CHIPS)':
 C_PATH='@t6g_mb_lib.t6g(sch_1):page99_i113@pure_quanta.mosfet_nch_dual(chips)';

SECTION_NUMBER 2
 '@T6G_MB_LIB.T6G(SCH_1):PAGE99_I120@PURE_QUANTA.MOSFET_NCH_DUAL(CHIPS)':
 C_PATH='@t6g_mb_lib.t6g(sch_1):page99_i120@pure_quanta.mosfet_nch_dual(chips)';

PART_NAME
 Q22 'MOSFET_NCH_DUAL-2N7002KDW,SMLF,IC,BAM70020047':;

SECTION_NUMBER 1
 '@T6G_MB_LIB.T6G(SCH_1):PAGE99_I36@PURE_QUANTA.MOSFET_NCH_DUAL(CHIPS)':
 C_PATH='@t6g_mb_lib.t6g(sch_1):page99_i36@pure_quanta.mosfet_nch_dual(chips)';

SECTION_NUMBER 2
 '@T6G_MB_LIB.T6G(SCH_1):PAGE99_I33@PURE_QUANTA.MOSFET_NCH_DUAL(CHIPS)':
 C_PATH='@t6g_mb_lib.t6g(sch_1):page99_i33@pure_quanta.mosfet_nch_dual(chips)';

PART_NAME
 Q21 'MOSFET_NCH_DUAL-2N7002KDW,SMLF,IC,BAM70020047':;

SECTION_NUMBER 1
 '@T6G_MB_LIB.T6G(SCH_1):PAGE99_I35@PURE_QUANTA.MOSFET_NCH_DUAL(CHIPS)':
 C_PATH='@t6g_mb_lib.t6g(sch_1):page99_i35@pure_quanta.mosfet_nch_dual(chips)';

SECTION_NUMBER 2
 '@T6G_MB_LIB.T6G(SCH_1):PAGE99_I25@PURE_QUANTA.MOSFET_NCH_DUAL(CHIPS)':
 C_PATH='@t6g_mb_lib.t6g(sch_1):page99_i25@pure_quanta.mosfet_nch_dual(chips)';

PART_NAME
 JP7 'CONN3_210HP1030BR1-CONN3_210-HP1-030BR1,THLF,IO,DFHD03MS213':;

SECTION_NUMBER 1
 '@T6G_MB_LIB.T6G(SCH_1):PAGE99_I66@PURE_QUANTA.CONN3_210HP1030BR1(CHIPS)':
 C_PATH='@s6q_mb_lib.s6q(sch_1):page99_i66@pure_quanta.conn3_210hp1030br1(chips)~
';

PART_NAME
 J206 'SCONN56_G64V31312HR-SCONN56_G64V31312HR,SMLF,IO,DFHS56FS029':;

SECTION_NUMBER 1
 '@T6G_MB_LIB.T6G(SCH_1):PAGE171_I90@PURE_QUANTA.SCONN56_G64V31312HR(CHIPS)':
 C_PATH='@t6g_mb_lib.t6g(sch_1):page171_i90@pure_quanta.sconn56_g64v31312hr(chip~
s)';

PART_NAME
 J205 'SCONN56_G64V31312HR-SCONN56_G64V31312HR,SMLF,IO,DFHS56FS029':;

SECTION_NUMBER 1
 '@T6G_MB_LIB.T6G(SCH_1):PAGE170_I47@PURE_QUANTA.SCONN56_G64V31312HR(CHIPS)':
 C_PATH='@t6g_mb_lib.t6g(sch_1):page170_i47@pure_quanta.sconn56_g64v31312hr(chip~
s)';

PART_NAME
 J204 'SCONN56_G64V31312HR-SCONN56_G64V31312HR,SMLF,IO,DFHS56FS029':;

SECTION_NUMBER 1
 '@T6G_MB_LIB.T6G(SCH_1):PAGE167_I15@PURE_QUANTA.SCONN56_G64V31312HR(CHIPS)':
 C_PATH='@t6g_mb_lib.t6g(sch_1):page167_i15@pure_quanta.sconn56_g64v31312hr(chip~
s)';

PART_NAME
 J203 'SCONN56_G64V31312HR-SCONN56_G64V31312HR,SMLF,IO,DFHS56FS029':;

SECTION_NUMBER 1
 '@T6G_MB_LIB.T6G(SCH_1):PAGE166_I45@PURE_QUANTA.SCONN56_G64V31312HR(CHIPS)':
 C_PATH='@t6g_mb_lib.t6g(sch_1):page166_i45@pure_quanta.sconn56_g64v31312hr(chip~
s)';

PART_NAME
 J202 'SCONN56_G64V31312HR-SCONN56_G64V31312HR,SMLF,IO,DFHS56FS029':;

SECTION_NUMBER 1
 '@T6G_MB_LIB.T6G(SCH_1):PAGE163_I90@PURE_QUANTA.SCONN56_G64V31312HR(CHIPS)':
 C_PATH='@t6g_mb_lib.t6g(sch_1):page163_i90@pure_quanta.sconn56_g64v31312hr(chip~
s)';

PART_NAME
 J201 'SCONN56_G64V31312HR-SCONN56_G64V31312HR,SMLF,IO,DFHS56FS029':;

SECTION_NUMBER 1
 '@T6G_MB_LIB.T6G(SCH_1):PAGE162_I45@PURE_QUANTA.SCONN56_G64V31312HR(CHIPS)':
 C_PATH='@t6g_mb_lib.t6g(sch_1):page162_i45@pure_quanta.sconn56_g64v31312hr(chip~
s)';

PART_NAME
 J200 'SCONN56_G64V31312HR-SCONN56_G64V31312HR,SMLF,IO,DFHS56FS029':;

SECTION_NUMBER 1
 '@T6G_MB_LIB.T6G(SCH_1):PAGE159_I45@PURE_QUANTA.SCONN56_G64V31312HR(CHIPS)':
 C_PATH='@t6g_mb_lib.t6g(sch_1):page159_i45@pure_quanta.sconn56_g64v31312hr(chip~
s)';

PART_NAME
 J199 'SCONN56_G64V31312HR-SCONN56_G64V31312HR,SMLF,IO,DFHS56FS029':;

SECTION_NUMBER 1
 '@T6G_MB_LIB.T6G(SCH_1):PAGE158_I68@PURE_QUANTA.SCONN56_G64V31312HR(CHIPS)':
 C_PATH='@t6g_mb_lib.t6g(sch_1):page158_i68@pure_quanta.sconn56_g64v31312hr(chip~
s)';

PART_NAME
 J287 'DELTA_L-DELTA-L,THLF,EMPTY,TP24':;

SECTION_NUMBER 1
 '@T6G_MB_LIB.T6G(SCH_1):PAGE334_I38@PURE_QUANTA.DELTA_L(CHIPS)':
 C_PATH='@t6g_mb_lib.t6g(sch_1):page334_i38@pure_quanta.delta_l(chips)';

PART_NAME
 J286 'DELTA_L-DELTA-L,THLF,EMPTY,TP24':;

SECTION_NUMBER 1
 '@T6G_MB_LIB.T6G(SCH_1):PAGE334_I45@PURE_QUANTA.DELTA_L(CHIPS)':
 C_PATH='@t6g_mb_lib.t6g(sch_1):page334_i45@pure_quanta.delta_l(chips)';

PART_NAME
 J285 'DELTA_L-DELTA-L,THLF,EMPTY,TP24':;

SECTION_NUMBER 1
 '@T6G_MB_LIB.T6G(SCH_1):PAGE334_I46@PURE_QUANTA.DELTA_L(CHIPS)':
 C_PATH='@t6g_mb_lib.t6g(sch_1):page334_i46@pure_quanta.delta_l(chips)';

PART_NAME
 J284 'DELTA_L-DELTA-L,THLF,EMPTY,TP24':;

SECTION_NUMBER 1
 '@T6G_MB_LIB.T6G(SCH_1):PAGE334_I31@PURE_QUANTA.DELTA_L(CHIPS)':
 C_PATH='@t6g_mb_lib.t6g(sch_1):page334_i31@pure_quanta.delta_l(chips)';

PART_NAME
 J283 'DELTA_L-DELTA-L,THLF,EMPTY,TP24':;

SECTION_NUMBER 1
 '@T6G_MB_LIB.T6G(SCH_1):PAGE334_I44@PURE_QUANTA.DELTA_L(CHIPS)':
 C_PATH='@t6g_mb_lib.t6g(sch_1):page334_i44@pure_quanta.delta_l(chips)';

PART_NAME
 J282 'DELTA_L-DELTA-L,THLF,EMPTY,TP24':;

SECTION_NUMBER 1
 '@T6G_MB_LIB.T6G(SCH_1):PAGE334_I8@PURE_QUANTA.DELTA_L(CHIPS)':
 C_PATH='@t6g_mb_lib.t6g(sch_1):page334_i8@pure_quanta.delta_l(chips)';

PART_NAME
 J281 'DELTA_L-DELTA-L,THLF,EMPTY,TP24':;

SECTION_NUMBER 1
 '@T6G_MB_LIB.T6G(SCH_1):PAGE334_I25@PURE_QUANTA.DELTA_L(CHIPS)':
 C_PATH='@t6g_mb_lib.t6g(sch_1):page334_i25@pure_quanta.delta_l(chips)';

PART_NAME
 J280 'DELTA_L-DELTA-L,THLF,EMPTY,TP24':;

SECTION_NUMBER 1
 '@T6G_MB_LIB.T6G(SCH_1):PAGE334_I10@PURE_QUANTA.DELTA_L(CHIPS)':
 C_PATH='@t6g_mb_lib.t6g(sch_1):page334_i10@pure_quanta.delta_l(chips)';

PART_NAME
 J279 'DELTA_L-DELTA-L,THLF,EMPTY,TP24':;

SECTION_NUMBER 1
 '@T6G_MB_LIB.T6G(SCH_1):PAGE334_I11@PURE_QUANTA.DELTA_L(CHIPS)':
 C_PATH='@t6g_mb_lib.t6g(sch_1):page334_i11@pure_quanta.delta_l(chips)';

PART_NAME
 J86 'DELTA_L-DELTA-L,THLF,EMPTY,TP24':;

SECTION_NUMBER 1
 '@T6G_MB_LIB.T6G(SCH_1):PAGE334_I32@PURE_QUANTA.DELTA_L(CHIPS)':
 C_PATH='@t6g_mb_lib.t6g(sch_1):page334_i32@pure_quanta.delta_l(chips)';

PART_NAME
 J85 'DELTA_L-DELTA-L,THLF,EMPTY,TP24':;

SECTION_NUMBER 1
 '@T6G_MB_LIB.T6G(SCH_1):PAGE334_I36@PURE_QUANTA.DELTA_L(CHIPS)':
 C_PATH='@t6g_mb_lib.t6g(sch_1):page334_i36@pure_quanta.delta_l(chips)';

PART_NAME
 J84 'DELTA_L-DELTA-L,THLF,EMPTY,TP24':;

SECTION_NUMBER 1
 '@T6G_MB_LIB.T6G(SCH_1):PAGE334_I37@PURE_QUANTA.DELTA_L(CHIPS)':
 C_PATH='@t6g_mb_lib.t6g(sch_1):page334_i37@pure_quanta.delta_l(chips)';

PART_NAME
 J79 'DELTA_L-DELTA-L,THLF,EMPTY,TP24':;

SECTION_NUMBER 1
 '@T6G_MB_LIB.T6G(SCH_1):PAGE334_I33@PURE_QUANTA.DELTA_L(CHIPS)':
 C_PATH='@t6g_mb_lib.t6g(sch_1):page334_i33@pure_quanta.delta_l(chips)';

PART_NAME
 J78 'DELTA_L-DELTA-L,THLF,EMPTY,TP24':;

SECTION_NUMBER 1
 '@T6G_MB_LIB.T6G(SCH_1):PAGE334_I34@PURE_QUANTA.DELTA_L(CHIPS)':
 C_PATH='@t6g_mb_lib.t6g(sch_1):page334_i34@pure_quanta.delta_l(chips)';

PART_NAME
 J77 'DELTA_L-DELTA-L,THLF,EMPTY,TP24':;

SECTION_NUMBER 1
 '@T6G_MB_LIB.T6G(SCH_1):PAGE334_I35@PURE_QUANTA.DELTA_L(CHIPS)':
 C_PATH='@t6g_mb_lib.t6g(sch_1):page334_i35@pure_quanta.delta_l(chips)';

PART_NAME
 J76 'DELTA_L-DELTA-L,THLF,EMPTY,TP24':;

SECTION_NUMBER 1
 '@T6G_MB_LIB.T6G(SCH_1):PAGE334_I43@PURE_QUANTA.DELTA_L(CHIPS)':
 C_PATH='@t6g_mb_lib.t6g(sch_1):page334_i43@pure_quanta.delta_l(chips)';

PART_NAME
 J73 'DELTA_L-DELTA-L,THLF,EMPTY,TP24':;

SECTION_NUMBER 1
 '@T6G_MB_LIB.T6G(SCH_1):PAGE334_I12@PURE_QUANTA.DELTA_L(CHIPS)':
 C_PATH='@t6g_mb_lib.t6g(sch_1):page334_i12@pure_quanta.delta_l(chips)';

PART_NAME
 J72 'DELTA_L-DELTA-L,THLF,EMPTY,TP24':;

SECTION_NUMBER 1
 '@T6G_MB_LIB.T6G(SCH_1):PAGE334_I13@PURE_QUANTA.DELTA_L(CHIPS)':
 C_PATH='@t6g_mb_lib.t6g(sch_1):page334_i13@pure_quanta.delta_l(chips)';

PART_NAME
 J71 'DELTA_L-DELTA-L,THLF,EMPTY,TP24':;

SECTION_NUMBER 1
 '@T6G_MB_LIB.T6G(SCH_1):PAGE334_I14@PURE_QUANTA.DELTA_L(CHIPS)':
 C_PATH='@t6g_mb_lib.t6g(sch_1):page334_i14@pure_quanta.delta_l(chips)';

PART_NAME
 J69 'DELTA_L-DELTA-L,THLF,EMPTY,TP24':;

SECTION_NUMBER 1
 '@T6G_MB_LIB.T6G(SCH_1):PAGE334_I26@PURE_QUANTA.DELTA_L(CHIPS)':
 C_PATH='@t6g_mb_lib.t6g(sch_1):page334_i26@pure_quanta.delta_l(chips)';

PART_NAME
 J68 'DELTA_L-DELTA-L,THLF,EMPTY,TP24':;

SECTION_NUMBER 1
 '@T6G_MB_LIB.T6G(SCH_1):PAGE334_I7@PURE_QUANTA.DELTA_L(CHIPS)':
 C_PATH='@t6g_mb_lib.t6g(sch_1):page334_i7@pure_quanta.delta_l(chips)';

PART_NAME
 J67 'DELTA_L-DELTA-L,THLF,EMPTY,TP24':;

SECTION_NUMBER 1
 '@T6G_MB_LIB.T6G(SCH_1):PAGE334_I9@PURE_QUANTA.DELTA_L(CHIPS)':
 C_PATH='@t6g_mb_lib.t6g(sch_1):page334_i9@pure_quanta.delta_l(chips)';

PART_NAME
 J64 'DELTA_L-DELTA-L,THLF,EMPTY,TP24':;

SECTION_NUMBER 1
 '@T6G_MB_LIB.T6G(SCH_1):PAGE334_I23@PURE_QUANTA.DELTA_L(CHIPS)':
 C_PATH='@t6g_mb_lib.t6g(sch_1):page334_i23@pure_quanta.delta_l(chips)';

PART_NAME
 J63 'DELTA_L-DELTA-L,THLF,EMPTY,TP24':;

SECTION_NUMBER 1
 '@T6G_MB_LIB.T6G(SCH_1):PAGE334_I24@PURE_QUANTA.DELTA_L(CHIPS)':
 C_PATH='@t6g_mb_lib.t6g(sch_1):page334_i24@pure_quanta.delta_l(chips)';

PART_NAME
 R3856 'Q_RES_0402LF-33,5%,1/16W,CHIP,CS03302JB29':;

SECTION_NUMBER 1
 '@T6G_MB_LIB.T6G(SCH_1):PAGE137_I125@PURE_QUANTA.Q_RES(CHIPS)':
 C_PATH='@t6g_mb_lib.t6g(sch_1):page137_i125@pure_quanta.q_res(chips)';

PART_NAME
 R3855 'Q_RES_0402LF-33,5%,1/16W,CHIP,CS03302JB29':;

SECTION_NUMBER 1
 '@T6G_MB_LIB.T6G(SCH_1):PAGE137_I123@PURE_QUANTA.Q_RES(CHIPS)':
 C_PATH='@t6g_mb_lib.t6g(sch_1):page137_i123@pure_quanta.q_res(chips)';

PART_NAME
 J56 'SCONN280_ME1028040102011-SCONN280_ME1028040102011,SMLF,IO,DFHST0FS008':;

SECTION_NUMBER 1
 '@T6G_MB_LIB.T6G(SCH_1):PAGE136_I929@PURE_QUANTA.SCONN280_ME1028040102011(CHIPS)':
 C_PATH='@t6g_mb_lib.t6g(sch_1):page136_i929@pure_quanta.sconn280_me102804010201~
1(chips)';

SECTION_NUMBER 2
 '@T6G_MB_LIB.T6G(SCH_1):PAGE137_I27@PURE_QUANTA.SCONN280_ME1028040102011(CHIPS)':
 C_PATH='@t6g_mb_lib.t6g(sch_1):page137_i27@pure_quanta.sconn280_me1028040102011~
(chips)';

PART_NAME
 R3854 'Q_RES_0402LF-33,5%,1/16W,CHIP,CS03302JB29':;

SECTION_NUMBER 1
 '@T6G_MB_LIB.T6G(SCH_1):PAGE135_I130@PURE_QUANTA.Q_RES(CHIPS)':
 C_PATH='@t6g_mb_lib.t6g(sch_1):page135_i130@pure_quanta.q_res(chips)';

PART_NAME
 R3853 'Q_RES_0402LF-33,5%,1/16W,CHIP,CS03302JB29':;

SECTION_NUMBER 1
 '@T6G_MB_LIB.T6G(SCH_1):PAGE135_I127@PURE_QUANTA.Q_RES(CHIPS)':
 C_PATH='@t6g_mb_lib.t6g(sch_1):page135_i127@pure_quanta.q_res(chips)';

PART_NAME
 J55 'SCONN280_ME1028040102011-SCONN280_ME1028040102011,SMLF,IO,DFHST0FS008':;

SECTION_NUMBER 1
 '@T6G_MB_LIB.T6G(SCH_1):PAGE134_I1243@PURE_QUANTA.SCONN280_ME1028040102011(CHIPS)':
 C_PATH='@t6g_mb_lib.t6g(sch_1):page134_i1243@pure_quanta.sconn280_me10280401020~
11(chips)';

SECTION_NUMBER 2
 '@T6G_MB_LIB.T6G(SCH_1):PAGE135_I51@PURE_QUANTA.SCONN280_ME1028040102011(CHIPS)':
 C_PATH='@t6g_mb_lib.t6g(sch_1):page135_i51@pure_quanta.sconn280_me1028040102011~
(chips)';

PART_NAME
 R705 'Q_RES_0402LF-33,5%,1/16W,CHIP,CS03302JB29':;

SECTION_NUMBER 1
 '@T6G_MB_LIB.T6G(SCH_1):PAGE203_I57@PURE_QUANTA.Q_RES(CHIPS)':
 C_PATH='@t6g_mb_lib.t6g(sch_1):page203_i57@pure_quanta.q_res(chips)';

PART_NAME
 R678 'Q_RES_0402LF-2.2K ,5%,1/16W,CHIP,CS22202JB18':;

SECTION_NUMBER 1
 '@T6G_MB_LIB.T6G(SCH_1):PAGE203_I58@PURE_QUANTA.Q_RES(CHIPS)':
 C_PATH='@t6g_mb_lib.t6g(sch_1):page203_i58@pure_quanta.q_res(chips)';

PART_NAME
 R677 'Q_RES_0402LF-2.2K ,5%,1/16W,CHIP,CS22202JB18':;

SECTION_NUMBER 1
 '@T6G_MB_LIB.T6G(SCH_1):PAGE203_I55@PURE_QUANTA.Q_RES(CHIPS)':
 C_PATH='@t6g_mb_lib.t6g(sch_1):page203_i55@pure_quanta.q_res(chips)';

PART_NAME
 R401 'Q_RES_0402LF-2K,1%,1/16W,CHIP,CS22002FB07':
;

SECTION_NUMBER 1
 '@T6G_MB_LIB.T6G(SCH_1):PAGE203_I49@PURE_QUANTA.Q_RES(CHIPS)':
 C_PATH='@t6g_mb_lib.t6g(sch_1):page203_i49@pure_quanta.q_res(chips)';

PART_NAME
 R400 'Q_RES_0402LF-49.9,1%,1/16W,CHIP,CS04992FB07':
;

SECTION_NUMBER 1
 '@T6G_MB_LIB.T6G(SCH_1):PAGE203_I52@PURE_QUANTA.Q_RES(CHIPS)':
 C_PATH='@t6g_mb_lib.t6g(sch_1):page203_i52@pure_quanta.q_res(chips)';

PART_NAME
 R399 'Q_RES_0402LF-49.9,1%,1/16W,CHIP,CS04992FB07':
;

SECTION_NUMBER 1
 '@T6G_MB_LIB.T6G(SCH_1):PAGE203_I51@PURE_QUANTA.Q_RES(CHIPS)':
 C_PATH='@t6g_mb_lib.t6g(sch_1):page203_i51@pure_quanta.q_res(chips)';

PART_NAME
 R398 'Q_RES_0402LF-49.9,1%,1/16W,CHIP,CS04992FB07':
;

SECTION_NUMBER 1
 '@T6G_MB_LIB.T6G(SCH_1):PAGE203_I50@PURE_QUANTA.Q_RES(CHIPS)':
 C_PATH='@t6g_mb_lib.t6g(sch_1):page203_i50@pure_quanta.q_res(chips)';

PART_NAME
 R396 'Q_RES_0402LF-49.9,1%,1/16W,CHIP,CS04992FB07':
;

SECTION_NUMBER 1
 '@T6G_MB_LIB.T6G(SCH_1):PAGE203_I45@PURE_QUANTA.Q_RES(CHIPS)':
 C_PATH='@t6g_mb_lib.t6g(sch_1):page203_i45@pure_quanta.q_res(chips)';

PART_NAME
 R395 'Q_RES_0402LF-49.9,1%,1/16W,CHIP,CS04992FB07':
;

SECTION_NUMBER 1
 '@T6G_MB_LIB.T6G(SCH_1):PAGE203_I46@PURE_QUANTA.Q_RES(CHIPS)':
 C_PATH='@t6g_mb_lib.t6g(sch_1):page203_i46@pure_quanta.q_res(chips)';

PART_NAME
 R394 'Q_RES_0402LF-49.9,1%,1/16W,CHIP,CS04992FB07':
;

SECTION_NUMBER 1
 '@T6G_MB_LIB.T6G(SCH_1):PAGE203_I44@PURE_QUANTA.Q_RES(CHIPS)':
 C_PATH='@t6g_mb_lib.t6g(sch_1):page203_i44@pure_quanta.q_res(chips)';

PART_NAME
 R374 'Q_RES_0402LF-2K,1%,1/16W,CHIP,CS22002FB07':
;

SECTION_NUMBER 1
 '@T6G_MB_LIB.T6G(SCH_1):PAGE203_I41@PURE_QUANTA.Q_RES(CHIPS)':
 C_PATH='@t6g_mb_lib.t6g(sch_1):page203_i41@pure_quanta.q_res(chips)';

PART_NAME
 R373 'Q_RES_0402LF-2K,1%,1/16W,CHIP,CS22002FB07':
;

SECTION_NUMBER 1
 '@T6G_MB_LIB.T6G(SCH_1):PAGE203_I42@PURE_QUANTA.Q_RES(CHIPS)':
 C_PATH='@t6g_mb_lib.t6g(sch_1):page203_i42@pure_quanta.q_res(chips)';

PART_NAME
 R372 'Q_RES_0402LF-2K,1%,1/16W,CHIP,CS22002FB07':
;

SECTION_NUMBER 1
 '@T6G_MB_LIB.T6G(SCH_1):PAGE203_I43@PURE_QUANTA.Q_RES(CHIPS)':
 C_PATH='@t6g_mb_lib.t6g(sch_1):page203_i43@pure_quanta.q_res(chips)';

PART_NAME
 R371 'Q_RES_0402LF-2K,1%,1/16W,CHIP,CS22002FB07':
;

SECTION_NUMBER 1
 '@T6G_MB_LIB.T6G(SCH_1):PAGE203_I47@PURE_QUANTA.Q_RES(CHIPS)':
 C_PATH='@t6g_mb_lib.t6g(sch_1):page203_i47@pure_quanta.q_res(chips)';

PART_NAME
 R316 'Q_RES_0402LF-2K,1%,1/16W,CHIP,CS22002FB07':
;

SECTION_NUMBER 1
 '@T6G_MB_LIB.T6G(SCH_1):PAGE203_I48@PURE_QUANTA.Q_RES(CHIPS)':
 C_PATH='@t6g_mb_lib.t6g(sch_1):page203_i48@pure_quanta.q_res(chips)';

PART_NAME
 J40 'CONN4_532900480-CONN4_53290-0480,THLF,IO,DFHD04MS119':;

SECTION_NUMBER 1
 '@T6G_MB_LIB.T6G(SCH_1):PAGE203_I53@PURE_QUANTA.CONN4_532900480(CHIPS)':
 C_PATH='@t6g_mb_lib.t6g(sch_1):page203_i53@pure_quanta.conn4_532900480(chips)';

PART_NAME
 H151 'HOLE_TH-EMPTY,HOLE1226':;

SECTION_NUMBER 1
 '@T6G_MB_LIB.T6G(SCH_1):PAGE335_I110@PURE_QUANTA.HOLE(CHIPS)':
 C_PATH='@t6g_mb_lib.t6g(sch_1):page335_i110@pure_quanta.hole(chips)';

PART_NAME
 H150 'HOLE_TH-EMPTY,HOLE1226':;

SECTION_NUMBER 1
 '@T6G_MB_LIB.T6G(SCH_1):PAGE335_I108@PURE_QUANTA.HOLE(CHIPS)':
 C_PATH='@t6g_mb_lib.t6g(sch_1):page335_i108@pure_quanta.hole(chips)';

PART_NAME
 H149 'HOLE_TH-EMPTY,HOLE1226':;

SECTION_NUMBER 1
 '@T6G_MB_LIB.T6G(SCH_1):PAGE335_I113@PURE_QUANTA.HOLE(CHIPS)':
 C_PATH='@t6g_mb_lib.t6g(sch_1):page335_i113@pure_quanta.hole(chips)';

PART_NAME
 H148 'HOLE_TH-EMPTY,HOLE1226':;

SECTION_NUMBER 1
 '@T6G_MB_LIB.T6G(SCH_1):PAGE335_I112@PURE_QUANTA.HOLE(CHIPS)':
 C_PATH='@t6g_mb_lib.t6g(sch_1):page335_i112@pure_quanta.hole(chips)';

PART_NAME
 H147 'HOLE_TH-EMPTY,HOLE1226':;

SECTION_NUMBER 1
 '@T6G_MB_LIB.T6G(SCH_1):PAGE335_I106@PURE_QUANTA.HOLE(CHIPS)':
 C_PATH='@t6g_mb_lib.t6g(sch_1):page335_i106@pure_quanta.hole(chips)';

PART_NAME
 H146 'HOLE_TH-EMPTY,HOLE1226':;

SECTION_NUMBER 1
 '@T6G_MB_LIB.T6G(SCH_1):PAGE335_I102@PURE_QUANTA.HOLE(CHIPS)':
 C_PATH='@t6g_mb_lib.t6g(sch_1):page335_i102@pure_quanta.hole(chips)';

PART_NAME
 H145 'HOLE_TH-EMPTY,HOLE1226':;

SECTION_NUMBER 1
 '@T6G_MB_LIB.T6G(SCH_1):PAGE335_I104@PURE_QUANTA.HOLE(CHIPS)':
 C_PATH='@t6g_mb_lib.t6g(sch_1):page335_i104@pure_quanta.hole(chips)';

PART_NAME
 H144 'HOLE_TH-EMPTY,HOLE1226':;

SECTION_NUMBER 1
 '@T6G_MB_LIB.T6G(SCH_1):PAGE335_I100@PURE_QUANTA.HOLE(CHIPS)':
 C_PATH='@t6g_mb_lib.t6g(sch_1):page335_i100@pure_quanta.hole(chips)';

PART_NAME
 H143 'HOLE_TH-EMPTY,HOLE1225':;

SECTION_NUMBER 1
 '@T6G_MB_LIB.T6G(SCH_1):PAGE335_I99@PURE_QUANTA.HOLE(CHIPS)':
 C_PATH='@t6g_mb_lib.t6g(sch_1):page335_i99@pure_quanta.hole(chips)';

PART_NAME
 H141 'HOLE_TH-EMPTY,HOLE1224':;

SECTION_NUMBER 1
 '@T6G_MB_LIB.T6G(SCH_1):PAGE335_I89@PURE_QUANTA.HOLE(CHIPS)':
 C_PATH='@t6g_mb_lib.t6g(sch_1):page335_i89@pure_quanta.hole(chips)';

PART_NAME
 H140 'HOLE_TH-EMPTY,HOLE1224':;

SECTION_NUMBER 1
 '@T6G_MB_LIB.T6G(SCH_1):PAGE335_I91@PURE_QUANTA.HOLE(CHIPS)':
 C_PATH='@t6g_mb_lib.t6g(sch_1):page335_i91@pure_quanta.hole(chips)';

PART_NAME
 H104 'HOLE_TH-EMPTY,DUMMY50':;

SECTION_NUMBER 1
 '@T6G_MB_LIB.T6G(SCH_1):PAGE335_I82@PURE_QUANTA.HOLE(CHIPS)':
 C_PATH='@t6g_mb_lib.t6g(sch_1):page335_i82@pure_quanta.hole(chips)';

PART_NAME
 H103 'HOLE_TH-EMPTY,DUMMY50':;

SECTION_NUMBER 1
 '@T6G_MB_LIB.T6G(SCH_1):PAGE335_I81@PURE_QUANTA.HOLE(CHIPS)':
 C_PATH='@t6g_mb_lib.t6g(sch_1):page335_i81@pure_quanta.hole(chips)';

PART_NAME
 H101 'HOLE_TH-EMPTY,DUMMY50':;

SECTION_NUMBER 1
 '@T6G_MB_LIB.T6G(SCH_1):PAGE335_I83@PURE_QUANTA.HOLE(CHIPS)':
 C_PATH='@t6g_mb_lib.t6g(sch_1):page335_i83@pure_quanta.hole(chips)';

PART_NAME
 H45 'HOLE_TH-EMPTY,HOLE1018':;

SECTION_NUMBER 1
 '@T6G_MB_LIB.T6G(SCH_1):PAGE335_I79@PURE_QUANTA.HOLE(CHIPS)':
 C_PATH='@t6g_mb_lib.t6g(sch_1):page335_i79@pure_quanta.hole(chips)';

PART_NAME
 H23 'HOLE_TH-EMPTY,TMP-C_HOLE23':;

SECTION_NUMBER 1
 '@T6G_MB_LIB.T6G(SCH_1):PAGE335_I34@PURE_QUANTA.HOLE(CHIPS)':
 C_PATH='@t6g_mb_lib.t6g(sch_1):page335_i34@pure_quanta.hole(chips)';

PART_NAME
 H22 'HOLE_TH-EMPTY,TMP-C_HOLE23':;

SECTION_NUMBER 1
 '@T6G_MB_LIB.T6G(SCH_1):PAGE335_I31@PURE_QUANTA.HOLE(CHIPS)':
 C_PATH='@t6g_mb_lib.t6g(sch_1):page335_i31@pure_quanta.hole(chips)';

PART_NAME
 H21 'HOLE_TH-EMPTY,HOLE1079':;

SECTION_NUMBER 1
 '@T6G_MB_LIB.T6G(SCH_1):PAGE335_I26@PURE_QUANTA.HOLE(CHIPS)':
 C_PATH='@t6g_mb_lib.t6g(sch_1):page335_i26@pure_quanta.hole(chips)';

PART_NAME
 H20 'HOLE_TH-EMPTY,HOLE1079':;

SECTION_NUMBER 1
 '@T6G_MB_LIB.T6G(SCH_1):PAGE335_I25@PURE_QUANTA.HOLE(CHIPS)':
 C_PATH='@t6g_mb_lib.t6g(sch_1):page335_i25@pure_quanta.hole(chips)';

PART_NAME
 H19 'HOLE_TH-EMPTY,HOLE1079':;

SECTION_NUMBER 1
 '@T6G_MB_LIB.T6G(SCH_1):PAGE335_I27@PURE_QUANTA.HOLE(CHIPS)':
 C_PATH='@t6g_mb_lib.t6g(sch_1):page335_i27@pure_quanta.hole(chips)';

PART_NAME
 H18 'HOLE_TH-EMPTY,HOLE1079':;

SECTION_NUMBER 1
 '@T6G_MB_LIB.T6G(SCH_1):PAGE335_I28@PURE_QUANTA.HOLE(CHIPS)':
 C_PATH='@t6g_mb_lib.t6g(sch_1):page335_i28@pure_quanta.hole(chips)';

PART_NAME
 H17 'HOLE_TH-EMPTY,HOLE1079':;

SECTION_NUMBER 1
 '@T6G_MB_LIB.T6G(SCH_1):PAGE335_I29@PURE_QUANTA.HOLE(CHIPS)':
 C_PATH='@t6g_mb_lib.t6g(sch_1):page335_i29@pure_quanta.hole(chips)';

PART_NAME
 H16 'HOLE_TH-EMPTY,HOLE1079':;

SECTION_NUMBER 1
 '@T6G_MB_LIB.T6G(SCH_1):PAGE335_I30@PURE_QUANTA.HOLE(CHIPS)':
 C_PATH='@t6g_mb_lib.t6g(sch_1):page335_i30@pure_quanta.hole(chips)';

PART_NAME
 H15 'HOLE_TH-EMPTY,HOLE1079':;

SECTION_NUMBER 1
 '@T6G_MB_LIB.T6G(SCH_1):PAGE335_I24@PURE_QUANTA.HOLE(CHIPS)':
 C_PATH='@t6g_mb_lib.t6g(sch_1):page335_i24@pure_quanta.hole(chips)';

PART_NAME
 H14 'HOLE_TH-EMPTY,HOLE1079':;

SECTION_NUMBER 1
 '@T6G_MB_LIB.T6G(SCH_1):PAGE335_I23@PURE_QUANTA.HOLE(CHIPS)':
 C_PATH='@t6g_mb_lib.t6g(sch_1):page335_i23@pure_quanta.hole(chips)';

PART_NAME
 H13 'HOLE_TH-EMPTY,HOLE1079':;

SECTION_NUMBER 1
 '@T6G_MB_LIB.T6G(SCH_1):PAGE335_I22@PURE_QUANTA.HOLE(CHIPS)':
 C_PATH='@t6g_mb_lib.t6g(sch_1):page335_i22@pure_quanta.hole(chips)';

PART_NAME
 H12 'HOLE_TH-EMPTY,HOLE1079':;

SECTION_NUMBER 1
 '@T6G_MB_LIB.T6G(SCH_1):PAGE335_I21@PURE_QUANTA.HOLE(CHIPS)':
 C_PATH='@t6g_mb_lib.t6g(sch_1):page335_i21@pure_quanta.hole(chips)';

PART_NAME
 H11 'HOLE_TH-EMPTY,HOLE1079':;

SECTION_NUMBER 1
 '@T6G_MB_LIB.T6G(SCH_1):PAGE335_I20@PURE_QUANTA.HOLE(CHIPS)':
 C_PATH='@t6g_mb_lib.t6g(sch_1):page335_i20@pure_quanta.hole(chips)';

PART_NAME
 H10 'HOLE_TH-EMPTY,HOLE1079':;

SECTION_NUMBER 1
 '@T6G_MB_LIB.T6G(SCH_1):PAGE335_I19@PURE_QUANTA.HOLE(CHIPS)':
 C_PATH='@t6g_mb_lib.t6g(sch_1):page335_i19@pure_quanta.hole(chips)';

PART_NAME
 H9 'HOLE_TH-EMPTY,HOLE1106':;

SECTION_NUMBER 1
 '@T6G_MB_LIB.T6G(SCH_1):PAGE335_I5@PURE_QUANTA.HOLE(CHIPS)':
 C_PATH='@t6g_mb_lib.t6g(sch_1):page335_i5@pure_quanta.hole(chips)';

PART_NAME
 H8 'HOLE_TH-EMPTY,HOLE1106':;

SECTION_NUMBER 1
 '@T6G_MB_LIB.T6G(SCH_1):PAGE335_I9@PURE_QUANTA.HOLE(CHIPS)':
 C_PATH='@t6g_mb_lib.t6g(sch_1):page335_i9@pure_quanta.hole(chips)';

PART_NAME
 H7 'HOLE_TH-EMPTY,HOLE1106':;

SECTION_NUMBER 1
 '@T6G_MB_LIB.T6G(SCH_1):PAGE335_I13@PURE_QUANTA.HOLE(CHIPS)':
 C_PATH='@t6g_mb_lib.t6g(sch_1):page335_i13@pure_quanta.hole(chips)';

PART_NAME
 H6 'HOLE_TH-EMPTY,HOLE1106':;

SECTION_NUMBER 1
 '@T6G_MB_LIB.T6G(SCH_1):PAGE335_I16@PURE_QUANTA.HOLE(CHIPS)':
 C_PATH='@t6g_mb_lib.t6g(sch_1):page335_i16@pure_quanta.hole(chips)';

PART_NAME
 H5 'HOLE_TH-EMPTY,HOLE1106':;

SECTION_NUMBER 1
 '@T6G_MB_LIB.T6G(SCH_1):PAGE335_I1@PURE_QUANTA.HOLE(CHIPS)':
 C_PATH='@t6g_mb_lib.t6g(sch_1):page335_i1@pure_quanta.hole(chips)';

PART_NAME
 H4 'HOLE_TH-EMPTY,HOLE1106':;

SECTION_NUMBER 1
 '@T6G_MB_LIB.T6G(SCH_1):PAGE335_I3@PURE_QUANTA.HOLE(CHIPS)':
 C_PATH='@t6g_mb_lib.t6g(sch_1):page335_i3@pure_quanta.hole(chips)';

PART_NAME
 H3 'HOLE_TH-EMPTY,HOLE1106':;

SECTION_NUMBER 1
 '@T6G_MB_LIB.T6G(SCH_1):PAGE335_I7@PURE_QUANTA.HOLE(CHIPS)':
 C_PATH='@t6g_mb_lib.t6g(sch_1):page335_i7@pure_quanta.hole(chips)';

PART_NAME
 H2 'HOLE_TH-EMPTY,HOLE1106':;

SECTION_NUMBER 1
 '@T6G_MB_LIB.T6G(SCH_1):PAGE335_I11@PURE_QUANTA.HOLE(CHIPS)':
 C_PATH='@t6g_mb_lib.t6g(sch_1):page335_i11@pure_quanta.hole(chips)';

PART_NAME
 H1 'HOLE_TH-EMPTY,HOLE1106':;

SECTION_NUMBER 1
 '@T6G_MB_LIB.T6G(SCH_1):PAGE335_I15@PURE_QUANTA.HOLE(CHIPS)':
 C_PATH='@t6g_mb_lib.t6g(sch_1):page335_i15@pure_quanta.hole(chips)';

PART_NAME
 DM11 'DUMMY_SYMBOL-QCT_LOGO_12X12,MECH,EMPTY,DUMMY13':;

SECTION_NUMBER 1
 '@T6G_MB_LIB.T6G(SCH_1):PAGE338_I6@PURE_QUANTA.DUMMY_SYMBOL(CHIPS)':
 C_PATH='@t6g_mb_lib.t6g(sch_1):page338_i6@pure_quanta.dummy_symbol(chips)';

PART_NAME
 DM5 'DUMMY_SYMBOL-BARCODE_20X6,MECH,MECH,DUMMY15':;

SECTION_NUMBER 1
 '@T6G_MB_LIB.T6G(SCH_1):PAGE338_I5@PURE_QUANTA.DUMMY_SYMBOL(CHIPS)':
 C_PATH='@t6g_mb_lib.t6g(sch_1):page338_i5@pure_quanta.dummy_symbol(chips)';

PART_NAME
 DM4 'DUMMY_SYMBOL-PCBA_LABEL_15X5,MECH,EMPTY,DUMMY4':;

SECTION_NUMBER 1
 '@T6G_MB_LIB.T6G(SCH_1):PAGE338_I4@PURE_QUANTA.DUMMY_SYMBOL(CHIPS)':
 C_PATH='@t6g_mb_lib.t6g(sch_1):page338_i4@pure_quanta.dummy_symbol(chips)';

PART_NAME
 DM3 'DUMMY_SYMBOL-PB-E1_SMALL,MECH,EMPTY,DUMMY3':;

SECTION_NUMBER 1
 '@T6G_MB_LIB.T6G(SCH_1):PAGE338_I3@PURE_QUANTA.DUMMY_SYMBOL(CHIPS)':
 C_PATH='@t6g_mb_lib.t6g(sch_1):page338_i3@pure_quanta.dummy_symbol(chips)';

PART_NAME
 DM2 'DUMMY_SYMBOL-WEEE,MECH,EMPTY,DUMMY2':;

SECTION_NUMBER 1
 '@T6G_MB_LIB.T6G(SCH_1):PAGE338_I2@PURE_QUANTA.DUMMY_SYMBOL(CHIPS)':
 C_PATH='@t6g_mb_lib.t6g(sch_1):page338_i2@pure_quanta.dummy_symbol(chips)';

PART_NAME
 R3743 'Q_RES_0402LF-10K,5%,1/16W,CHIP,TMP_QCS31002JB28':;

SECTION_NUMBER 1
 '@T6G_MB_LIB.T6G(SCH_1):PAGE253_I66@PURE_QUANTA.Q_RES(CHIPS)':
 C_PATH='@t6g_mb_lib.t6g(sch_1):page253_i66@pure_quanta.q_res(chips)';

PART_NAME
 R3742 'Q_RES_0402LF-10K,5%,1/16W,CHIP,TMP_QCS31002JB28':;

SECTION_NUMBER 1
 '@T6G_MB_LIB.T6G(SCH_1):PAGE253_I64@PURE_QUANTA.Q_RES(CHIPS)':
 C_PATH='@t6g_mb_lib.t6g(sch_1):page253_i64@pure_quanta.q_res(chips)';

PART_NAME
 R3741 'Q_RES_0402LF-10K,5%,1/16W,CHIP,TMP_QCS31002JB28':;

SECTION_NUMBER 1
 '@T6G_MB_LIB.T6G(SCH_1):PAGE253_I63@PURE_QUANTA.Q_RES(CHIPS)':
 C_PATH='@t6g_mb_lib.t6g(sch_1):page253_i63@pure_quanta.q_res(chips)';

PART_NAME
 R3737 'Q_RES_0402LF-33,5%,1/16W,CHIP,CS03302JB29':;

SECTION_NUMBER 1
 '@T6G_MB_LIB.T6G(SCH_1):PAGE253_I38@PURE_QUANTA.Q_RES(CHIPS)':
 C_PATH='@t6g_mb_lib.t6g(sch_1):page253_i38@pure_quanta.q_res(chips)';

PART_NAME
 R3736 'Q_RES_0402LF-33,5%,1/16W,CHIP,CS03302JB29':;

SECTION_NUMBER 1
 '@T6G_MB_LIB.T6G(SCH_1):PAGE253_I37@PURE_QUANTA.Q_RES(CHIPS)':
 C_PATH='@t6g_mb_lib.t6g(sch_1):page253_i37@pure_quanta.q_res(chips)';

PART_NAME
 R3735 'Q_RES_0402LF-33,5%,1/16W,CHIP,CS03302JB29':;

SECTION_NUMBER 1
 '@T6G_MB_LIB.T6G(SCH_1):PAGE253_I34@PURE_QUANTA.Q_RES(CHIPS)':
 C_PATH='@t6g_mb_lib.t6g(sch_1):page253_i34@pure_quanta.q_res(chips)';

PART_NAME
 R3734 'Q_RES_0402LF-33,5%,1/16W,CHIP,CS03302JB29':;

SECTION_NUMBER 1
 '@T6G_MB_LIB.T6G(SCH_1):PAGE253_I35@PURE_QUANTA.Q_RES(CHIPS)':
 C_PATH='@t6g_mb_lib.t6g(sch_1):page253_i35@pure_quanta.q_res(chips)';

PART_NAME
 R3733 'Q_RES_0402LF-33,5%,1/16W,CHIP,CS03302JB29':;

SECTION_NUMBER 1
 '@T6G_MB_LIB.T6G(SCH_1):PAGE253_I12@PURE_QUANTA.Q_RES(CHIPS)':
 C_PATH='@t6g_mb_lib.t6g(sch_1):page253_i12@pure_quanta.q_res(chips)';

PART_NAME
 R3732 'Q_RES_0402LF-33,5%,1/16W,CHIP,CS03302JB29':;

SECTION_NUMBER 1
 '@T6G_MB_LIB.T6G(SCH_1):PAGE253_I13@PURE_QUANTA.Q_RES(CHIPS)':
 C_PATH='@t6g_mb_lib.t6g(sch_1):page253_i13@pure_quanta.q_res(chips)';

PART_NAME
 R3731 'Q_RES_0402LF-33,5%,1/16W,CHIP,CS03302JB29':;

SECTION_NUMBER 1
 '@T6G_MB_LIB.T6G(SCH_1):PAGE253_I10@PURE_QUANTA.Q_RES(CHIPS)':
 C_PATH='@t6g_mb_lib.t6g(sch_1):page253_i10@pure_quanta.q_res(chips)';

PART_NAME
 R3730 'Q_RES_0402LF-33,5%,1/16W,CHIP,CS03302JB29':;

SECTION_NUMBER 1
 '@T6G_MB_LIB.T6G(SCH_1):PAGE253_I11@PURE_QUANTA.Q_RES(CHIPS)':
 C_PATH='@t6g_mb_lib.t6g(sch_1):page253_i11@pure_quanta.q_res(chips)';

PART_NAME
 R3718 'Q_RES_0402LF-33,5%,1/16W,CHIP,CS03302JB29':;

SECTION_NUMBER 1
 '@T6G_MB_LIB.T6G(SCH_1):PAGE253_I33@PURE_QUANTA.Q_RES(CHIPS)':
 C_PATH='@t6g_mb_lib.t6g(sch_1):page253_i33@pure_quanta.q_res(chips)';

PART_NAME
 R3717 'Q_RES_0402LF-33,5%,1/16W,CHIP,CS03302JB29':;

SECTION_NUMBER 1
 '@T6G_MB_LIB.T6G(SCH_1):PAGE253_I36@PURE_QUANTA.Q_RES(CHIPS)':
 C_PATH='@t6g_mb_lib.t6g(sch_1):page253_i36@pure_quanta.q_res(chips)';

PART_NAME
 R3705 'Q_RES_0402LF-10K,5%,1/16W,CHIP,TMP_QCS31002JB28':;

SECTION_NUMBER 1
 '@T6G_MB_LIB.T6G(SCH_1):PAGE253_I61@PURE_QUANTA.Q_RES(CHIPS)':
 C_PATH='@t6g_mb_lib.t6g(sch_1):page253_i61@pure_quanta.q_res(chips)';

PART_NAME
 R2849 'Q_RES_0402LF-33,5%,1/16W,CHIP,CS03302JB29':;

SECTION_NUMBER 1
 '@T6G_MB_LIB.T6G(SCH_1):PAGE253_I9@PURE_QUANTA.Q_RES(CHIPS)':
 C_PATH='@t6g_mb_lib.t6g(sch_1):page253_i9@pure_quanta.q_res(chips)';

PART_NAME
 R1454 'Q_RES_0402LF-33,5%,1/16W,CHIP,CS03302JB29':;

SECTION_NUMBER 1
 '@T6G_MB_LIB.T6G(SCH_1):PAGE253_I8@PURE_QUANTA.Q_RES(CHIPS)':
 C_PATH='@t6g_mb_lib.t6g(sch_1):page253_i8@pure_quanta.q_res(chips)';

PART_NAME
 J37 'SCONN20_5011902017-SCONN20_501190-2017,SMLF,IO,DFWF20MS004':;

SECTION_NUMBER 1
 '@T6G_MB_LIB.T6G(SCH_1):PAGE253_I25@PURE_QUANTA.SCONN20_5011902017(CHIPS)':
 C_PATH='@t6g_mb_lib.t6g(sch_1):page253_i25@pure_quanta.sconn20_5011902017(chips~
)';

PART_NAME
 J35 'SCONN20_5011902017-SCONN20_501190-2017,SMLF,IO,DFWF20MS004':;

SECTION_NUMBER 1
 '@T6G_MB_LIB.T6G(SCH_1):PAGE253_I15@PURE_QUANTA.SCONN20_5011902017(CHIPS)':
 C_PATH='@t6g_mb_lib.t6g(sch_1):page253_i15@pure_quanta.sconn20_5011902017(chips~
)';

PART_NAME
 D100 'Q_DIODE_SMLF-SDMK0340L-7-F,IC,BC000340033':;

SECTION_NUMBER 1
 '@T6G_MB_LIB.T6G(SCH_1):PAGE253_I58@PURE_QUANTA.Q_DIODE(CHIPS)':
 C_PATH='@t6g_mb_lib.t6g(sch_1):page253_i58@pure_quanta.q_diode(chips)';

PART_NAME
 D99 'Q_DIODE_SMLF-SDMK0340L-7-F,IC,BC000340033':;

SECTION_NUMBER 1
 '@T6G_MB_LIB.T6G(SCH_1):PAGE253_I49@PURE_QUANTA.Q_DIODE(CHIPS)':
 C_PATH='@t6g_mb_lib.t6g(sch_1):page253_i49@pure_quanta.q_diode(chips)';

PART_NAME
 D98 'Q_DIODE_SMLF-SDMK0340L-7-F,IC,BC000340033':;

SECTION_NUMBER 1
 '@T6G_MB_LIB.T6G(SCH_1):PAGE253_I50@PURE_QUANTA.Q_DIODE(CHIPS)':
 C_PATH='@t6g_mb_lib.t6g(sch_1):page253_i50@pure_quanta.q_diode(chips)';

PART_NAME
 R3598 'Q_RES_0402LF-1K,1%,1/16W,CHIP,TMP_QCS21002FB24':;

SECTION_NUMBER 1
 '@T6G_MB_LIB.T6G(SCH_1):PAGE211_I170@PURE_QUANTA.Q_RES(CHIPS)':
 C_PATH='@t6g_mb_lib.t6g(sch_1):page211_i170@pure_quanta.q_res(chips)';

PART_NAME
 R3597 'Q_RES_0402LF-1K,1%,1/16W,CHIP,TMP_QCS21002FB24':;

SECTION_NUMBER 1
 '@T6G_MB_LIB.T6G(SCH_1):PAGE211_I169@PURE_QUANTA.Q_RES(CHIPS)':
 C_PATH='@t6g_mb_lib.t6g(sch_1):page211_i169@pure_quanta.q_res(chips)';

PART_NAME
 R3596 'Q_RES_0402LF-1K,1%,1/16W,CHIP,TMP_QCS21002FB24':;

SECTION_NUMBER 1
 '@T6G_MB_LIB.T6G(SCH_1):PAGE211_I167@PURE_QUANTA.Q_RES(CHIPS)':
 C_PATH='@t6g_mb_lib.t6g(sch_1):page211_i167@pure_quanta.q_res(chips)';

PART_NAME
 R3595 'Q_RES_0402LF-1K,1%,1/16W,CHIP,TMP_QCS21002FB24':;

SECTION_NUMBER 1
 '@T6G_MB_LIB.T6G(SCH_1):PAGE211_I166@PURE_QUANTA.Q_RES(CHIPS)':
 C_PATH='@t6g_mb_lib.t6g(sch_1):page211_i166@pure_quanta.q_res(chips)';

PART_NAME
 R3594 'Q_RES_0402LF-1K,1%,1/16W,CHIP,TMP_QCS21002FB24':;

SECTION_NUMBER 1
 '@T6G_MB_LIB.T6G(SCH_1):PAGE211_I168@PURE_QUANTA.Q_RES(CHIPS)':
 C_PATH='@t6g_mb_lib.t6g(sch_1):page211_i168@pure_quanta.q_res(chips)';

PART_NAME
 R3593 'Q_RES_0402LF-1K,1%,1/16W,CHIP,TMP_QCS21002FB24':;

SECTION_NUMBER 1
 '@T6G_MB_LIB.T6G(SCH_1):PAGE211_I164@PURE_QUANTA.Q_RES(CHIPS)':
 C_PATH='@t6g_mb_lib.t6g(sch_1):page211_i164@pure_quanta.q_res(chips)';

PART_NAME
 R3592 'Q_RES_0402LF-1K,1%,1/16W,CHIP,TMP_QCS21002FB24':;

SECTION_NUMBER 1
 '@T6G_MB_LIB.T6G(SCH_1):PAGE211_I165@PURE_QUANTA.Q_RES(CHIPS)':
 C_PATH='@t6g_mb_lib.t6g(sch_1):page211_i165@pure_quanta.q_res(chips)';

PART_NAME
 R3591 'Q_RES_0402LF-1K,1%,1/16W,CHIP,TMP_QCS21002FB24':;

SECTION_NUMBER 1
 '@T6G_MB_LIB.T6G(SCH_1):PAGE211_I163@PURE_QUANTA.Q_RES(CHIPS)':
 C_PATH='@t6g_mb_lib.t6g(sch_1):page211_i163@pure_quanta.q_res(chips)';

PART_NAME
 R3571 'Q_RES_0402LF-1K,1%,1/16W,CHIP,TMP_QCS21002FB24':;

SECTION_NUMBER 1
 '@T6G_MB_LIB.T6G(SCH_1):PAGE211_I149@PURE_QUANTA.Q_RES(CHIPS)':
 C_PATH='@t6g_mb_lib.t6g(sch_1):page211_i149@pure_quanta.q_res(chips)';

PART_NAME
 R3570 'Q_RES_0402LF-1K,1%,1/16W,CHIP,TMP_QCS21002FB24':;

SECTION_NUMBER 1
 '@T6G_MB_LIB.T6G(SCH_1):PAGE211_I150@PURE_QUANTA.Q_RES(CHIPS)':
 C_PATH='@t6g_mb_lib.t6g(sch_1):page211_i150@pure_quanta.q_res(chips)';

PART_NAME
 R3569 'Q_RES_0402LF-1K,1%,1/16W,CHIP,TMP_QCS21002FB24':;

SECTION_NUMBER 1
 '@T6G_MB_LIB.T6G(SCH_1):PAGE211_I145@PURE_QUANTA.Q_RES(CHIPS)':
 C_PATH='@t6g_mb_lib.t6g(sch_1):page211_i145@pure_quanta.q_res(chips)';

PART_NAME
 R3568 'Q_RES_0402LF-1K,1%,1/16W,CHIP,TMP_QCS21002FB24':;

SECTION_NUMBER 1
 '@T6G_MB_LIB.T6G(SCH_1):PAGE211_I144@PURE_QUANTA.Q_RES(CHIPS)':
 C_PATH='@t6g_mb_lib.t6g(sch_1):page211_i144@pure_quanta.q_res(chips)';

PART_NAME
 R3567 'Q_RES_0402LF-1K,1%,1/16W,CHIP,TMP_QCS21002FB24':;

SECTION_NUMBER 1
 '@T6G_MB_LIB.T6G(SCH_1):PAGE211_I146@PURE_QUANTA.Q_RES(CHIPS)':
 C_PATH='@t6g_mb_lib.t6g(sch_1):page211_i146@pure_quanta.q_res(chips)';

PART_NAME
 R3566 'Q_RES_0402LF-1K,1%,1/16W,CHIP,TMP_QCS21002FB24':;

SECTION_NUMBER 1
 '@T6G_MB_LIB.T6G(SCH_1):PAGE211_I148@PURE_QUANTA.Q_RES(CHIPS)':
 C_PATH='@t6g_mb_lib.t6g(sch_1):page211_i148@pure_quanta.q_res(chips)';

PART_NAME
 R3565 'Q_RES_0402LF-1K,1%,1/16W,CHIP,TMP_QCS21002FB24':;

SECTION_NUMBER 1
 '@T6G_MB_LIB.T6G(SCH_1):PAGE211_I147@PURE_QUANTA.Q_RES(CHIPS)':
 C_PATH='@t6g_mb_lib.t6g(sch_1):page211_i147@pure_quanta.q_res(chips)';

PART_NAME
 R3564 'Q_RES_0402LF-1K,1%,1/16W,CHIP,TMP_QCS21002FB24':;

SECTION_NUMBER 1
 '@T6G_MB_LIB.T6G(SCH_1):PAGE211_I143@PURE_QUANTA.Q_RES(CHIPS)':
 C_PATH='@t6g_mb_lib.t6g(sch_1):page211_i143@pure_quanta.q_res(chips)';

PART_NAME
 R2955 'Q_RES_0402LF-0,5%,1/16W,CHIP,CS00002JB13':
;

SECTION_NUMBER 1
 '@T6G_MB_LIB.T6G(SCH_1):PAGE211_I137@PURE_QUANTA.Q_RES(CHIPS)':
 C_PATH='@t6g_mb_lib.t6g(sch_1):page211_i137@pure_quanta.q_res(chips)';

PART_NAME
 R2954 'Q_RES_0402LF-0,5%,1/16W,CHIP,CS00002JB13':
;

SECTION_NUMBER 1
 '@T6G_MB_LIB.T6G(SCH_1):PAGE211_I141@PURE_QUANTA.Q_RES(CHIPS)':
 C_PATH='@t6g_mb_lib.t6g(sch_1):page211_i141@pure_quanta.q_res(chips)';

PART_NAME
 R2946 'Q_RES_0402LF-0,5%,1/16W,CHIP,CS00002JB13':
;

SECTION_NUMBER 1
 '@T6G_MB_LIB.T6G(SCH_1):PAGE211_I136@PURE_QUANTA.Q_RES(CHIPS)':
 C_PATH='@t6g_mb_lib.t6g(sch_1):page211_i136@pure_quanta.q_res(chips)';

PART_NAME
 R2945 'Q_RES_0402LF-0,5%,1/16W,CHIP,CS00002JB13':
;

SECTION_NUMBER 1
 '@T6G_MB_LIB.T6G(SCH_1):PAGE211_I133@PURE_QUANTA.Q_RES(CHIPS)':
 C_PATH='@t6g_mb_lib.t6g(sch_1):page211_i133@pure_quanta.q_res(chips)';

PART_NAME
 R2123 'Q_RES_0402LF-0,5%,1/16W,EMPTY,CS00002JB13':
;

SECTION_NUMBER 1
 '@T6G_MB_LIB.T6G(SCH_1):PAGE211_I104@PURE_QUANTA.Q_RES(CHIPS)':
 C_PATH='@t6g_mb_lib.t6g(sch_1):page211_i104@pure_quanta.q_res(chips)';

PART_NAME
 R2121 'Q_RES_0402LF-0,5%,1/16W,EMPTY,CS00002JB13':
;

SECTION_NUMBER 1
 '@T6G_MB_LIB.T6G(SCH_1):PAGE211_I139@PURE_QUANTA.Q_RES(CHIPS)':
 C_PATH='@t6g_mb_lib.t6g(sch_1):page211_i139@pure_quanta.q_res(chips)';

PART_NAME
 R2120 'Q_RES_0402LF-0,5%,1/16W,EMPTY,CS00002JB13':
;

SECTION_NUMBER 1
 '@T6G_MB_LIB.T6G(SCH_1):PAGE211_I7@PURE_QUANTA.Q_RES(CHIPS)':
 C_PATH='@t6g_mb_lib.t6g(sch_1):page211_i7@pure_quanta.q_res(chips)';

PART_NAME
 R2118 'Q_RES_0402LF-0,5%,1/16W,EMPTY,CS00002JB13':
;

SECTION_NUMBER 1
 '@T6G_MB_LIB.T6G(SCH_1):PAGE211_I85@PURE_QUANTA.Q_RES(CHIPS)':
 C_PATH='@t6g_mb_lib.t6g(sch_1):page211_i85@pure_quanta.q_res(chips)';

PART_NAME
 D97 'Q_DIODE_SMLF-SDMK0340L-7-F,IC,BC000340033':;

SECTION_NUMBER 1
 '@T6G_MB_LIB.T6G(SCH_1):PAGE211_I182@PURE_QUANTA.Q_DIODE(CHIPS)':
 C_PATH='@t6g_mb_lib.t6g(sch_1):page211_i182@pure_quanta.q_diode(chips)';

PART_NAME
 D96 'Q_DIODE_SMLF-SDMK0340L-7-F,IC,BC000340033':;

SECTION_NUMBER 1
 '@T6G_MB_LIB.T6G(SCH_1):PAGE211_I181@PURE_QUANTA.Q_DIODE(CHIPS)':
 C_PATH='@t6g_mb_lib.t6g(sch_1):page211_i181@pure_quanta.q_diode(chips)';

PART_NAME
 D95 'Q_DIODE_SMLF-SDMK0340L-7-F,IC,BC000340033':;

SECTION_NUMBER 1
 '@T6G_MB_LIB.T6G(SCH_1):PAGE211_I180@PURE_QUANTA.Q_DIODE(CHIPS)':
 C_PATH='@t6g_mb_lib.t6g(sch_1):page211_i180@pure_quanta.q_diode(chips)';

PART_NAME
 D94 'Q_DIODE_SMLF-SDMK0340L-7-F,IC,BC000340033':;

SECTION_NUMBER 1
 '@T6G_MB_LIB.T6G(SCH_1):PAGE211_I179@PURE_QUANTA.Q_DIODE(CHIPS)':
 C_PATH='@t6g_mb_lib.t6g(sch_1):page211_i179@pure_quanta.q_diode(chips)';

PART_NAME
 D93 'Q_DIODE_SMLF-SDMK0340L-7-F,IC,BC000340033':;

SECTION_NUMBER 1
 '@T6G_MB_LIB.T6G(SCH_1):PAGE211_I161@PURE_QUANTA.Q_DIODE(CHIPS)':
 C_PATH='@t6g_mb_lib.t6g(sch_1):page211_i161@pure_quanta.q_diode(chips)';

PART_NAME
 D92 'Q_DIODE_SMLF-SDMK0340L-7-F,IC,BC000340033':;

SECTION_NUMBER 1
 '@T6G_MB_LIB.T6G(SCH_1):PAGE211_I160@PURE_QUANTA.Q_DIODE(CHIPS)':
 C_PATH='@t6g_mb_lib.t6g(sch_1):page211_i160@pure_quanta.q_diode(chips)';

PART_NAME
 D91 'Q_DIODE_SMLF-SDMK0340L-7-F,IC,BC000340033':;

SECTION_NUMBER 1
 '@T6G_MB_LIB.T6G(SCH_1):PAGE211_I159@PURE_QUANTA.Q_DIODE(CHIPS)':
 C_PATH='@t6g_mb_lib.t6g(sch_1):page211_i159@pure_quanta.q_diode(chips)';

PART_NAME
 D80 'Q_DIODE_SMLF-SDMK0340L-7-F,IC,BC000340033':;

SECTION_NUMBER 1
 '@T6G_MB_LIB.T6G(SCH_1):PAGE211_I142@PURE_QUANTA.Q_DIODE(CHIPS)':
 C_PATH='@t6g_mb_lib.t6g(sch_1):page211_i142@pure_quanta.q_diode(chips)';

PART_NAME
 R3655 'Q_RES_0402LF-4.7K,1%,1/16W,EMPTY,CS24702FB10':;

SECTION_NUMBER 1
 '@T6G_MB_LIB.T6G(SCH_1):PAGE174_I138@PURE_QUANTA.Q_RES(CHIPS)':
 C_PATH='@t6g_mb_lib.t6g(sch_1):page174_i138@pure_quanta.q_res(chips)';

PART_NAME
 R3614 'Q_RES_0402LF-4.7K,1%,1/16W,EMPTY,CS24702FB10':;

SECTION_NUMBER 1
 '@T6G_MB_LIB.T6G(SCH_1):PAGE174_I120@PURE_QUANTA.Q_RES(CHIPS)':
 C_PATH='@t6g_mb_lib.t6g(sch_1):page174_i120@pure_quanta.q_res(chips)';

PART_NAME
 R3612 'Q_RES_0402LF-4.7K,1%,1/16W,EMPTY,CS24702FB10':;

SECTION_NUMBER 1
 '@T6G_MB_LIB.T6G(SCH_1):PAGE174_I111@PURE_QUANTA.Q_RES(CHIPS)':
 C_PATH='@t6g_mb_lib.t6g(sch_1):page174_i111@pure_quanta.q_res(chips)';

PART_NAME
 R3563 'Q_RES_0402LF-4.7K,1%,1/16W,EMPTY,CS24702FB10':;

SECTION_NUMBER 1
 '@T6G_MB_LIB.T6G(SCH_1):PAGE174_I100@PURE_QUANTA.Q_RES(CHIPS)':
 C_PATH='@t6g_mb_lib.t6g(sch_1):page174_i100@pure_quanta.q_res(chips)';

PART_NAME
 R3562 'Q_RES_0402LF-4.7K,1%,1/16W,EMPTY,CS24702FB10':;

SECTION_NUMBER 1
 '@T6G_MB_LIB.T6G(SCH_1):PAGE174_I103@PURE_QUANTA.Q_RES(CHIPS)':
 C_PATH='@t6g_mb_lib.t6g(sch_1):page174_i103@pure_quanta.q_res(chips)';

PART_NAME
 R3492 'Q_RES_0402LF-4.7K,1%,1/16W,EMPTY,CS24702FB10':;

SECTION_NUMBER 1
 '@T6G_MB_LIB.T6G(SCH_1):PAGE174_I61@PURE_QUANTA.Q_RES(CHIPS)':
 C_PATH='@t6g_mb_lib.t6g(sch_1):page174_i61@pure_quanta.q_res(chips)';

PART_NAME
 R3491 'Q_RES_0402LF-4.7K,1%,1/16W,EMPTY,CS24702FB10':;

SECTION_NUMBER 1
 '@T6G_MB_LIB.T6G(SCH_1):PAGE174_I67@PURE_QUANTA.Q_RES(CHIPS)':
 C_PATH='@t6g_mb_lib.t6g(sch_1):page174_i67@pure_quanta.q_res(chips)';

PART_NAME
 R3490 'Q_RES_0402LF-4.7K,1%,1/16W,EMPTY,CS24702FB10':;

SECTION_NUMBER 1
 '@T6G_MB_LIB.T6G(SCH_1):PAGE174_I69@PURE_QUANTA.Q_RES(CHIPS)':
 C_PATH='@t6g_mb_lib.t6g(sch_1):page174_i69@pure_quanta.q_res(chips)';

PART_NAME
 R3489 'Q_RES_0402LF-4.7K,1%,1/16W,EMPTY,CS24702FB10':;

SECTION_NUMBER 1
 '@T6G_MB_LIB.T6G(SCH_1):PAGE174_I72@PURE_QUANTA.Q_RES(CHIPS)':
 C_PATH='@t6g_mb_lib.t6g(sch_1):page174_i72@pure_quanta.q_res(chips)';

PART_NAME
 R1726 'Q_RES_0402LF-4.7K,1%,1/16W,CHIP,CS24702FB10':;

SECTION_NUMBER 1
 '@T6G_MB_LIB.T6G(SCH_1):PAGE174_I82@PURE_QUANTA.Q_RES(CHIPS)':
 C_PATH='@t6g_mb_lib.t6g(sch_1):page174_i82@pure_quanta.q_res(chips)';

PART_NAME
 R1724 'Q_RES_0402LF-4.7K,1%,1/16W,CHIP,CS24702FB10':;

SECTION_NUMBER 1
 '@T6G_MB_LIB.T6G(SCH_1):PAGE174_I84@PURE_QUANTA.Q_RES(CHIPS)':
 C_PATH='@t6g_mb_lib.t6g(sch_1):page174_i84@pure_quanta.q_res(chips)';

PART_NAME
 D90 'Q_DIODE_SMLF-SDMK0340L-7-F,IC,BC000340033':;

SECTION_NUMBER 1
 '@T6G_MB_LIB.T6G(SCH_1):PAGE174_I142@PURE_QUANTA.Q_DIODE(CHIPS)':
 C_PATH='@t6g_mb_lib.t6g(sch_1):page174_i142@pure_quanta.q_diode(chips)';

PART_NAME
 D89 'Q_DIODE_SMLF-SDMK0340L-7-F,IC,BC000340033':;

SECTION_NUMBER 1
 '@T6G_MB_LIB.T6G(SCH_1):PAGE174_I139@PURE_QUANTA.Q_DIODE(CHIPS)':
 C_PATH='@t6g_mb_lib.t6g(sch_1):page174_i139@pure_quanta.q_diode(chips)';

PART_NAME
 D86 'Q_DIODE_SMLF-SDMK0340L-7-F,IC,BC000340033':;

SECTION_NUMBER 1
 '@T6G_MB_LIB.T6G(SCH_1):PAGE174_I135@PURE_QUANTA.Q_DIODE(CHIPS)':
 C_PATH='@t6g_mb_lib.t6g(sch_1):page174_i135@pure_quanta.q_diode(chips)';

PART_NAME
 D85 'Q_DIODE_SMLF-SDMK0340L-7-F,IC,BC000340033':;

SECTION_NUMBER 1
 '@T6G_MB_LIB.T6G(SCH_1):PAGE174_I136@PURE_QUANTA.Q_DIODE(CHIPS)':
 C_PATH='@t6g_mb_lib.t6g(sch_1):page174_i136@pure_quanta.q_diode(chips)';

PART_NAME
 D82 'Q_DIODE_SMLF-SDMK0340L-7-F,IC,BC000340033':;

SECTION_NUMBER 1
 '@T6G_MB_LIB.T6G(SCH_1):PAGE174_I107@PURE_QUANTA.Q_DIODE(CHIPS)':
 C_PATH='@t6g_mb_lib.t6g(sch_1):page174_i107@pure_quanta.q_diode(chips)';

PART_NAME
 D81 'Q_DIODE_SMLF-SDMK0340L-7-F,IC,BC000340033':;

SECTION_NUMBER 1
 '@T6G_MB_LIB.T6G(SCH_1):PAGE174_I108@PURE_QUANTA.Q_DIODE(CHIPS)':
 C_PATH='@t6g_mb_lib.t6g(sch_1):page174_i108@pure_quanta.q_diode(chips)';

PART_NAME
 D77 'Q_DIODE_SMLF-SDMK0340L-7-F,IC,BC000340033':;

SECTION_NUMBER 1
 '@T6G_MB_LIB.T6G(SCH_1):PAGE174_I95@PURE_QUANTA.Q_DIODE(CHIPS)':
 C_PATH='@t6g_mb_lib.t6g(sch_1):page174_i95@pure_quanta.q_diode(chips)';

PART_NAME
 D75 'Q_DIODE_SMLF-SDMK0340L-7-F,IC,BC000340033':;

SECTION_NUMBER 1
 '@T6G_MB_LIB.T6G(SCH_1):PAGE174_I96@PURE_QUANTA.Q_DIODE(CHIPS)':
 C_PATH='@t6g_mb_lib.t6g(sch_1):page174_i96@pure_quanta.q_diode(chips)';

PART_NAME
 D74 'Q_DIODE_SMLF-SDMK0340L-7-F,IC,BC000340033':;

SECTION_NUMBER 1
 '@T6G_MB_LIB.T6G(SCH_1):PAGE174_I97@PURE_QUANTA.Q_DIODE(CHIPS)':
 C_PATH='@t6g_mb_lib.t6g(sch_1):page174_i97@pure_quanta.q_diode(chips)';

PART_NAME
 D73 'Q_DIODE_SMLF-SDMK0340L-7-F,IC,BC000340033':;

SECTION_NUMBER 1
 '@T6G_MB_LIB.T6G(SCH_1):PAGE174_I98@PURE_QUANTA.Q_DIODE(CHIPS)':
 C_PATH='@t6g_mb_lib.t6g(sch_1):page174_i98@pure_quanta.q_diode(chips)';

PART_NAME
 D72 'Q_DIODE_SMLF-SDMK0340L-7-F,IC,BC000340033':;

SECTION_NUMBER 1
 '@T6G_MB_LIB.T6G(SCH_1):PAGE174_I55@PURE_QUANTA.Q_DIODE(CHIPS)':
 C_PATH='@t6g_mb_lib.t6g(sch_1):page174_i55@pure_quanta.q_diode(chips)';

PART_NAME
 D71 'Q_DIODE_SMLF-SDMK0340L-7-F,IC,BC000340033':;

SECTION_NUMBER 1
 '@T6G_MB_LIB.T6G(SCH_1):PAGE174_I56@PURE_QUANTA.Q_DIODE(CHIPS)':
 C_PATH='@t6g_mb_lib.t6g(sch_1):page174_i56@pure_quanta.q_diode(chips)';

PART_NAME
 D70 'Q_DIODE_SMLF-SDMK0340L-7-F,IC,BC000340033':;

SECTION_NUMBER 1
 '@T6G_MB_LIB.T6G(SCH_1):PAGE174_I57@PURE_QUANTA.Q_DIODE(CHIPS)':
 C_PATH='@t6g_mb_lib.t6g(sch_1):page174_i57@pure_quanta.q_diode(chips)';

PART_NAME
 D69 'Q_DIODE_SMLF-SDMK0340L-7-F,IC,BC000340033':;

SECTION_NUMBER 1
 '@T6G_MB_LIB.T6G(SCH_1):PAGE174_I58@PURE_QUANTA.Q_DIODE(CHIPS)':
 C_PATH='@t6g_mb_lib.t6g(sch_1):page174_i58@pure_quanta.q_diode(chips)';

PART_NAME
 D68 'Q_DIODE_SMLF-SDMK0340L-7-F,IC,BC000340033':;

SECTION_NUMBER 1
 '@T6G_MB_LIB.T6G(SCH_1):PAGE174_I63@PURE_QUANTA.Q_DIODE(CHIPS)':
 C_PATH='@t6g_mb_lib.t6g(sch_1):page174_i63@pure_quanta.q_diode(chips)';

PART_NAME
 D67 'Q_DIODE_SMLF-SDMK0340L-7-F,IC,BC000340033':;

SECTION_NUMBER 1
 '@T6G_MB_LIB.T6G(SCH_1):PAGE174_I64@PURE_QUANTA.Q_DIODE(CHIPS)':
 C_PATH='@t6g_mb_lib.t6g(sch_1):page174_i64@pure_quanta.q_diode(chips)';

PART_NAME
 D66 'Q_DIODE_SMLF-SDMK0340L-7-F,IC,BC000340033':;

SECTION_NUMBER 1
 '@T6G_MB_LIB.T6G(SCH_1):PAGE174_I65@PURE_QUANTA.Q_DIODE(CHIPS)':
 C_PATH='@t6g_mb_lib.t6g(sch_1):page174_i65@pure_quanta.q_diode(chips)';

PART_NAME
 D65 'Q_DIODE_SMLF-SDMK0340L-7-F,IC,BC000340033':;

SECTION_NUMBER 1
 '@T6G_MB_LIB.T6G(SCH_1):PAGE174_I66@PURE_QUANTA.Q_DIODE(CHIPS)':
 C_PATH='@t6g_mb_lib.t6g(sch_1):page174_i66@pure_quanta.q_diode(chips)';

PART_NAME
 D64 'Q_DIODE_SMLF-SDMK0340L-7-F,IC,BC000340033':;

SECTION_NUMBER 1
 '@T6G_MB_LIB.T6G(SCH_1):PAGE174_I76@PURE_QUANTA.Q_DIODE(CHIPS)':
 C_PATH='@t6g_mb_lib.t6g(sch_1):page174_i76@pure_quanta.q_diode(chips)';

PART_NAME
 D63 'Q_DIODE_SMLF-SDMK0340L-7-F,IC,BC000340033':;

SECTION_NUMBER 1
 '@T6G_MB_LIB.T6G(SCH_1):PAGE174_I77@PURE_QUANTA.Q_DIODE(CHIPS)':
 C_PATH='@t6g_mb_lib.t6g(sch_1):page174_i77@pure_quanta.q_diode(chips)';

PART_NAME
 D62 'Q_DIODE_SMLF-SDMK0340L-7-F,IC,BC000340033':;

SECTION_NUMBER 1
 '@T6G_MB_LIB.T6G(SCH_1):PAGE174_I78@PURE_QUANTA.Q_DIODE(CHIPS)':
 C_PATH='@t6g_mb_lib.t6g(sch_1):page174_i78@pure_quanta.q_diode(chips)';

PART_NAME
 D61 'Q_DIODE_SMLF-SDMK0340L-7-F,IC,BC000340033':;

SECTION_NUMBER 1
 '@T6G_MB_LIB.T6G(SCH_1):PAGE174_I79@PURE_QUANTA.Q_DIODE(CHIPS)':
 C_PATH='@t6g_mb_lib.t6g(sch_1):page174_i79@pure_quanta.q_diode(chips)';

PART_NAME
 R3704 'Q_RES_0402LF-0,5%,1/16W,CHIP,CS00002JB38':;

SECTION_NUMBER 1
 '@T6G_MB_LIB.T6G(SCH_1):PAGE241_I288@PURE_QUANTA.Q_RES(CHIPS)':
 C_PATH='@t6g_mb_lib.t6g(sch_1):page241_i288@pure_quanta.q_res(chips)';

PART_NAME
 R3654 'Q_RES_0402LF-0,5%,1/16W,EMPTY,CS00002JB38':;

SECTION_NUMBER 1
 '@T6G_MB_LIB.T6G(SCH_1):PAGE241_I276@PURE_QUANTA.Q_RES(CHIPS)':
 C_PATH='@t6g_mb_lib.t6g(sch_1):page241_i276@pure_quanta.q_res(chips)';

PART_NAME
 R3495 'Q_RES_0402LF-33,5%,1/16W,CHIP,CS03302JB29':;

SECTION_NUMBER 1
 '@T6G_MB_LIB.T6G(SCH_1):PAGE241_I273@PURE_QUANTA.Q_RES(CHIPS)':
 C_PATH='@t6g_mb_lib.t6g(sch_1):page241_i273@pure_quanta.q_res(chips)';

PART_NAME
 R1841 'Q_RES_0402LF-10K,1%,1/16W,EMPTY,TMP_QCS31002FB26':;

SECTION_NUMBER 1
 '@T6G_MB_LIB.T6G(SCH_1):PAGE241_I245@PURE_QUANTA.Q_RES(CHIPS)':
 C_PATH='@t6g_mb_lib.t6g(sch_1):page241_i245@pure_quanta.q_res(chips)';

PART_NAME
 R1725 'Q_RES_0402LF-33,5%,1/16W,CHIP,CS03302JB29':;

SECTION_NUMBER 1
 '@T6G_MB_LIB.T6G(SCH_1):PAGE241_I209@PURE_QUANTA.Q_RES(CHIPS)':
 C_PATH='@t6g_mb_lib.t6g(sch_1):page241_i209@pure_quanta.q_res(chips)';

PART_NAME
 R1560 'Q_RES_0402LF-0,5%,1/16W,EMPTY,CS00002JB38':;

SECTION_NUMBER 1
 '@T6G_MB_LIB.T6G(SCH_1):PAGE241_I269@PURE_QUANTA.Q_RES(CHIPS)':
 C_PATH='@t6g_mb_lib.t6g(sch_1):page241_i269@pure_quanta.q_res(chips)';

PART_NAME
 R1559 'Q_RES_0402LF-0,5%,1/16W,EMPTY,CS00002JB38':;

SECTION_NUMBER 1
 '@T6G_MB_LIB.T6G(SCH_1):PAGE241_I268@PURE_QUANTA.Q_RES(CHIPS)':
 C_PATH='@t6g_mb_lib.t6g(sch_1):page241_i268@pure_quanta.q_res(chips)';

PART_NAME
 R1550 'Q_RES_0402LF-4.7K,1%,1/16W,CHIP,CS24702FB10':;

SECTION_NUMBER 1
 '@T6G_MB_LIB.T6G(SCH_1):PAGE241_I264@PURE_QUANTA.Q_RES(CHIPS)':
 C_PATH='@t6g_mb_lib.t6g(sch_1):page241_i264@pure_quanta.q_res(chips)';

PART_NAME
 R1549 'Q_RES_0402LF-4.7K,1%,1/16W,CHIP,CS24702FB10':;

SECTION_NUMBER 1
 '@T6G_MB_LIB.T6G(SCH_1):PAGE241_I265@PURE_QUANTA.Q_RES(CHIPS)':
 C_PATH='@t6g_mb_lib.t6g(sch_1):page241_i265@pure_quanta.q_res(chips)';

PART_NAME
 R700 'Q_RES_0402LF-0,5%,1/16W,CHIP,CS00002JB38':;

SECTION_NUMBER 1
 '@T6G_MB_LIB.T6G(SCH_1):PAGE241_I234@PURE_QUANTA.Q_RES(CHIPS)':
 C_PATH='@t6g_mb_lib.t6g(sch_1):page241_i234@pure_quanta.q_res(chips)';

PART_NAME
 R366 'Q_RES_0402LF-332,1%,1/16W,CHIP,CS13322FB10':;

SECTION_NUMBER 1
 '@T6G_MB_LIB.T6G(SCH_1):PAGE241_I241@PURE_QUANTA.Q_RES(CHIPS)':
 C_PATH='@t6g_mb_lib.t6g(sch_1):page241_i241@pure_quanta.q_res(chips)';

PART_NAME
 R365 'Q_RES_0402LF-0,5%,1/16W,CHIP,CS00002JB38':;

SECTION_NUMBER 1
 '@T6G_MB_LIB.T6G(SCH_1):PAGE241_I240@PURE_QUANTA.Q_RES(CHIPS)':
 C_PATH='@t6g_mb_lib.t6g(sch_1):page241_i240@pure_quanta.q_res(chips)';

PART_NAME
 Q114 'MOSFET_PCH_GDS_ESD_PROTECTED-PJA3415AE,SMLF,IC,BAM34150008':;

SECTION_NUMBER 1
 '@T6G_MB_LIB.T6G(SCH_1):PAGE241_I239@PURE_QUANTA.MOSFET_PCH_GDS_ESD_PROTECTED(CHIPS)':
 C_PATH='@t6g_mb_lib.t6g(sch_1):page241_i239@pure_quanta.mosfet_pch_gds_esd_prot~
ected(chips)';

PART_NAME
 D6 'Q_LED_SMLF-LED_RED,19-217/R6C-P1Q2/3T,IC,BERD0034Z07':;

SECTION_NUMBER 1
 '@T6G_MB_LIB.T6G(SCH_1):PAGE241_I246@PURE_QUANTA.Q_LED(CHIPS)':
 C_PATH='@t6g_mb_lib.t6g(sch_1):page241_i246@pure_quanta.q_led(chips)';

PART_NAME
 R4226 'Q_RES_0402LF-1M,5%,1/16W,CHIP,CS51002JB21':;

SECTION_NUMBER 1
 '@T6G_MB_LIB.T6G(SCH_1):PAGE260_I20@PURE_QUANTA.Q_RES(CHIPS)':
 C_PATH='@t6g_mb_lib.t6g(sch_1):page260_i20@pure_quanta.q_res(chips)';

PART_NAME
 R4225 'Q_RES_0402LF-1M,5%,1/16W,CHIP,CS51002JB21':;

SECTION_NUMBER 1
 '@T6G_MB_LIB.T6G(SCH_1):PAGE260_I21@PURE_QUANTA.Q_RES(CHIPS)':
 C_PATH='@t6g_mb_lib.t6g(sch_1):page260_i21@pure_quanta.q_res(chips)';

PART_NAME
 R4106 'Q_RES_0402LF-4.7K,5%,1/16W,CHIP,TMP_QCS24702JB38':;

SECTION_NUMBER 1
 '@T6G_MB_LIB.T6G(SCH_1):PAGE260_I27@PURE_QUANTA.Q_RES(CHIPS)':
 C_PATH='@t6g_mb_lib.t6g(sch_1):page260_i27@pure_quanta.q_res(chips)';

PART_NAME
 R2458 'Q_RES_0402LF-0,5%,1/16W,CHIP,CS00002JB38':;

SECTION_NUMBER 1
 '@T6G_MB_LIB.T6G(SCH_1):PAGE260_I5@PURE_QUANTA.Q_RES(CHIPS)':
 C_PATH='@t6g_mb_lib.t6g(sch_1):page260_i5@pure_quanta.q_res(chips)';

PART_NAME
 Q66 'MOSFET_NCH_DUAL-2N7002KDW,SMLF,IC,BAM70020047':;

SECTION_NUMBER 1
 '@T6G_MB_LIB.T6G(SCH_1):PAGE260_I10@PURE_QUANTA.MOSFET_NCH_DUAL(CHIPS)':
 C_PATH='@t6g_mb_lib.t6g(sch_1):page260_i10@pure_quanta.mosfet_nch_dual(chips)';

SECTION_NUMBER 2
 '@T6G_MB_LIB.T6G(SCH_1):PAGE260_I11@PURE_QUANTA.MOSFET_NCH_DUAL(CHIPS)':
 C_PATH='@t6g_mb_lib.t6g(sch_1):page260_i11@pure_quanta.mosfet_nch_dual(chips)';

PART_NAME
 JP21 'SCONN10_504290054N001-SCONN10_50429-0054N-001,SMLF,IO,DFHD05MR223':;

SECTION_NUMBER 1
 '@T6G_MB_LIB.T6G(SCH_1):PAGE260_I19@PURE_QUANTA.SCONN10_504290054N001(CHIPS)':
 C_PATH='@t6g_mb_lib.t6g(sch_1):page260_i19@pure_quanta.sconn10_504290054n001(ch~
ips)';

PART_NAME
 D78 'Q_DIODE_SMLF-SDMK0340L-7-F,IC,BC000340033':;

SECTION_NUMBER 1
 '@T6G_MB_LIB.T6G(SCH_1):PAGE260_I24@PURE_QUANTA.Q_DIODE(CHIPS)':
 C_PATH='@t6g_mb_lib.t6g(sch_1):page260_i24@pure_quanta.q_diode(chips)';

PART_NAME
 C4485 'Q_CAP_C0402-1UF,25V,10%,EMPTY,CH-104K6B00':;

SECTION_NUMBER 1
 '@T6G_MB_LIB.T6G(SCH_1):PAGE260_I14@PURE_QUANTA.Q_CAP(CHIPS)':
 C_PATH='@t6g_mb_lib.t6g(sch_1):page260_i14@pure_quanta.q_cap(chips)';

PART_NAME
 R3847 'Q_RES_0402LF-47K,1%,1/16W,CHIP,TMP_QCS34702FB11':;

SECTION_NUMBER 1
 '@T6G_MB_LIB.T6G(SCH_1):PAGE251_I50@PURE_QUANTA.Q_RES(CHIPS)':
 C_PATH='@t6g_mb_lib.t6g(sch_1):page251_i50@pure_quanta.q_res(chips)';

PART_NAME
 R3609 'Q_RES_0402LF-10K,1%,1/16W,CHIP,TMP_QCS31002FB26':;

SECTION_NUMBER 1
 '@T6G_MB_LIB.T6G(SCH_1):PAGE251_I25@PURE_QUANTA.Q_RES(CHIPS)':
 C_PATH='@t6g_mb_lib.t6g(sch_1):page251_i25@pure_quanta.q_res(chips)';

PART_NAME
 R3607 'Q_RES_0402LF-10K,1%,1/16W,CHIP,TMP_QCS31002FB26':;

SECTION_NUMBER 1
 '@T6G_MB_LIB.T6G(SCH_1):PAGE251_I9@PURE_QUANTA.Q_RES(CHIPS)':
 C_PATH='@t6g_mb_lib.t6g(sch_1):page251_i9@pure_quanta.q_res(chips)';

PART_NAME
 R3605 'Q_RES_0402LF-10K,1%,1/16W,CHIP,TMP_QCS31002FB26':;

SECTION_NUMBER 1
 '@T6G_MB_LIB.T6G(SCH_1):PAGE251_I28@PURE_QUANTA.Q_RES(CHIPS)':
 C_PATH='@t6g_mb_lib.t6g(sch_1):page251_i28@pure_quanta.q_res(chips)';

PART_NAME
 R3603 'Q_RES_0402LF-10K,1%,1/16W,CHIP,TMP_QCS31002FB26':;

SECTION_NUMBER 1
 '@T6G_MB_LIB.T6G(SCH_1):PAGE251_I12@PURE_QUANTA.Q_RES(CHIPS)':
 C_PATH='@t6g_mb_lib.t6g(sch_1):page251_i12@pure_quanta.q_res(chips)';

PART_NAME
 R3601 'Q_RES_0402LF-0,5%,1/16W,CHIP,CS00002JB38':;

SECTION_NUMBER 1
 '@T6G_MB_LIB.T6G(SCH_1):PAGE251_I38@PURE_QUANTA.Q_RES(CHIPS)':
 C_PATH='@t6g_mb_lib.t6g(sch_1):page251_i38@pure_quanta.q_res(chips)';

PART_NAME
 R3599 'Q_RES_0402LF-0,5%,1/16W,CHIP,CS00002JB38':;

SECTION_NUMBER 1
 '@T6G_MB_LIB.T6G(SCH_1):PAGE251_I18@PURE_QUANTA.Q_RES(CHIPS)':
 C_PATH='@t6g_mb_lib.t6g(sch_1):page251_i18@pure_quanta.q_res(chips)';

PART_NAME
 R1329 'Q_RES_0402LF-100K,1%,1/16W,CHIP,TMP_QCS41002FB28':;

SECTION_NUMBER 1
 '@T6G_MB_LIB.T6G(SCH_1):PAGE251_I46@PURE_QUANTA.Q_RES(CHIPS)':
 C_PATH='@t6g_mb_lib.t6g(sch_1):page251_i46@pure_quanta.q_res(chips)';

PART_NAME
 R1328 'Q_RES_0402LF-200K,1%,1/16W,CHIP,CS42002FB12':;

SECTION_NUMBER 1
 '@T6G_MB_LIB.T6G(SCH_1):PAGE251_I43@PURE_QUANTA.Q_RES(CHIPS)':
 C_PATH='@t6g_mb_lib.t6g(sch_1):page251_i43@pure_quanta.q_res(chips)';

PART_NAME
 Q129 'MOSFET_NCH_DUAL-2N7002KDW,SMLF,IC,BAM70020047':;

SECTION_NUMBER 1
 '@T6G_MB_LIB.T6G(SCH_1):PAGE251_I37@PURE_QUANTA.MOSFET_NCH_DUAL(CHIPS)':
 C_PATH='@t6g_mb_lib.t6g(sch_1):page251_i37@pure_quanta.mosfet_nch_dual(chips)';

SECTION_NUMBER 2
 '@T6G_MB_LIB.T6G(SCH_1):PAGE251_I32@PURE_QUANTA.MOSFET_NCH_DUAL(CHIPS)':
 C_PATH='@t6g_mb_lib.t6g(sch_1):page251_i32@pure_quanta.mosfet_nch_dual(chips)';

PART_NAME
 Q127 'MOSFET_NCH_DUAL-2N7002KDW,SMLF,IC,BAM70020047':;

SECTION_NUMBER 1
 '@T6G_MB_LIB.T6G(SCH_1):PAGE251_I17@PURE_QUANTA.MOSFET_NCH_DUAL(CHIPS)':
 C_PATH='@t6g_mb_lib.t6g(sch_1):page251_i17@pure_quanta.mosfet_nch_dual(chips)';

SECTION_NUMBER 2
 '@T6G_MB_LIB.T6G(SCH_1):PAGE251_I10@PURE_QUANTA.MOSFET_NCH_DUAL(CHIPS)':
 C_PATH='@t6g_mb_lib.t6g(sch_1):page251_i10@pure_quanta.mosfet_nch_dual(chips)';

PART_NAME
 Q43 'MOSFET_N_GSD-DMG6968U-7,SMLF,IC,BAM69680000':;

SECTION_NUMBER 1
 '@T6G_MB_LIB.T6G(SCH_1):PAGE251_I44@PURE_QUANTA.MOSFET_N_GSD(CHIPS)':
 C_PATH='@t6g_mb_lib.t6g(sch_1):page251_i44@pure_quanta.mosfet_n_gsd(chips)';

PART_NAME
 C2929 'Q_CAP_0402-100PF,50V,5%,NPO,CH11006JB00':;

SECTION_NUMBER 1
 '@T6G_MB_LIB.T6G(SCH_1):PAGE251_I45@PURE_QUANTA.Q_CAP(CHIPS)':
 C_PATH='@t6g_mb_lib.t6g(sch_1):page251_i45@pure_quanta.q_cap(chips)';

PART_NAME
 C2928 'Q_CAP_0402-0.22UF,16V,10%,EMPTY,CH4223K1B00':;

SECTION_NUMBER 1
 '@T6G_MB_LIB.T6G(SCH_1):PAGE251_I48@PURE_QUANTA.Q_CAP(CHIPS)':
 C_PATH='@t6g_mb_lib.t6g(sch_1):page251_i48@pure_quanta.q_cap(chips)';

PART_NAME
 U197 'PCA9848PW-PCA9848PW,SMLF,IC,AL009848K00':;

SECTION_NUMBER 1
 '@T6G_MB_LIB.T6G(SCH_1):PAGE288_I61@PURE_QUANTA.PCA9848PW(CHIPS)':
 C_PATH='@t6g_mb_lib.t6g(sch_1):page288_i61@pure_quanta.pca9848pw(chips)';

PART_NAME
 R3819 'Q_RES_0402LF-10K,1%,1/16W,CHIP,TMP_QCS31002FB26':;

SECTION_NUMBER 1
 '@T6G_MB_LIB.T6G(SCH_1):PAGE288_I147@PURE_QUANTA.Q_RES(CHIPS)':
 C_PATH='@t6g_mb_lib.t6g(sch_1):page288_i147@pure_quanta.q_res(chips)';

PART_NAME
 R3818 'Q_RES_0402LF-10K,1%,1/16W,CHIP,TMP_QCS31002FB26':;

SECTION_NUMBER 1
 '@T6G_MB_LIB.T6G(SCH_1):PAGE288_I148@PURE_QUANTA.Q_RES(CHIPS)':
 C_PATH='@t6g_mb_lib.t6g(sch_1):page288_i148@pure_quanta.q_res(chips)';

PART_NAME
 R3817 'Q_RES_0402LF-10K,1%,1/16W,CHIP,TMP_QCS31002FB26':;

SECTION_NUMBER 1
 '@T6G_MB_LIB.T6G(SCH_1):PAGE288_I145@PURE_QUANTA.Q_RES(CHIPS)':
 C_PATH='@t6g_mb_lib.t6g(sch_1):page288_i145@pure_quanta.q_res(chips)';

PART_NAME
 R3816 'Q_RES_0402LF-10K,1%,1/16W,CHIP,TMP_QCS31002FB26':;

SECTION_NUMBER 1
 '@T6G_MB_LIB.T6G(SCH_1):PAGE288_I146@PURE_QUANTA.Q_RES(CHIPS)':
 C_PATH='@t6g_mb_lib.t6g(sch_1):page288_i146@pure_quanta.q_res(chips)';

PART_NAME
 R3815 'Q_RES_0402LF-10K,1%,1/16W,CHIP,TMP_QCS31002FB26':;

SECTION_NUMBER 1
 '@T6G_MB_LIB.T6G(SCH_1):PAGE288_I143@PURE_QUANTA.Q_RES(CHIPS)':
 C_PATH='@t6g_mb_lib.t6g(sch_1):page288_i143@pure_quanta.q_res(chips)';

PART_NAME
 R3814 'Q_RES_0402LF-10K,1%,1/16W,CHIP,TMP_QCS31002FB26':;

SECTION_NUMBER 1
 '@T6G_MB_LIB.T6G(SCH_1):PAGE288_I144@PURE_QUANTA.Q_RES(CHIPS)':
 C_PATH='@t6g_mb_lib.t6g(sch_1):page288_i144@pure_quanta.q_res(chips)';

PART_NAME
 R3813 'Q_RES_0402LF-10K,1%,1/16W,CHIP,TMP_QCS31002FB26':;

SECTION_NUMBER 1
 '@T6G_MB_LIB.T6G(SCH_1):PAGE288_I141@PURE_QUANTA.Q_RES(CHIPS)':
 C_PATH='@t6g_mb_lib.t6g(sch_1):page288_i141@pure_quanta.q_res(chips)';

PART_NAME
 R3812 'Q_RES_0402LF-10K,1%,1/16W,CHIP,TMP_QCS31002FB26':;

SECTION_NUMBER 1
 '@T6G_MB_LIB.T6G(SCH_1):PAGE288_I142@PURE_QUANTA.Q_RES(CHIPS)':
 C_PATH='@t6g_mb_lib.t6g(sch_1):page288_i142@pure_quanta.q_res(chips)';

PART_NAME
 R3811 'Q_RES_0402LF-10K,1%,1/16W,CHIP,TMP_QCS31002FB26':;

SECTION_NUMBER 1
 '@T6G_MB_LIB.T6G(SCH_1):PAGE288_I139@PURE_QUANTA.Q_RES(CHIPS)':
 C_PATH='@t6g_mb_lib.t6g(sch_1):page288_i139@pure_quanta.q_res(chips)';

PART_NAME
 R3810 'Q_RES_0402LF-10K,1%,1/16W,CHIP,TMP_QCS31002FB26':;

SECTION_NUMBER 1
 '@T6G_MB_LIB.T6G(SCH_1):PAGE288_I140@PURE_QUANTA.Q_RES(CHIPS)':
 C_PATH='@t6g_mb_lib.t6g(sch_1):page288_i140@pure_quanta.q_res(chips)';

PART_NAME
 R3809 'Q_RES_0402LF-10K,1%,1/16W,CHIP,TMP_QCS31002FB26':;

SECTION_NUMBER 1
 '@T6G_MB_LIB.T6G(SCH_1):PAGE288_I137@PURE_QUANTA.Q_RES(CHIPS)':
 C_PATH='@t6g_mb_lib.t6g(sch_1):page288_i137@pure_quanta.q_res(chips)';

PART_NAME
 R3808 'Q_RES_0402LF-10K,1%,1/16W,CHIP,TMP_QCS31002FB26':;

SECTION_NUMBER 1
 '@T6G_MB_LIB.T6G(SCH_1):PAGE288_I138@PURE_QUANTA.Q_RES(CHIPS)':
 C_PATH='@t6g_mb_lib.t6g(sch_1):page288_i138@pure_quanta.q_res(chips)';

PART_NAME
 R3807 'Q_RES_0402LF-10K,1%,1/16W,CHIP,TMP_QCS31002FB26':;

SECTION_NUMBER 1
 '@T6G_MB_LIB.T6G(SCH_1):PAGE288_I136@PURE_QUANTA.Q_RES(CHIPS)':
 C_PATH='@t6g_mb_lib.t6g(sch_1):page288_i136@pure_quanta.q_res(chips)';

PART_NAME
 R3806 'Q_RES_0402LF-10K,1%,1/16W,CHIP,TMP_QCS31002FB26':;

SECTION_NUMBER 1
 '@T6G_MB_LIB.T6G(SCH_1):PAGE288_I135@PURE_QUANTA.Q_RES(CHIPS)':
 C_PATH='@t6g_mb_lib.t6g(sch_1):page288_i135@pure_quanta.q_res(chips)';

PART_NAME
 R3804 'Q_RES_0402LF-10K,1%,1/16W,CHIP,TMP_QCS31002FB26':;

SECTION_NUMBER 1
 '@T6G_MB_LIB.T6G(SCH_1):PAGE288_I132@PURE_QUANTA.Q_RES(CHIPS)':
 C_PATH='@t6g_mb_lib.t6g(sch_1):page288_i132@pure_quanta.q_res(chips)';

PART_NAME
 R3803 'Q_RES_0402LF-10K,1%,1/16W,CHIP,TMP_QCS31002FB26':;

SECTION_NUMBER 1
 '@T6G_MB_LIB.T6G(SCH_1):PAGE288_I133@PURE_QUANTA.Q_RES(CHIPS)':
 C_PATH='@t6g_mb_lib.t6g(sch_1):page288_i133@pure_quanta.q_res(chips)';

PART_NAME
 R3802 'Q_RES_0402LF-10K,1%,1/16W,CHIP,TMP_QCS31002FB26':;

SECTION_NUMBER 1
 '@T6G_MB_LIB.T6G(SCH_1):PAGE288_I63@PURE_QUANTA.Q_RES(CHIPS)':
 C_PATH='@t6g_mb_lib.t6g(sch_1):page288_i63@pure_quanta.q_res(chips)';

PART_NAME
 R3801 'Q_RES_0402LF-1K,1%,1/16W,EMPTY,TMP_QCS21002FB24':;

SECTION_NUMBER 1
 '@T6G_MB_LIB.T6G(SCH_1):PAGE288_I69@PURE_QUANTA.Q_RES(CHIPS)':
 C_PATH='@t6g_mb_lib.t6g(sch_1):page288_i69@pure_quanta.q_res(chips)';

PART_NAME
 R3800 'Q_RES_0402LF-10K,1%,1/16W,CHIP,TMP_QCS31002FB26':;

SECTION_NUMBER 1
 '@T6G_MB_LIB.T6G(SCH_1):PAGE288_I66@PURE_QUANTA.Q_RES(CHIPS)':
 C_PATH='@t6g_mb_lib.t6g(sch_1):page288_i66@pure_quanta.q_res(chips)';

PART_NAME
 R3799 'Q_RES_0402LF-1K,1%,1/16W,EMPTY,TMP_QCS21002FB24':;

SECTION_NUMBER 1
 '@T6G_MB_LIB.T6G(SCH_1):PAGE288_I71@PURE_QUANTA.Q_RES(CHIPS)':
 C_PATH='@t6g_mb_lib.t6g(sch_1):page288_i71@pure_quanta.q_res(chips)';

PART_NAME
 R3798 'Q_RES_0402LF-10K,1%,1/16W,CHIP,TMP_QCS31002FB26':;

SECTION_NUMBER 1
 '@T6G_MB_LIB.T6G(SCH_1):PAGE288_I68@PURE_QUANTA.Q_RES(CHIPS)':
 C_PATH='@t6g_mb_lib.t6g(sch_1):page288_i68@pure_quanta.q_res(chips)';

PART_NAME
 R2321 'Q_RES_0402LF-33,5%,1/16W,CHIP,CS03302JB29':;

SECTION_NUMBER 1
 '@T6G_MB_LIB.T6G(SCH_1):PAGE288_I55@PURE_QUANTA.Q_RES(CHIPS)':
 C_PATH='@t6g_mb_lib.t6g(sch_1):page288_i55@pure_quanta.q_res(chips)';

PART_NAME
 R2320 'Q_RES_0402LF-33,5%,1/16W,CHIP,CS03302JB29':;

SECTION_NUMBER 1
 '@T6G_MB_LIB.T6G(SCH_1):PAGE288_I54@PURE_QUANTA.Q_RES(CHIPS)':
 C_PATH='@t6g_mb_lib.t6g(sch_1):page288_i54@pure_quanta.q_res(chips)';

PART_NAME
 PJP2 'CONN3_210HP1030BR1-CONN3_210-HP1-030BR1,THLF,IO,DFHD03MS213':;

SECTION_NUMBER 1
 '@T6G_MB_LIB.T6G(SCH_1):PAGE288_I100@PURE_QUANTA.CONN3_210HP1030BR1(CHIPS)':
 C_PATH='@t6g_mb_lib.t6g(sch_1):page288_i100@pure_quanta.conn3_210hp1030br1(chip~
s)';

PART_NAME
 C2927 'Q_CAP_0402-0.1UF,25V,10%,X7R,CH4104K1B00':;

SECTION_NUMBER 1
 '@T6G_MB_LIB.T6G(SCH_1):PAGE288_I59@PURE_QUANTA.Q_CAP(CHIPS)':
 C_PATH='@t6g_mb_lib.t6g(sch_1):page288_i59@pure_quanta.q_cap(chips)';

PART_NAME
 R479 'Q_RES_0402LF-33,5%,1/16W,CHIP,CS03302JB29':;

SECTION_NUMBER 1
 '@T6G_MB_LIB.T6G(SCH_1):PAGE270_I194@PURE_QUANTA.Q_RES(CHIPS)':
 C_PATH='@t6g_mb_lib.t6g(sch_1):page270_i194@pure_quanta.q_res(chips)';

PART_NAME
 R478 'Q_RES_0402LF-33,5%,1/16W,CHIP,CS03302JB29':;

SECTION_NUMBER 1
 '@T6G_MB_LIB.T6G(SCH_1):PAGE270_I196@PURE_QUANTA.Q_RES(CHIPS)':
 C_PATH='@t6g_mb_lib.t6g(sch_1):page270_i196@pure_quanta.q_res(chips)';

PART_NAME
 JP12 'CONN6_G88MP0610282REU-CONN6_G88MP0610282REU,THLF,IO,DFHD06MS234':;

SECTION_NUMBER 1
 '@T6G_MB_LIB.T6G(SCH_1):PAGE270_I4@PURE_QUANTA.CONN6_G88MP0610282REU(CHIPS)':
 C_PATH='@t6g_mb_lib.t6g(sch_1):page270_i4@pure_quanta.conn6_g88mp0610282reu(chi~
ps)';

PART_NAME
 JP3 'CONN6_G88MP0610282REU-CONN6_G88MP0610282REU,THLF,IO,DFHD06MS234':;

SECTION_NUMBER 1
 '@T6G_MB_LIB.T6G(SCH_1):PAGE270_I11@PURE_QUANTA.CONN6_G88MP0610282REU(CHIPS)':
 C_PATH='@t6g_mb_lib.t6g(sch_1):page270_i11@pure_quanta.conn6_g88mp0610282reu(ch~
ips)';

PART_NAME
 J93 'CONN24_G88MP2410282REU-CONN24_G88MP2410282REU,THLF,IO,DFHD24MS065':;

SECTION_NUMBER 1
 '@T6G_MB_LIB.T6G(SCH_1):PAGE270_I94@PURE_QUANTA.CONN24_G88MP2410282REU(CHIPS)':
 C_PATH='@t6g_mb_lib.t6g(sch_1):page270_i94@pure_quanta.conn24_g88mp2410282reu(c~
hips)';

PART_NAME
 J92 'CONN24_G88MP2410282REU-CONN24_G88MP2410282REU,THLF,IO,DFHD24MS065':;

SECTION_NUMBER 1
 '@T6G_MB_LIB.T6G(SCH_1):PAGE270_I97@PURE_QUANTA.CONN24_G88MP2410282REU(CHIPS)':
 C_PATH='@t6g_mb_lib.t6g(sch_1):page270_i97@pure_quanta.conn24_g88mp2410282reu(c~
hips)';

PART_NAME
 J33 'SCONN26_504290130NV01-SCONN26_50429-0130N-V01,SMLF,IO,DFHD13MR075':;

SECTION_NUMBER 1
 '@T6G_MB_LIB.T6G(SCH_1):PAGE270_I177@PURE_QUANTA.SCONN26_504290130NV01(CHIPS)':
 C_PATH='@t6g_mb_lib.t6g(sch_1):page270_i177@pure_quanta.sconn26_504290130nv01(c~
hips)';

PART_NAME
 C2910 'Q_CAP_0402-0.1UF,25V,10%,X7R,CH4104K1B00':;

SECTION_NUMBER 1
 '@T6G_MB_LIB.T6G(SCH_1):PAGE270_I228@PURE_QUANTA.Q_CAP(CHIPS)':
 C_PATH='@t6g_mb_lib.t6g(sch_1):page270_i228@pure_quanta.q_cap(chips)';

PART_NAME
 C2909 'Q_CAP_0402-0.1UF,25V,10%,X7R,CH4104K1B00':;

SECTION_NUMBER 1
 '@T6G_MB_LIB.T6G(SCH_1):PAGE270_I225@PURE_QUANTA.Q_CAP(CHIPS)':
 C_PATH='@t6g_mb_lib.t6g(sch_1):page270_i225@pure_quanta.q_cap(chips)';

PART_NAME
 C2908 'Q_CAP_0402-0.1UF,25V,10%,X7R,CH4104K1B00':;

SECTION_NUMBER 1
 '@T6G_MB_LIB.T6G(SCH_1):PAGE270_I226@PURE_QUANTA.Q_CAP(CHIPS)':
 C_PATH='@t6g_mb_lib.t6g(sch_1):page270_i226@pure_quanta.q_cap(chips)';

PART_NAME
 C2907 'Q_CAP_0402-0.1UF,25V,10%,X7R,CH4104K1B00':;

SECTION_NUMBER 1
 '@T6G_MB_LIB.T6G(SCH_1):PAGE270_I235@PURE_QUANTA.Q_CAP(CHIPS)':
 C_PATH='@t6g_mb_lib.t6g(sch_1):page270_i235@pure_quanta.q_cap(chips)';

PART_NAME
 C2906 'Q_CAP_C0402-1UF,25V,10%,X6S,CH5104KEB02':;

SECTION_NUMBER 1
 '@T6G_MB_LIB.T6G(SCH_1):PAGE270_I237@PURE_QUANTA.Q_CAP(CHIPS)':
 C_PATH='@t6g_mb_lib.t6g(sch_1):page270_i237@pure_quanta.q_cap(chips)';

PART_NAME
 C2905 'Q_CAPP_RDLF-270UF,16V,20%,ALUM,CC72703MD23':;

SECTION_NUMBER 1
 '@T6G_MB_LIB.T6G(SCH_1):PAGE270_I210@PURE_QUANTA.Q_CAPP(CHIPS)':
 C_PATH='@t6g_mb_lib.t6g(sch_1):page270_i210@pure_quanta.q_capp(chips)';

PART_NAME
 C2904 'Q_CAPP_RDLF-270UF,16V,20%,ALUM,CC72703MD23':;

SECTION_NUMBER 1
 '@T6G_MB_LIB.T6G(SCH_1):PAGE270_I207@PURE_QUANTA.Q_CAPP(CHIPS)':
 C_PATH='@t6g_mb_lib.t6g(sch_1):page270_i207@pure_quanta.q_capp(chips)';

PART_NAME
 C2903 'Q_CAP_0402-0.1UF,25V,10%,X7R,CH4104K1B00':;

SECTION_NUMBER 1
 '@T6G_MB_LIB.T6G(SCH_1):PAGE270_I214@PURE_QUANTA.Q_CAP(CHIPS)':
 C_PATH='@t6g_mb_lib.t6g(sch_1):page270_i214@pure_quanta.q_cap(chips)';

PART_NAME
 C2902 'Q_CAP_0402-0.1UF,25V,10%,X7R,CH4104K1B00':;

SECTION_NUMBER 1
 '@T6G_MB_LIB.T6G(SCH_1):PAGE270_I215@PURE_QUANTA.Q_CAP(CHIPS)':
 C_PATH='@t6g_mb_lib.t6g(sch_1):page270_i215@pure_quanta.q_cap(chips)';

PART_NAME
 C2901 'Q_CAP_0402-0.1UF,25V,10%,X7R,CH4104K1B00':;

SECTION_NUMBER 1
 '@T6G_MB_LIB.T6G(SCH_1):PAGE270_I218@PURE_QUANTA.Q_CAP(CHIPS)':
 C_PATH='@t6g_mb_lib.t6g(sch_1):page270_i218@pure_quanta.q_cap(chips)';

PART_NAME
 C2900 'Q_CAP_0402-0.1UF,25V,10%,X7R,CH4104K1B00':;

SECTION_NUMBER 1
 '@T6G_MB_LIB.T6G(SCH_1):PAGE270_I219@PURE_QUANTA.Q_CAP(CHIPS)':
 C_PATH='@t6g_mb_lib.t6g(sch_1):page270_i219@pure_quanta.q_cap(chips)';

PART_NAME
 C2899 'Q_CAP_C0402-1UF,25V,10%,X6S,CH5104KEB02':;

SECTION_NUMBER 1
 '@T6G_MB_LIB.T6G(SCH_1):PAGE270_I224@PURE_QUANTA.Q_CAP(CHIPS)':
 C_PATH='@t6g_mb_lib.t6g(sch_1):page270_i224@pure_quanta.q_cap(chips)';

PART_NAME
 U193 'M24C64WMN6TP-M24C64-WMN6TP,SMLF,IC,AKE3C8B0619':;

SECTION_NUMBER 1
 '@T6G_MB_LIB.T6G(SCH_1):PAGE214_I24@PURE_QUANTA.M24C64WMN6TP(CHIPS)':
 C_PATH='@t6g_mb_lib.t6g(sch_1):page214_i24@pure_quanta.m24c64wmn6tp(chips)';

PART_NAME
 R3542 'Q_RES_0402LF-100,5%,1/16W,CHIP,TMP_QCS11002JB32':;

SECTION_NUMBER 1
 '@T6G_MB_LIB.T6G(SCH_1):PAGE214_I13@PURE_QUANTA.Q_RES(CHIPS)':
 C_PATH='@t6g_mb_lib.t6g(sch_1):page214_i13@pure_quanta.q_res(chips)';

PART_NAME
 R3541 'Q_RES_0402LF-100,5%,1/16W,CHIP,TMP_QCS11002JB32':;

SECTION_NUMBER 1
 '@T6G_MB_LIB.T6G(SCH_1):PAGE214_I7@PURE_QUANTA.Q_RES(CHIPS)':
 C_PATH='@t6g_mb_lib.t6g(sch_1):page214_i7@pure_quanta.q_res(chips)';

PART_NAME
 R3540 'Q_RES_0402LF-4.7K,5%,1/16W,EMPTY,TMP_QCS24702JB38':;

SECTION_NUMBER 1
 '@T6G_MB_LIB.T6G(SCH_1):PAGE214_I9@PURE_QUANTA.Q_RES(CHIPS)':
 C_PATH='@t6g_mb_lib.t6g(sch_1):page214_i9@pure_quanta.q_res(chips)';

PART_NAME
 R3539 'Q_RES_0402LF-100,5%,1/16W,CHIP,TMP_QCS11002JB32':;

SECTION_NUMBER 1
 '@T6G_MB_LIB.T6G(SCH_1):PAGE214_I5@PURE_QUANTA.Q_RES(CHIPS)':
 C_PATH='@t6g_mb_lib.t6g(sch_1):page214_i5@pure_quanta.q_res(chips)';

PART_NAME
 R3538 'Q_RES_0402LF-4.7K,5%,1/16W,EMPTY,TMP_QCS24702JB38':;

SECTION_NUMBER 1
 '@T6G_MB_LIB.T6G(SCH_1):PAGE214_I8@PURE_QUANTA.Q_RES(CHIPS)':
 C_PATH='@t6g_mb_lib.t6g(sch_1):page214_i8@pure_quanta.q_res(chips)';

PART_NAME
 R3537 'Q_RES_0402LF-100,5%,1/16W,EMPTY,TMP_QCS11002JB32':;

SECTION_NUMBER 1
 '@T6G_MB_LIB.T6G(SCH_1):PAGE214_I2@PURE_QUANTA.Q_RES(CHIPS)':
 C_PATH='@t6g_mb_lib.t6g(sch_1):page214_i2@pure_quanta.q_res(chips)';

PART_NAME
 R3536 'Q_RES_0402LF-4.7K,5%,1/16W,CHIP,TMP_QCS24702JB38':;

SECTION_NUMBER 1
 '@T6G_MB_LIB.T6G(SCH_1):PAGE214_I3@PURE_QUANTA.Q_RES(CHIPS)':
 C_PATH='@t6g_mb_lib.t6g(sch_1):page214_i3@pure_quanta.q_res(chips)';

PART_NAME
 C2824 'Q_CAP_C0402-0.1UF,16V,10%,X7R,CH4103K1B08':;

SECTION_NUMBER 1
 '@T6G_MB_LIB.T6G(SCH_1):PAGE214_I16@PURE_QUANTA.Q_CAP(CHIPS)':
 C_PATH='@t6g_mb_lib.t6g(sch_1):page214_i16@pure_quanta.q_cap(chips)';

PART_NAME
 U194 'PCA9555PW_SMLF-PCA9555PW,IC,TMP_QAL009555K04':;

SECTION_NUMBER 1
 '@T6G_MB_LIB.T6G(SCH_1):PAGE263_I198@PURE_QUANTA.PCA9555PW(CHIPS)':
 C_PATH='@t6g_mb_lib.t6g(sch_1):page263_i198@pure_quanta.pca9555pw(chips)';

PART_NAME
 U15 'PCA9555PW_SMLF-PCA9555PW,IC,TMP_QAL009555K04':;

SECTION_NUMBER 1
 '@T6G_MB_LIB.T6G(SCH_1):PAGE263_I182@PURE_QUANTA.PCA9555PW(CHIPS)':
 C_PATH='@t6g_mb_lib.t6g(sch_1):page263_i182@pure_quanta.pca9555pw(chips)';

PART_NAME
 U14 'PCA9555PW_SMLF-PCA9555PW,IC,TMP_QAL009555K04':;

SECTION_NUMBER 1
 '@T6G_MB_LIB.T6G(SCH_1):PAGE263_I35@PURE_QUANTA.PCA9555PW(CHIPS)':
 C_PATH='@t6g_mb_lib.t6g(sch_1):page263_i35@pure_quanta.pca9555pw(chips)';

PART_NAME
 R3873 'Q_RES_0402LF-4.7K,5%,1/16W,CHIP,TMP_QCS24702JB38':
;

SECTION_NUMBER 1
 '@T6G_MB_LIB.T6G(SCH_1):PAGE263_I459@PURE_QUANTA.Q_RES(CHIPS)':
 C_PATH='@t6g_mb_lib.t6g(sch_1):page263_i459@pure_quanta.q_res(chips)';

PART_NAME
 R3870 'Q_RES_0402LF-10K,5%,1/16W,CHIP,TMP_QCS31002JB28':
;

SECTION_NUMBER 1
 '@T6G_MB_LIB.T6G(SCH_1):PAGE263_I443@PURE_QUANTA.Q_RES(CHIPS)':
 C_PATH='@t6g_mb_lib.t6g(sch_1):page263_i443@pure_quanta.q_res(chips)';

PART_NAME
 R3869 'Q_RES_0402LF-10K,5%,1/16W,CHIP,TMP_QCS31002JB28':
;

SECTION_NUMBER 1
 '@T6G_MB_LIB.T6G(SCH_1):PAGE263_I430@PURE_QUANTA.Q_RES(CHIPS)':
 C_PATH='@t6g_mb_lib.t6g(sch_1):page263_i430@pure_quanta.q_res(chips)';

PART_NAME
 R3868 'Q_RES_0402LF-10K,5%,1/16W,CHIP,TMP_QCS31002JB28':
;

SECTION_NUMBER 1
 '@T6G_MB_LIB.T6G(SCH_1):PAGE263_I444@PURE_QUANTA.Q_RES(CHIPS)':
 C_PATH='@t6g_mb_lib.t6g(sch_1):page263_i444@pure_quanta.q_res(chips)';

PART_NAME
 R3867 'Q_RES_0402LF-10K,5%,1/16W,CHIP,TMP_QCS31002JB28':
;

SECTION_NUMBER 1
 '@T6G_MB_LIB.T6G(SCH_1):PAGE263_I431@PURE_QUANTA.Q_RES(CHIPS)':
 C_PATH='@t6g_mb_lib.t6g(sch_1):page263_i431@pure_quanta.q_res(chips)';

PART_NAME
 R3866 'Q_RES_0402LF-10K,5%,1/16W,CHIP,TMP_QCS31002JB28':
;

SECTION_NUMBER 1
 '@T6G_MB_LIB.T6G(SCH_1):PAGE263_I445@PURE_QUANTA.Q_RES(CHIPS)':
 C_PATH='@t6g_mb_lib.t6g(sch_1):page263_i445@pure_quanta.q_res(chips)';

PART_NAME
 R3865 'Q_RES_0402LF-10K,5%,1/16W,CHIP,TMP_QCS31002JB28':
;

SECTION_NUMBER 1
 '@T6G_MB_LIB.T6G(SCH_1):PAGE263_I432@PURE_QUANTA.Q_RES(CHIPS)':
 C_PATH='@t6g_mb_lib.t6g(sch_1):page263_i432@pure_quanta.q_res(chips)';

PART_NAME
 R3864 'Q_RES_0402LF-10K,5%,1/16W,CHIP,TMP_QCS31002JB28':
;

SECTION_NUMBER 1
 '@T6G_MB_LIB.T6G(SCH_1):PAGE263_I446@PURE_QUANTA.Q_RES(CHIPS)':
 C_PATH='@t6g_mb_lib.t6g(sch_1):page263_i446@pure_quanta.q_res(chips)';

PART_NAME
 R3863 'Q_RES_0402LF-10K,5%,1/16W,CHIP,TMP_QCS31002JB28':
;

SECTION_NUMBER 1
 '@T6G_MB_LIB.T6G(SCH_1):PAGE263_I433@PURE_QUANTA.Q_RES(CHIPS)':
 C_PATH='@t6g_mb_lib.t6g(sch_1):page263_i433@pure_quanta.q_res(chips)';

PART_NAME
 R3862 'Q_RES_0402LF-10K,5%,1/16W,CHIP,TMP_QCS31002JB28':
;

SECTION_NUMBER 1
 '@T6G_MB_LIB.T6G(SCH_1):PAGE263_I447@PURE_QUANTA.Q_RES(CHIPS)':
 C_PATH='@t6g_mb_lib.t6g(sch_1):page263_i447@pure_quanta.q_res(chips)';

PART_NAME
 R3861 'Q_RES_0402LF-10K,5%,1/16W,CHIP,TMP_QCS31002JB28':
;

SECTION_NUMBER 1
 '@T6G_MB_LIB.T6G(SCH_1):PAGE263_I448@PURE_QUANTA.Q_RES(CHIPS)':
 C_PATH='@t6g_mb_lib.t6g(sch_1):page263_i448@pure_quanta.q_res(chips)';

PART_NAME
 R3860 'Q_RES_0402LF-10K,5%,1/16W,CHIP,TMP_QCS31002JB28':
;

SECTION_NUMBER 1
 '@T6G_MB_LIB.T6G(SCH_1):PAGE263_I449@PURE_QUANTA.Q_RES(CHIPS)':
 C_PATH='@t6g_mb_lib.t6g(sch_1):page263_i449@pure_quanta.q_res(chips)';

PART_NAME
 R3859 'Q_RES_0402LF-10K,5%,1/16W,CHIP,TMP_QCS31002JB28':
;

SECTION_NUMBER 1
 '@T6G_MB_LIB.T6G(SCH_1):PAGE263_I450@PURE_QUANTA.Q_RES(CHIPS)':
 C_PATH='@t6g_mb_lib.t6g(sch_1):page263_i450@pure_quanta.q_res(chips)';

PART_NAME
 R3852 'Q_RES_0402LF-100,1%,1/16W,CHIP,TMP_QCS11002FB22':;

SECTION_NUMBER 1
 '@T6G_MB_LIB.T6G(SCH_1):PAGE263_I429@PURE_QUANTA.Q_RES(CHIPS)':
 C_PATH='@t6g_mb_lib.t6g(sch_1):page263_i429@pure_quanta.q_res(chips)';

PART_NAME
 R3851 'Q_RES_0402LF-10K,5%,1/16W,CHIP,TMP_QCS31002JB28':
;

SECTION_NUMBER 1
 '@T6G_MB_LIB.T6G(SCH_1):PAGE263_I391@PURE_QUANTA.Q_RES(CHIPS)':
 C_PATH='@t6g_mb_lib.t6g(sch_1):page263_i391@pure_quanta.q_res(chips)';

PART_NAME
 R3850 'Q_RES_0402LF-10K,5%,1/16W,CHIP,TMP_QCS31002JB28':
;

SECTION_NUMBER 1
 '@T6G_MB_LIB.T6G(SCH_1):PAGE263_I392@PURE_QUANTA.Q_RES(CHIPS)':
 C_PATH='@t6g_mb_lib.t6g(sch_1):page263_i392@pure_quanta.q_res(chips)';

PART_NAME
 R3849 'Q_RES_0402LF-10K,5%,1/16W,CHIP,TMP_QCS31002JB28':
;

SECTION_NUMBER 1
 '@T6G_MB_LIB.T6G(SCH_1):PAGE263_I395@PURE_QUANTA.Q_RES(CHIPS)':
 C_PATH='@t6g_mb_lib.t6g(sch_1):page263_i395@pure_quanta.q_res(chips)';

PART_NAME
 R3848 'Q_RES_0402LF-10K,5%,1/16W,CHIP,TMP_QCS31002JB28':
;

SECTION_NUMBER 1
 '@T6G_MB_LIB.T6G(SCH_1):PAGE263_I396@PURE_QUANTA.Q_RES(CHIPS)':
 C_PATH='@t6g_mb_lib.t6g(sch_1):page263_i396@pure_quanta.q_res(chips)';

PART_NAME
 R3623 'Q_RES_0402LF-33,5%,1/16W,CHIP,CS03302JB29':;

SECTION_NUMBER 1
 '@T6G_MB_LIB.T6G(SCH_1):PAGE263_I153@PURE_QUANTA.Q_RES(CHIPS)':
 C_PATH='@t6g_mb_lib.t6g(sch_1):page263_i153@pure_quanta.q_res(chips)';

PART_NAME
 R3622 'Q_RES_0402LF-33,5%,1/16W,CHIP,CS03302JB29':;

SECTION_NUMBER 1
 '@T6G_MB_LIB.T6G(SCH_1):PAGE263_I152@PURE_QUANTA.Q_RES(CHIPS)':
 C_PATH='@t6g_mb_lib.t6g(sch_1):page263_i152@pure_quanta.q_res(chips)';

PART_NAME
 R3621 'Q_RES_0402LF-1K,5%,1/16W,CHIP,TMP_QCS21002JB34':;

SECTION_NUMBER 1
 '@T6G_MB_LIB.T6G(SCH_1):PAGE263_I158@PURE_QUANTA.Q_RES(CHIPS)':
 C_PATH='@t6g_mb_lib.t6g(sch_1):page263_i158@pure_quanta.q_res(chips)';

PART_NAME
 R3620 'Q_RES_0402LF-1K,5%,1/16W,EMPTY,TMP_QCS21002JB34':;

SECTION_NUMBER 1
 '@T6G_MB_LIB.T6G(SCH_1):PAGE263_I154@PURE_QUANTA.Q_RES(CHIPS)':
 C_PATH='@t6g_mb_lib.t6g(sch_1):page263_i154@pure_quanta.q_res(chips)';

PART_NAME
 R3619 'Q_RES_0402LF-1K,5%,1/16W,CHIP,TMP_QCS21002JB34':;

SECTION_NUMBER 1
 '@T6G_MB_LIB.T6G(SCH_1):PAGE263_I160@PURE_QUANTA.Q_RES(CHIPS)':
 C_PATH='@t6g_mb_lib.t6g(sch_1):page263_i160@pure_quanta.q_res(chips)';

PART_NAME
 R3618 'Q_RES_0402LF-1K,5%,1/16W,EMPTY,TMP_QCS21002JB34':;

SECTION_NUMBER 1
 '@T6G_MB_LIB.T6G(SCH_1):PAGE263_I155@PURE_QUANTA.Q_RES(CHIPS)':
 C_PATH='@t6g_mb_lib.t6g(sch_1):page263_i155@pure_quanta.q_res(chips)';

PART_NAME
 R3617 'Q_RES_0402LF-1K,5%,1/16W,EMPTY,TMP_QCS21002JB34':;

SECTION_NUMBER 1
 '@T6G_MB_LIB.T6G(SCH_1):PAGE263_I162@PURE_QUANTA.Q_RES(CHIPS)':
 C_PATH='@t6g_mb_lib.t6g(sch_1):page263_i162@pure_quanta.q_res(chips)';

PART_NAME
 R3616 'Q_RES_0402LF-1K,5%,1/16W,CHIP,TMP_QCS21002JB34':;

SECTION_NUMBER 1
 '@T6G_MB_LIB.T6G(SCH_1):PAGE263_I157@PURE_QUANTA.Q_RES(CHIPS)':
 C_PATH='@t6g_mb_lib.t6g(sch_1):page263_i157@pure_quanta.q_res(chips)';

PART_NAME
 R3530 'Q_RES_0402LF-33,5%,1/16W,CHIP,CS03302JB29':;

SECTION_NUMBER 1
 '@T6G_MB_LIB.T6G(SCH_1):PAGE263_I185@PURE_QUANTA.Q_RES(CHIPS)':
 C_PATH='@t6g_mb_lib.t6g(sch_1):page263_i185@pure_quanta.q_res(chips)';

PART_NAME
 R3529 'Q_RES_0402LF-33,5%,1/16W,CHIP,CS03302JB29':;

SECTION_NUMBER 1
 '@T6G_MB_LIB.T6G(SCH_1):PAGE263_I184@PURE_QUANTA.Q_RES(CHIPS)':
 C_PATH='@t6g_mb_lib.t6g(sch_1):page263_i184@pure_quanta.q_res(chips)';

PART_NAME
 R3528 'Q_RES_0402LF-33,5%,1/16W,CHIP,CS03302JB29':;

SECTION_NUMBER 1
 '@T6G_MB_LIB.T6G(SCH_1):PAGE263_I60@PURE_QUANTA.Q_RES(CHIPS)':
 C_PATH='@t6g_mb_lib.t6g(sch_1):page263_i60@pure_quanta.q_res(chips)';

PART_NAME
 R3527 'Q_RES_0402LF-33,5%,1/16W,CHIP,CS03302JB29':;

SECTION_NUMBER 1
 '@T6G_MB_LIB.T6G(SCH_1):PAGE263_I64@PURE_QUANTA.Q_RES(CHIPS)':
 C_PATH='@t6g_mb_lib.t6g(sch_1):page263_i64@pure_quanta.q_res(chips)';

PART_NAME
 R3519 'Q_RES_0402LF-1K,5%,1/16W,EMPTY,TMP_QCS21002JB34':;

SECTION_NUMBER 1
 '@T6G_MB_LIB.T6G(SCH_1):PAGE263_I192@PURE_QUANTA.Q_RES(CHIPS)':
 C_PATH='@t6g_mb_lib.t6g(sch_1):page263_i192@pure_quanta.q_res(chips)';

PART_NAME
 R3518 'Q_RES_0402LF-1K,5%,1/16W,CHIP,TMP_QCS21002JB34':;

SECTION_NUMBER 1
 '@T6G_MB_LIB.T6G(SCH_1):PAGE263_I186@PURE_QUANTA.Q_RES(CHIPS)':
 C_PATH='@t6g_mb_lib.t6g(sch_1):page263_i186@pure_quanta.q_res(chips)';

PART_NAME
 R3517 'Q_RES_0402LF-1K,5%,1/16W,CHIP,TMP_QCS21002JB34':;

SECTION_NUMBER 1
 '@T6G_MB_LIB.T6G(SCH_1):PAGE263_I26@PURE_QUANTA.Q_RES(CHIPS)':
 C_PATH='@t6g_mb_lib.t6g(sch_1):page263_i26@pure_quanta.q_res(chips)';

PART_NAME
 R3516 'Q_RES_0402LF-1K,5%,1/16W,EMPTY,TMP_QCS21002JB34':;

SECTION_NUMBER 1
 '@T6G_MB_LIB.T6G(SCH_1):PAGE263_I30@PURE_QUANTA.Q_RES(CHIPS)':
 C_PATH='@t6g_mb_lib.t6g(sch_1):page263_i30@pure_quanta.q_res(chips)';

PART_NAME
 R3515 'Q_RES_0402LF-1K,5%,1/16W,EMPTY,TMP_QCS21002JB34':;

SECTION_NUMBER 1
 '@T6G_MB_LIB.T6G(SCH_1):PAGE263_I194@PURE_QUANTA.Q_RES(CHIPS)':
 C_PATH='@t6g_mb_lib.t6g(sch_1):page263_i194@pure_quanta.q_res(chips)';

PART_NAME
 R3514 'Q_RES_0402LF-1K,5%,1/16W,CHIP,TMP_QCS21002JB34':;

SECTION_NUMBER 1
 '@T6G_MB_LIB.T6G(SCH_1):PAGE263_I188@PURE_QUANTA.Q_RES(CHIPS)':
 C_PATH='@t6g_mb_lib.t6g(sch_1):page263_i188@pure_quanta.q_res(chips)';

PART_NAME
 R3513 'Q_RES_0402LF-1K,5%,1/16W,EMPTY,TMP_QCS21002JB34':;

SECTION_NUMBER 1
 '@T6G_MB_LIB.T6G(SCH_1):PAGE263_I24@PURE_QUANTA.Q_RES(CHIPS)':
 C_PATH='@t6g_mb_lib.t6g(sch_1):page263_i24@pure_quanta.q_res(chips)';

PART_NAME
 R3512 'Q_RES_0402LF-1K,5%,1/16W,CHIP,TMP_QCS21002JB34':;

SECTION_NUMBER 1
 '@T6G_MB_LIB.T6G(SCH_1):PAGE263_I29@PURE_QUANTA.Q_RES(CHIPS)':
 C_PATH='@t6g_mb_lib.t6g(sch_1):page263_i29@pure_quanta.q_res(chips)';

PART_NAME
 R3511 'Q_RES_0402LF-1K,5%,1/16W,CHIP,TMP_QCS21002JB34':;

SECTION_NUMBER 1
 '@T6G_MB_LIB.T6G(SCH_1):PAGE263_I196@PURE_QUANTA.Q_RES(CHIPS)':
 C_PATH='@t6g_mb_lib.t6g(sch_1):page263_i196@pure_quanta.q_res(chips)';

PART_NAME
 R3510 'Q_RES_0402LF-1K,5%,1/16W,EMPTY,TMP_QCS21002JB34':;

SECTION_NUMBER 1
 '@T6G_MB_LIB.T6G(SCH_1):PAGE263_I189@PURE_QUANTA.Q_RES(CHIPS)':
 C_PATH='@t6g_mb_lib.t6g(sch_1):page263_i189@pure_quanta.q_res(chips)';

PART_NAME
 R3509 'Q_RES_0402LF-1K,5%,1/16W,CHIP,TMP_QCS21002JB34':;

SECTION_NUMBER 1
 '@T6G_MB_LIB.T6G(SCH_1):PAGE263_I22@PURE_QUANTA.Q_RES(CHIPS)':
 C_PATH='@t6g_mb_lib.t6g(sch_1):page263_i22@pure_quanta.q_res(chips)';

PART_NAME
 R3508 'Q_RES_0402LF-1K,5%,1/16W,EMPTY,TMP_QCS21002JB34':;

SECTION_NUMBER 1
 '@T6G_MB_LIB.T6G(SCH_1):PAGE263_I27@PURE_QUANTA.Q_RES(CHIPS)':
 C_PATH='@t6g_mb_lib.t6g(sch_1):page263_i27@pure_quanta.q_res(chips)';

PART_NAME
 J288 'CONN2_210HP102GBR05K-CONN2_210-HP1-02GBR05K,SMLF,IO,DFHD02MS353':;

SECTION_NUMBER 1
 '@T6G_MB_LIB.T6G(SCH_1):PAGE263_I414@PURE_QUANTA.CONN2_210HP102GBR05K(CHIPS)':
 C_PATH='@t6g_mb_lib.t6g(sch_1):page263_i414@pure_quanta.conn2_210hp102gbr05k(ch~
ips)';

PART_NAME
 C2892 'Q_CAP_0402-0.1UF,25V,10%,X7R,CH4104K1B00':;

SECTION_NUMBER 1
 '@T6G_MB_LIB.T6G(SCH_1):PAGE263_I150@PURE_QUANTA.Q_CAP(CHIPS)':
 C_PATH='@t6g_mb_lib.t6g(sch_1):page263_i150@pure_quanta.q_cap(chips)';

PART_NAME
 C2818 'Q_CAP_0402-0.1UF,25V,10%,X7R,CH4104K1B00':;

SECTION_NUMBER 1
 '@T6G_MB_LIB.T6G(SCH_1):PAGE263_I180@PURE_QUANTA.Q_CAP(CHIPS)':
 C_PATH='@t6g_mb_lib.t6g(sch_1):page263_i180@pure_quanta.q_cap(chips)';

PART_NAME
 C2817 'Q_CAP_0402-0.1UF,25V,10%,X7R,CH4104K1B00':;

SECTION_NUMBER 1
 '@T6G_MB_LIB.T6G(SCH_1):PAGE263_I36@PURE_QUANTA.Q_CAP(CHIPS)':
 C_PATH='@t6g_mb_lib.t6g(sch_1):page263_i36@pure_quanta.q_cap(chips)';

PART_NAME
 R3702 'Q_RES_0402LF-0,5%,1/16W,CHIP,CS00002JB38':;

SECTION_NUMBER 1
 '@T6G_MB_LIB.T6G(SCH_1):PAGE276_I139@PURE_QUANTA.Q_RES(CHIPS)':
 C_PATH='@t6g_mb_lib.t6g(sch_1):page276_i139@pure_quanta.q_res(chips)';

PART_NAME
 R3701 'Q_RES_0402LF -680,5%,1/16W ,CHIP,TMP_QCS16802JB27':;

SECTION_NUMBER 1
 '@T6G_MB_LIB.T6G(SCH_1):PAGE276_I142@PURE_QUANTA.Q_RES(CHIPS)':
 C_PATH='@t6g_mb_lib.t6g(sch_1):page276_i142@pure_quanta.q_res(chips)';

PART_NAME
 R3507 'Q_RES_0402LF-33,5%,1/16W,CHIP,CS03302JB29':;

SECTION_NUMBER 1
 '@T6G_MB_LIB.T6G(SCH_1):PAGE276_I99@PURE_QUANTA.Q_RES(CHIPS)':
 C_PATH='@t6g_mb_lib.t6g(sch_1):page276_i99@pure_quanta.q_res(chips)';

PART_NAME
 R3506 'Q_RES_0402LF-33,5%,1/16W,CHIP,CS03302JB29':;

SECTION_NUMBER 1
 '@T6G_MB_LIB.T6G(SCH_1):PAGE276_I100@PURE_QUANTA.Q_RES(CHIPS)':
 C_PATH='@t6g_mb_lib.t6g(sch_1):page276_i100@pure_quanta.q_res(chips)';

PART_NAME
 R3505 'Q_RES_0402LF-10K,5%,1/16W,CHIP,TMP_QCS31002JB28':;

SECTION_NUMBER 1
 '@T6G_MB_LIB.T6G(SCH_1):PAGE276_I107@PURE_QUANTA.Q_RES(CHIPS)':
 C_PATH='@t6g_mb_lib.t6g(sch_1):page276_i107@pure_quanta.q_res(chips)';

PART_NAME
 R3504 'Q_RES_0402LF-100,1%,1/16W,CHIP,TMP_QCS11002FB22':;

SECTION_NUMBER 1
 '@T6G_MB_LIB.T6G(SCH_1):PAGE276_I118@PURE_QUANTA.Q_RES(CHIPS)':
 C_PATH='@t6g_mb_lib.t6g(sch_1):page276_i118@pure_quanta.q_res(chips)';

PART_NAME
 R3503 'Q_RES_0402LF-100,1%,1/16W,CHIP,TMP_QCS11002FB22':;

SECTION_NUMBER 1
 '@T6G_MB_LIB.T6G(SCH_1):PAGE276_I117@PURE_QUANTA.Q_RES(CHIPS)':
 C_PATH='@t6g_mb_lib.t6g(sch_1):page276_i117@pure_quanta.q_res(chips)';

PART_NAME
 R3502 'Q_RES_0402LF-332,1%,1/16W,CHIP,CS13322FB10':;

SECTION_NUMBER 1
 '@T6G_MB_LIB.T6G(SCH_1):PAGE276_I119@PURE_QUANTA.Q_RES(CHIPS)':
 C_PATH='@t6g_mb_lib.t6g(sch_1):page276_i119@pure_quanta.q_res(chips)';

PART_NAME
 R3501 'Q_RES_0402LF-332,1%,1/16W,CHIP,CS13322FB10':;

SECTION_NUMBER 1
 '@T6G_MB_LIB.T6G(SCH_1):PAGE276_I115@PURE_QUANTA.Q_RES(CHIPS)':
 C_PATH='@t6g_mb_lib.t6g(sch_1):page276_i115@pure_quanta.q_res(chips)';

PART_NAME
 R3500 'Q_RES_0402LF-100,1%,1/16W,CHIP,TMP_QCS11002FB22':;

SECTION_NUMBER 1
 '@T6G_MB_LIB.T6G(SCH_1):PAGE276_I114@PURE_QUANTA.Q_RES(CHIPS)':
 C_PATH='@t6g_mb_lib.t6g(sch_1):page276_i114@pure_quanta.q_res(chips)';

PART_NAME
 R3498 'Q_RES_0402LF-100,1%,1/16W,CHIP,TMP_QCS11002FB22':;

SECTION_NUMBER 1
 '@T6G_MB_LIB.T6G(SCH_1):PAGE276_I124@PURE_QUANTA.Q_RES(CHIPS)':
 C_PATH='@t6g_mb_lib.t6g(sch_1):page276_i124@pure_quanta.q_res(chips)';

PART_NAME
 R3497 'Q_RES_0402LF-33,5%,1/16W,CHIP,CS03302JB29':;

SECTION_NUMBER 1
 '@T6G_MB_LIB.T6G(SCH_1):PAGE276_I95@PURE_QUANTA.Q_RES(CHIPS)':
 C_PATH='@t6g_mb_lib.t6g(sch_1):page276_i95@pure_quanta.q_res(chips)';

PART_NAME
 R3496 'Q_RES_0402LF-33,5%,1/16W,CHIP,CS03302JB29':;

SECTION_NUMBER 1
 '@T6G_MB_LIB.T6G(SCH_1):PAGE276_I94@PURE_QUANTA.Q_RES(CHIPS)':
 C_PATH='@t6g_mb_lib.t6g(sch_1):page276_i94@pure_quanta.q_res(chips)';

PART_NAME
 R1491 'Q_RES_0402LF-33,5%,1/16W,CHIP,CS03302JB29':;

SECTION_NUMBER 1
 '@T6G_MB_LIB.T6G(SCH_1):PAGE276_I89@PURE_QUANTA.Q_RES(CHIPS)':
 C_PATH='@t6g_mb_lib.t6g(sch_1):page276_i89@pure_quanta.q_res(chips)';

PART_NAME
 R1490 'Q_RES_0402LF-0,5%,1/16W,CHIP,CS00002JB38':;

SECTION_NUMBER 1
 '@T6G_MB_LIB.T6G(SCH_1):PAGE276_I69@PURE_QUANTA.Q_RES(CHIPS)':
 C_PATH='@t6g_mb_lib.t6g(sch_1):page276_i69@pure_quanta.q_res(chips)';

PART_NAME
 R1485 'Q_RES_0402LF-33,5%,1/16W,CHIP,CS03302JB29':;

SECTION_NUMBER 1
 '@T6G_MB_LIB.T6G(SCH_1):PAGE276_I90@PURE_QUANTA.Q_RES(CHIPS)':
 C_PATH='@t6g_mb_lib.t6g(sch_1):page276_i90@pure_quanta.q_res(chips)';

PART_NAME
 R1094 'Q_RES_0402LF-49.9     ,1%  ,1/16W,CHIP,CS04992FB31':;

SECTION_NUMBER 1
 '@T6G_MB_LIB.T6G(SCH_1):PAGE276_I126@PURE_QUANTA.Q_RES(CHIPS)':
 C_PATH='@t6g_mb_lib.t6g(sch_1):page276_i126@pure_quanta.q_res(chips)';

PART_NAME
 R1089 'Q_RES_0402LF-49.9     ,1%  ,1/16W,CHIP,CS04992FB31':;

SECTION_NUMBER 1
 '@T6G_MB_LIB.T6G(SCH_1):PAGE276_I127@PURE_QUANTA.Q_RES(CHIPS)':
 C_PATH='@t6g_mb_lib.t6g(sch_1):page276_i127@pure_quanta.q_res(chips)';

PART_NAME
 R432 'Q_RES_0402LF-33,5%,1/16W,CHIP,CS03302JB29':;

SECTION_NUMBER 1
 '@T6G_MB_LIB.T6G(SCH_1):PAGE276_I68@PURE_QUANTA.Q_RES(CHIPS)':
 C_PATH='@t6g_mb_lib.t6g(sch_1):page276_i68@pure_quanta.q_res(chips)';

PART_NAME
 Q19 'MOSFET_NCH_DUAL-2N7002KDW,SMLF,IC,BAM70020047':;

SECTION_NUMBER 1
 '@T6G_MB_LIB.T6G(SCH_1):PAGE276_I130@PURE_QUANTA.MOSFET_NCH_DUAL(CHIPS)':
 C_PATH='@t6g_mb_lib.t6g(sch_1):page276_i130@pure_quanta.mosfet_nch_dual(chips)';

SECTION_NUMBER 2
 '@T6G_MB_LIB.T6G(SCH_1):PAGE276_I144@PURE_QUANTA.MOSFET_NCH_DUAL(CHIPS)':
 C_PATH='@t6g_mb_lib.t6g(sch_1):page276_i144@pure_quanta.mosfet_nch_dual(chips)';

PART_NAME
 J269 'SCONN24_5041902441001-SCONN24_5041902441001,SMLF,IO,DFWF24MS006':;

SECTION_NUMBER 1
 '@T6G_MB_LIB.T6G(SCH_1):PAGE276_I51@PURE_QUANTA.SCONN24_5041902441001(CHIPS)':
 C_PATH='@t6g_mb_lib.t6g(sch_1):page276_i51@pure_quanta.sconn24_5041902441001(ch~
ips)';

PART_NAME
 J127 'SCONN20_5011902017-SCONN20_501190-2017,SMLF,IO,DFWF20MS004':;

SECTION_NUMBER 1
 '@T6G_MB_LIB.T6G(SCH_1):PAGE276_I123@PURE_QUANTA.SCONN20_5011902017(CHIPS)':
 C_PATH='@t6g_mb_lib.t6g(sch_1):page276_i123@pure_quanta.sconn20_5011902017(chip~
s)';

PART_NAME
 D12 'Q_LED_SMLF-LED_GREEN,19-213/GVC-AMNB/3T,IC,BEGR0278Z00':;

SECTION_NUMBER 1
 '@T6G_MB_LIB.T6G(SCH_1):PAGE276_I141@PURE_QUANTA.Q_LED(CHIPS)':
 C_PATH='@t6g_mb_lib.t6g(sch_1):page276_i141@pure_quanta.q_led(chips)';

PART_NAME
 C2815 'Q_CAP_0402-0.1UF,25V,10%,X7R,CH4104K1B00':;

SECTION_NUMBER 1
 '@T6G_MB_LIB.T6G(SCH_1):PAGE276_I113@PURE_QUANTA.Q_CAP(CHIPS)':
 C_PATH='@t6g_mb_lib.t6g(sch_1):page276_i113@pure_quanta.q_cap(chips)';

PART_NAME
 R3712 'Q_RES_0402LF-2K,1%,1/16W,CHIP,CS22002FB07':
;

SECTION_NUMBER 1
 '@T6G_MB_LIB.T6G(SCH_1):PAGE201_I796@PURE_QUANTA.Q_RES(CHIPS)':
 C_PATH='@t6g_mb_lib.t6g(sch_1):page201_i796@pure_quanta.q_res(chips)';

PART_NAME
 R3711 'Q_RES_0402LF-2K,1%,1/16W,CHIP,CS22002FB07':
;

SECTION_NUMBER 1
 '@T6G_MB_LIB.T6G(SCH_1):PAGE201_I799@PURE_QUANTA.Q_RES(CHIPS)':
 C_PATH='@t6g_mb_lib.t6g(sch_1):page201_i799@pure_quanta.q_res(chips)';

PART_NAME
 J278 'SCONN38_U10D238300T-SCONN38_U10-D238-300T,SMLF,IO,DFHS38FS015':;

SECTION_NUMBER 1
 '@T6G_MB_LIB.T6G(SCH_1):PAGE201_I708@PURE_QUANTA.SCONN38_U10D238300T(CHIPS)':
 C_PATH='@t6g_mb_lib.t6g(sch_1):page201_i708@pure_quanta.sconn38_u10d238300t(chi~
ps)';

PART_NAME
 J277 'SCONN38_U10D238300T-SCONN38_U10-D238-300T,SMLF,IO,DFHS38FS015':;

SECTION_NUMBER 1
 '@T6G_MB_LIB.T6G(SCH_1):PAGE201_I786@PURE_QUANTA.SCONN38_U10D238300T(CHIPS)':
 C_PATH='@t6g_mb_lib.t6g(sch_1):page201_i786@pure_quanta.sconn38_u10d238300t(chi~
ps)';

PART_NAME
 J276 'SCONN38_U10D238300T-SCONN38_U10-D238-300T,SMLF,IO,DFHS38FS015':;

SECTION_NUMBER 1
 '@T6G_MB_LIB.T6G(SCH_1):PAGE201_I728@PURE_QUANTA.SCONN38_U10D238300T(CHIPS)':
 C_PATH='@t6g_mb_lib.t6g(sch_1):page201_i728@pure_quanta.sconn38_u10d238300t(chi~
ps)';

PART_NAME
 C2922 'Q_CAP_0402-0.01UF,25V,10%,X7R,TMP_QCH31004KB17':
;

SECTION_NUMBER 1
 '@T6G_MB_LIB.T6G(SCH_1):PAGE201_I869@PURE_QUANTA.Q_CAP(CHIPS)':
 C_PATH='@t6g_mb_lib.t6g(sch_1):page201_i869@pure_quanta.q_cap(chips)';

PART_NAME
 C2921 'Q_CAP_0402-0.01UF,25V,10%,X7R,TMP_QCH31004KB17':
;

SECTION_NUMBER 1
 '@T6G_MB_LIB.T6G(SCH_1):PAGE201_I861@PURE_QUANTA.Q_CAP(CHIPS)':
 C_PATH='@t6g_mb_lib.t6g(sch_1):page201_i861@pure_quanta.q_cap(chips)';

PART_NAME
 C2920 'Q_CAP_0402-0.01UF,25V,10%,X7R,TMP_QCH31004KB17':
;

SECTION_NUMBER 1
 '@T6G_MB_LIB.T6G(SCH_1):PAGE201_I856@PURE_QUANTA.Q_CAP(CHIPS)':
 C_PATH='@t6g_mb_lib.t6g(sch_1):page201_i856@pure_quanta.q_cap(chips)';

PART_NAME
 C2919 'Q_CAP_0402-0.01UF,25V,10%,X7R,TMP_QCH31004KB17':
;

SECTION_NUMBER 1
 '@T6G_MB_LIB.T6G(SCH_1):PAGE201_I870@PURE_QUANTA.Q_CAP(CHIPS)':
 C_PATH='@t6g_mb_lib.t6g(sch_1):page201_i870@pure_quanta.q_cap(chips)';

PART_NAME
 C2918 'Q_CAP_0402-0.01UF,25V,10%,X7R,TMP_QCH31004KB17':
;

SECTION_NUMBER 1
 '@T6G_MB_LIB.T6G(SCH_1):PAGE201_I862@PURE_QUANTA.Q_CAP(CHIPS)':
 C_PATH='@t6g_mb_lib.t6g(sch_1):page201_i862@pure_quanta.q_cap(chips)';

PART_NAME
 C2917 'Q_CAP_0402-0.01UF,25V,10%,X7R,TMP_QCH31004KB17':
;

SECTION_NUMBER 1
 '@T6G_MB_LIB.T6G(SCH_1):PAGE201_I855@PURE_QUANTA.Q_CAP(CHIPS)':
 C_PATH='@t6g_mb_lib.t6g(sch_1):page201_i855@pure_quanta.q_cap(chips)';

PART_NAME
 C2916 'Q_CAP_0402-0.01UF,25V,10%,X7R,TMP_QCH31004KB17':
;

SECTION_NUMBER 1
 '@T6G_MB_LIB.T6G(SCH_1):PAGE201_I871@PURE_QUANTA.Q_CAP(CHIPS)':
 C_PATH='@t6g_mb_lib.t6g(sch_1):page201_i871@pure_quanta.q_cap(chips)';

PART_NAME
 C2915 'Q_CAP_0402-0.01UF,25V,10%,X7R,TMP_QCH31004KB17':
;

SECTION_NUMBER 1
 '@T6G_MB_LIB.T6G(SCH_1):PAGE201_I863@PURE_QUANTA.Q_CAP(CHIPS)':
 C_PATH='@t6g_mb_lib.t6g(sch_1):page201_i863@pure_quanta.q_cap(chips)';

PART_NAME
 C2914 'Q_CAP_0402-0.01UF,25V,10%,X7R,TMP_QCH31004KB17':
;

SECTION_NUMBER 1
 '@T6G_MB_LIB.T6G(SCH_1):PAGE201_I851@PURE_QUANTA.Q_CAP(CHIPS)':
 C_PATH='@t6g_mb_lib.t6g(sch_1):page201_i851@pure_quanta.q_cap(chips)';

PART_NAME
 C2913 'Q_CAP_0402-0.01UF,25V,10%,X7R,TMP_QCH31004KB17':
;

SECTION_NUMBER 1
 '@T6G_MB_LIB.T6G(SCH_1):PAGE201_I872@PURE_QUANTA.Q_CAP(CHIPS)':
 C_PATH='@t6g_mb_lib.t6g(sch_1):page201_i872@pure_quanta.q_cap(chips)';

PART_NAME
 C2912 'Q_CAP_0402-0.01UF,25V,10%,X7R,TMP_QCH31004KB17':
;

SECTION_NUMBER 1
 '@T6G_MB_LIB.T6G(SCH_1):PAGE201_I864@PURE_QUANTA.Q_CAP(CHIPS)':
 C_PATH='@t6g_mb_lib.t6g(sch_1):page201_i864@pure_quanta.q_cap(chips)';

PART_NAME
 C2911 'Q_CAP_0402-0.01UF,25V,10%,X7R,TMP_QCH31004KB17':
;

SECTION_NUMBER 1
 '@T6G_MB_LIB.T6G(SCH_1):PAGE201_I852@PURE_QUANTA.Q_CAP(CHIPS)':
 C_PATH='@t6g_mb_lib.t6g(sch_1):page201_i852@pure_quanta.q_cap(chips)';

PART_NAME
 C2810 'Q_CAP_0402-0.01UF,25V,10%,X7R,TMP_QCH31004KB17':
;

SECTION_NUMBER 1
 '@T6G_MB_LIB.T6G(SCH_1):PAGE201_I865@PURE_QUANTA.Q_CAP(CHIPS)':
 C_PATH='@t6g_mb_lib.t6g(sch_1):page201_i865@pure_quanta.q_cap(chips)';

PART_NAME
 C2808 'Q_CAP_0402-0.01UF,25V,10%,X7R,TMP_QCH31004KB17':
;

SECTION_NUMBER 1
 '@T6G_MB_LIB.T6G(SCH_1):PAGE201_I736@PURE_QUANTA.Q_CAP(CHIPS)':
 C_PATH='@t6g_mb_lib.t6g(sch_1):page201_i736@pure_quanta.q_cap(chips)';

PART_NAME
 C2807 'Q_CAP_0402-0.01UF,25V,10%,X7R,TMP_QCH31004KB17':
;

SECTION_NUMBER 1
 '@T6G_MB_LIB.T6G(SCH_1):PAGE201_I737@PURE_QUANTA.Q_CAP(CHIPS)':
 C_PATH='@t6g_mb_lib.t6g(sch_1):page201_i737@pure_quanta.q_cap(chips)';

PART_NAME
 C2806 'Q_CAP_0402-0.01UF,25V,10%,X7R,TMP_QCH31004KB17':
;

SECTION_NUMBER 1
 '@T6G_MB_LIB.T6G(SCH_1):PAGE201_I857@PURE_QUANTA.Q_CAP(CHIPS)':
 C_PATH='@t6g_mb_lib.t6g(sch_1):page201_i857@pure_quanta.q_cap(chips)';

PART_NAME
 C2804 'Q_CAP_0402-0.01UF,25V,10%,X7R,TMP_QCH31004KB17':
;

SECTION_NUMBER 1
 '@T6G_MB_LIB.T6G(SCH_1):PAGE201_I746@PURE_QUANTA.Q_CAP(CHIPS)':
 C_PATH='@t6g_mb_lib.t6g(sch_1):page201_i746@pure_quanta.q_cap(chips)';

PART_NAME
 C2803 'Q_CAP_0402-0.01UF,25V,10%,X7R,TMP_QCH31004KB17':
;

SECTION_NUMBER 1
 '@T6G_MB_LIB.T6G(SCH_1):PAGE201_I747@PURE_QUANTA.Q_CAP(CHIPS)':
 C_PATH='@t6g_mb_lib.t6g(sch_1):page201_i747@pure_quanta.q_cap(chips)';

PART_NAME
 C2802 'Q_CAP_0402-0.01UF,25V,10%,X7R,TMP_QCH31004KB17':
;

SECTION_NUMBER 1
 '@T6G_MB_LIB.T6G(SCH_1):PAGE201_I854@PURE_QUANTA.Q_CAP(CHIPS)':
 C_PATH='@t6g_mb_lib.t6g(sch_1):page201_i854@pure_quanta.q_cap(chips)';

PART_NAME
 C2800 'Q_CAP_0402-0.01UF,25V,10%,X7R,TMP_QCH31004KB17':
;

SECTION_NUMBER 1
 '@T6G_MB_LIB.T6G(SCH_1):PAGE201_I773@PURE_QUANTA.Q_CAP(CHIPS)':
 C_PATH='@t6g_mb_lib.t6g(sch_1):page201_i773@pure_quanta.q_cap(chips)';

PART_NAME
 C2799 'Q_CAP_0402-0.01UF,25V,10%,X7R,TMP_QCH31004KB17':
;

SECTION_NUMBER 1
 '@T6G_MB_LIB.T6G(SCH_1):PAGE201_I774@PURE_QUANTA.Q_CAP(CHIPS)':
 C_PATH='@t6g_mb_lib.t6g(sch_1):page201_i774@pure_quanta.q_cap(chips)';

PART_NAME
 C2798 'Q_CAP_0402-0.01UF,25V,10%,X7R,TMP_QCH31004KB17':
;

SECTION_NUMBER 1
 '@T6G_MB_LIB.T6G(SCH_1):PAGE201_I866@PURE_QUANTA.Q_CAP(CHIPS)':
 C_PATH='@t6g_mb_lib.t6g(sch_1):page201_i866@pure_quanta.q_cap(chips)';

PART_NAME
 C2796 'Q_CAP_0402-0.01UF,25V,10%,X7R,TMP_QCH31004KB17':
;

SECTION_NUMBER 1
 '@T6G_MB_LIB.T6G(SCH_1):PAGE201_I732@PURE_QUANTA.Q_CAP(CHIPS)':
 C_PATH='@t6g_mb_lib.t6g(sch_1):page201_i732@pure_quanta.q_cap(chips)';

PART_NAME
 C2795 'Q_CAP_0402-0.01UF,25V,10%,X7R,TMP_QCH31004KB17':
;

SECTION_NUMBER 1
 '@T6G_MB_LIB.T6G(SCH_1):PAGE201_I733@PURE_QUANTA.Q_CAP(CHIPS)':
 C_PATH='@t6g_mb_lib.t6g(sch_1):page201_i733@pure_quanta.q_cap(chips)';

PART_NAME
 C2794 'Q_CAP_0402-0.01UF,25V,10%,X7R,TMP_QCH31004KB17':
;

SECTION_NUMBER 1
 '@T6G_MB_LIB.T6G(SCH_1):PAGE201_I858@PURE_QUANTA.Q_CAP(CHIPS)':
 C_PATH='@t6g_mb_lib.t6g(sch_1):page201_i858@pure_quanta.q_cap(chips)';

PART_NAME
 C2792 'Q_CAP_0402-0.01UF,25V,10%,X7R,TMP_QCH31004KB17':
;

SECTION_NUMBER 1
 '@T6G_MB_LIB.T6G(SCH_1):PAGE201_I742@PURE_QUANTA.Q_CAP(CHIPS)':
 C_PATH='@t6g_mb_lib.t6g(sch_1):page201_i742@pure_quanta.q_cap(chips)';

PART_NAME
 C2791 'Q_CAP_0402-0.01UF,25V,10%,X7R,TMP_QCH31004KB17':
;

SECTION_NUMBER 1
 '@T6G_MB_LIB.T6G(SCH_1):PAGE201_I743@PURE_QUANTA.Q_CAP(CHIPS)':
 C_PATH='@t6g_mb_lib.t6g(sch_1):page201_i743@pure_quanta.q_cap(chips)';

PART_NAME
 C2790 'Q_CAP_0402-0.01UF,25V,10%,X7R,TMP_QCH31004KB17':
;

SECTION_NUMBER 1
 '@T6G_MB_LIB.T6G(SCH_1):PAGE201_I853@PURE_QUANTA.Q_CAP(CHIPS)':
 C_PATH='@t6g_mb_lib.t6g(sch_1):page201_i853@pure_quanta.q_cap(chips)';

PART_NAME
 C2788 'Q_CAP_0402-0.01UF,25V,10%,X7R,TMP_QCH31004KB17':
;

SECTION_NUMBER 1
 '@T6G_MB_LIB.T6G(SCH_1):PAGE201_I769@PURE_QUANTA.Q_CAP(CHIPS)':
 C_PATH='@t6g_mb_lib.t6g(sch_1):page201_i769@pure_quanta.q_cap(chips)';

PART_NAME
 C2787 'Q_CAP_0402-0.01UF,25V,10%,X7R,TMP_QCH31004KB17':
;

SECTION_NUMBER 1
 '@T6G_MB_LIB.T6G(SCH_1):PAGE201_I770@PURE_QUANTA.Q_CAP(CHIPS)':
 C_PATH='@t6g_mb_lib.t6g(sch_1):page201_i770@pure_quanta.q_cap(chips)';

PART_NAME
 C2786 'Q_CAP_0402-0.01UF,25V,10%,X7R,TMP_QCH31004KB17':
;

SECTION_NUMBER 1
 '@T6G_MB_LIB.T6G(SCH_1):PAGE201_I867@PURE_QUANTA.Q_CAP(CHIPS)':
 C_PATH='@t6g_mb_lib.t6g(sch_1):page201_i867@pure_quanta.q_cap(chips)';

PART_NAME
 C2784 'Q_CAP_0402-0.01UF,25V,10%,X7R,TMP_QCH31004KB17':
;

SECTION_NUMBER 1
 '@T6G_MB_LIB.T6G(SCH_1):PAGE201_I688@PURE_QUANTA.Q_CAP(CHIPS)':
 C_PATH='@t6g_mb_lib.t6g(sch_1):page201_i688@pure_quanta.q_cap(chips)';

PART_NAME
 C2783 'Q_CAP_0402-0.01UF,25V,10%,X7R,TMP_QCH31004KB17':
;

SECTION_NUMBER 1
 '@T6G_MB_LIB.T6G(SCH_1):PAGE201_I689@PURE_QUANTA.Q_CAP(CHIPS)':
 C_PATH='@t6g_mb_lib.t6g(sch_1):page201_i689@pure_quanta.q_cap(chips)';

PART_NAME
 C2782 'Q_CAP_0402-0.01UF,25V,10%,X7R,TMP_QCH31004KB17':
;

SECTION_NUMBER 1
 '@T6G_MB_LIB.T6G(SCH_1):PAGE201_I860@PURE_QUANTA.Q_CAP(CHIPS)':
 C_PATH='@t6g_mb_lib.t6g(sch_1):page201_i860@pure_quanta.q_cap(chips)';

PART_NAME
 C2780 'Q_CAP_0402-0.01UF,25V,10%,X7R,TMP_QCH31004KB17':
;

SECTION_NUMBER 1
 '@T6G_MB_LIB.T6G(SCH_1):PAGE201_I704@PURE_QUANTA.Q_CAP(CHIPS)':
 C_PATH='@t6g_mb_lib.t6g(sch_1):page201_i704@pure_quanta.q_cap(chips)';

PART_NAME
 C2779 'Q_CAP_0402-0.01UF,25V,10%,X7R,TMP_QCH31004KB17':
;

SECTION_NUMBER 1
 '@T6G_MB_LIB.T6G(SCH_1):PAGE201_I705@PURE_QUANTA.Q_CAP(CHIPS)':
 C_PATH='@t6g_mb_lib.t6g(sch_1):page201_i705@pure_quanta.q_cap(chips)';

PART_NAME
 C2778 'Q_CAP_0402-0.01UF,25V,10%,X7R,TMP_QCH31004KB17':
;

SECTION_NUMBER 1
 '@T6G_MB_LIB.T6G(SCH_1):PAGE201_I849@PURE_QUANTA.Q_CAP(CHIPS)':
 C_PATH='@t6g_mb_lib.t6g(sch_1):page201_i849@pure_quanta.q_cap(chips)';

PART_NAME
 C2776 'Q_CAP_0402-0.01UF,25V,10%,X7R,TMP_QCH31004KB17':
;

SECTION_NUMBER 1
 '@T6G_MB_LIB.T6G(SCH_1):PAGE201_I725@PURE_QUANTA.Q_CAP(CHIPS)':
 C_PATH='@t6g_mb_lib.t6g(sch_1):page201_i725@pure_quanta.q_cap(chips)';

PART_NAME
 C2775 'Q_CAP_0402-0.01UF,25V,10%,X7R,TMP_QCH31004KB17':
;

SECTION_NUMBER 1
 '@T6G_MB_LIB.T6G(SCH_1):PAGE201_I726@PURE_QUANTA.Q_CAP(CHIPS)':
 C_PATH='@t6g_mb_lib.t6g(sch_1):page201_i726@pure_quanta.q_cap(chips)';

PART_NAME
 C2774 'Q_CAP_0402-0.01UF,25V,10%,X7R,TMP_QCH31004KB17':
;

SECTION_NUMBER 1
 '@T6G_MB_LIB.T6G(SCH_1):PAGE201_I868@PURE_QUANTA.Q_CAP(CHIPS)':
 C_PATH='@t6g_mb_lib.t6g(sch_1):page201_i868@pure_quanta.q_cap(chips)';

PART_NAME
 C2772 'Q_CAP_0402-0.01UF,25V,10%,X7R,TMP_QCH31004KB17':
;

SECTION_NUMBER 1
 '@T6G_MB_LIB.T6G(SCH_1):PAGE201_I683@PURE_QUANTA.Q_CAP(CHIPS)':
 C_PATH='@t6g_mb_lib.t6g(sch_1):page201_i683@pure_quanta.q_cap(chips)';

PART_NAME
 C2771 'Q_CAP_0402-0.01UF,25V,10%,X7R,TMP_QCH31004KB17':
;

SECTION_NUMBER 1
 '@T6G_MB_LIB.T6G(SCH_1):PAGE201_I682@PURE_QUANTA.Q_CAP(CHIPS)':
 C_PATH='@t6g_mb_lib.t6g(sch_1):page201_i682@pure_quanta.q_cap(chips)';

PART_NAME
 C2770 'Q_CAP_0402-0.01UF,25V,10%,X7R,TMP_QCH31004KB17':
;

SECTION_NUMBER 1
 '@T6G_MB_LIB.T6G(SCH_1):PAGE201_I859@PURE_QUANTA.Q_CAP(CHIPS)':
 C_PATH='@t6g_mb_lib.t6g(sch_1):page201_i859@pure_quanta.q_cap(chips)';

PART_NAME
 C2768 'Q_CAP_0402-0.01UF,25V,10%,X7R,TMP_QCH31004KB17':
;

SECTION_NUMBER 1
 '@T6G_MB_LIB.T6G(SCH_1):PAGE201_I700@PURE_QUANTA.Q_CAP(CHIPS)':
 C_PATH='@t6g_mb_lib.t6g(sch_1):page201_i700@pure_quanta.q_cap(chips)';

PART_NAME
 C2767 'Q_CAP_0402-0.01UF,25V,10%,X7R,TMP_QCH31004KB17':
;

SECTION_NUMBER 1
 '@T6G_MB_LIB.T6G(SCH_1):PAGE201_I701@PURE_QUANTA.Q_CAP(CHIPS)':
 C_PATH='@t6g_mb_lib.t6g(sch_1):page201_i701@pure_quanta.q_cap(chips)';

PART_NAME
 C2766 'Q_CAP_0402-0.01UF,25V,10%,X7R,TMP_QCH31004KB17':
;

SECTION_NUMBER 1
 '@T6G_MB_LIB.T6G(SCH_1):PAGE201_I850@PURE_QUANTA.Q_CAP(CHIPS)':
 C_PATH='@t6g_mb_lib.t6g(sch_1):page201_i850@pure_quanta.q_cap(chips)';

PART_NAME
 C2764 'Q_CAP_0402-0.01UF,25V,10%,X7R,TMP_QCH31004KB17':
;

SECTION_NUMBER 1
 '@T6G_MB_LIB.T6G(SCH_1):PAGE201_I720@PURE_QUANTA.Q_CAP(CHIPS)':
 C_PATH='@t6g_mb_lib.t6g(sch_1):page201_i720@pure_quanta.q_cap(chips)';

PART_NAME
 C2763 'Q_CAP_0402-0.01UF,25V,10%,X7R,TMP_QCH31004KB17':
;

SECTION_NUMBER 1
 '@T6G_MB_LIB.T6G(SCH_1):PAGE201_I721@PURE_QUANTA.Q_CAP(CHIPS)':
 C_PATH='@t6g_mb_lib.t6g(sch_1):page201_i721@pure_quanta.q_cap(chips)';

PART_NAME
 L84 'Q_INDUCTOR_SMLF-GMLB-201209-0330P-N8(330/3A),IND,CX090330000':;

SECTION_NUMBER 1
 '@T6G_MB_LIB.T6G(SCH_1):PAGE266_I18@PURE_QUANTA.Q_INDUCTOR(CHIPS)':
 C_PATH='@t6g_mb_lib.t6g(sch_1):page266_i18@pure_quanta.q_inductor(chips)';

PART_NAME
 L83 'Q_INDUCTOR_SMLF-GMLB-201209-0330P-N8(330/3A),IND,CX090330000':;

SECTION_NUMBER 1
 '@T6G_MB_LIB.T6G(SCH_1):PAGE266_I24@PURE_QUANTA.Q_INDUCTOR(CHIPS)':
 C_PATH='@t6g_mb_lib.t6g(sch_1):page266_i24@pure_quanta.q_inductor(chips)';

PART_NAME
 C2628 'Q_CAP_C0603-22UF,6.3V,20%,X6S,CH6221ME900':;

SECTION_NUMBER 1
 '@T6G_MB_LIB.T6G(SCH_1):PAGE266_I61@PURE_QUANTA.Q_CAP(CHIPS)':
 C_PATH='@t6g_mb_lib.t6g(sch_1):page266_i61@pure_quanta.q_cap(chips)';

PART_NAME
 C2627 'Q_CAP_C0603-22UF,6.3V,20%,X6S,CH6221ME900':;

SECTION_NUMBER 1
 '@T6G_MB_LIB.T6G(SCH_1):PAGE266_I67@PURE_QUANTA.Q_CAP(CHIPS)':
 C_PATH='@t6g_mb_lib.t6g(sch_1):page266_i67@pure_quanta.q_cap(chips)';

PART_NAME
 C2626 'Q_CAP_C0402-1UF,25V,10%,X6S,CH5104KEB02':;

SECTION_NUMBER 1
 '@T6G_MB_LIB.T6G(SCH_1):PAGE266_I59@PURE_QUANTA.Q_CAP(CHIPS)':
 C_PATH='@t6g_mb_lib.t6g(sch_1):page266_i59@pure_quanta.q_cap(chips)';

PART_NAME
 C2625 'Q_CAP_C0402-1UF,25V,10%,X6S,CH5104KEB02':;

SECTION_NUMBER 1
 '@T6G_MB_LIB.T6G(SCH_1):PAGE266_I65@PURE_QUANTA.Q_CAP(CHIPS)':
 C_PATH='@t6g_mb_lib.t6g(sch_1):page266_i65@pure_quanta.q_cap(chips)';

PART_NAME
 C2616 'Q_CAP_C0402-1UF,25V,10%,X6S,CH5104KEB02':;

SECTION_NUMBER 1
 '@T6G_MB_LIB.T6G(SCH_1):PAGE266_I16@PURE_QUANTA.Q_CAP(CHIPS)':
 C_PATH='@t6g_mb_lib.t6g(sch_1):page266_i16@pure_quanta.q_cap(chips)';

PART_NAME
 C2615 'Q_CAP_C0402-0.1UF,16V,10%,X7R,CH4103K1B08':;

SECTION_NUMBER 1
 '@T6G_MB_LIB.T6G(SCH_1):PAGE266_I14@PURE_QUANTA.Q_CAP(CHIPS)':
 C_PATH='@t6g_mb_lib.t6g(sch_1):page266_i14@pure_quanta.q_cap(chips)';

PART_NAME
 C2612 'Q_CAP_C0402-0.1UF,16V,10%,X7R,CH4103K1B08':;

SECTION_NUMBER 1
 '@T6G_MB_LIB.T6G(SCH_1):PAGE266_I13@PURE_QUANTA.Q_CAP(CHIPS)':
 C_PATH='@t6g_mb_lib.t6g(sch_1):page266_i13@pure_quanta.q_cap(chips)';

PART_NAME
 C2607 'Q_CAP_C0402-0.1UF,16V,10%,X7R,CH4103K1B08':;

SECTION_NUMBER 1
 '@T6G_MB_LIB.T6G(SCH_1):PAGE266_I69@PURE_QUANTA.Q_CAP(CHIPS)':
 C_PATH='@t6g_mb_lib.t6g(sch_1):page266_i69@pure_quanta.q_cap(chips)';

PART_NAME
 C2606 'Q_CAP_C0402-0.1UF,16V,10%,X7R,CH4103K1B08':;

SECTION_NUMBER 1
 '@T6G_MB_LIB.T6G(SCH_1):PAGE266_I38@PURE_QUANTA.Q_CAP(CHIPS)':
 C_PATH='@t6g_mb_lib.t6g(sch_1):page266_i38@pure_quanta.q_cap(chips)';

PART_NAME
 C2605 'Q_CAP_C0402-0.1UF,16V,10%,X7R,CH4103K1B08':;

SECTION_NUMBER 1
 '@T6G_MB_LIB.T6G(SCH_1):PAGE266_I11@PURE_QUANTA.Q_CAP(CHIPS)':
 C_PATH='@t6g_mb_lib.t6g(sch_1):page266_i11@pure_quanta.q_cap(chips)';

PART_NAME
 C2604 'Q_CAP_C0603-22UF,6.3V,20%,X6S,CH6221ME900':;

SECTION_NUMBER 1
 '@T6G_MB_LIB.T6G(SCH_1):PAGE266_I27@PURE_QUANTA.Q_CAP(CHIPS)':
 C_PATH='@t6g_mb_lib.t6g(sch_1):page266_i27@pure_quanta.q_cap(chips)';

PART_NAME
 C2602 'Q_CAP_C0402-0.1UF,16V,10%,X7R,CH4103K1B08':;

SECTION_NUMBER 1
 '@T6G_MB_LIB.T6G(SCH_1):PAGE266_I8@PURE_QUANTA.Q_CAP(CHIPS)':
 C_PATH='@t6g_mb_lib.t6g(sch_1):page266_i8@pure_quanta.q_cap(chips)';

PART_NAME
 C2601 'Q_CAP_C0402-1UF,25V,10%,X6S,CH5104KEB02':;

SECTION_NUMBER 1
 '@T6G_MB_LIB.T6G(SCH_1):PAGE266_I25@PURE_QUANTA.Q_CAP(CHIPS)':
 C_PATH='@t6g_mb_lib.t6g(sch_1):page266_i25@pure_quanta.q_cap(chips)';

PART_NAME
 C2600 'Q_CAP_C0402-0.1UF,16V,10%,X7R,CH4103K1B08':;

SECTION_NUMBER 1
 '@T6G_MB_LIB.T6G(SCH_1):PAGE266_I33@PURE_QUANTA.Q_CAP(CHIPS)':
 C_PATH='@t6g_mb_lib.t6g(sch_1):page266_i33@pure_quanta.q_cap(chips)';

PART_NAME
 C2599 'Q_CAP_C0603-22UF,6.3V,20%,X6S,CH6221ME900':;

SECTION_NUMBER 1
 '@T6G_MB_LIB.T6G(SCH_1):PAGE266_I7@PURE_QUANTA.Q_CAP(CHIPS)':
 C_PATH='@t6g_mb_lib.t6g(sch_1):page266_i7@pure_quanta.q_cap(chips)';

PART_NAME
 C2598 'Q_CAP_C0402-1UF,25V,10%,X6S,CH5104KEB02':;

SECTION_NUMBER 1
 '@T6G_MB_LIB.T6G(SCH_1):PAGE266_I4@PURE_QUANTA.Q_CAP(CHIPS)':
 C_PATH='@t6g_mb_lib.t6g(sch_1):page266_i4@pure_quanta.q_cap(chips)';

PART_NAME
 C2597 'Q_CAP_C0603-22UF,6.3V,20%,X6S,CH6221ME900':;

SECTION_NUMBER 1
 '@T6G_MB_LIB.T6G(SCH_1):PAGE266_I23@PURE_QUANTA.Q_CAP(CHIPS)':
 C_PATH='@t6g_mb_lib.t6g(sch_1):page266_i23@pure_quanta.q_cap(chips)';

PART_NAME
 C2596 'Q_CAP_C0402-1UF,25V,10%,X6S,CH5104KEB02':;

SECTION_NUMBER 1
 '@T6G_MB_LIB.T6G(SCH_1):PAGE266_I21@PURE_QUANTA.Q_CAP(CHIPS)':
 C_PATH='@t6g_mb_lib.t6g(sch_1):page266_i21@pure_quanta.q_cap(chips)';

PART_NAME
 C2595 'Q_CAP_C0402-0.01UF,50V,10%,X7R,CH31006KB18':
;

SECTION_NUMBER 1
 '@T6G_MB_LIB.T6G(SCH_1):PAGE266_I58@PURE_QUANTA.Q_CAP(CHIPS)':
 C_PATH='@t6g_mb_lib.t6g(sch_1):page266_i58@pure_quanta.q_cap(chips)';

PART_NAME
 C2594 'Q_CAP_C0402-0.01UF,50V,10%,X7R,CH31006KB18':
;

SECTION_NUMBER 1
 '@T6G_MB_LIB.T6G(SCH_1):PAGE266_I63@PURE_QUANTA.Q_CAP(CHIPS)':
 C_PATH='@t6g_mb_lib.t6g(sch_1):page266_i63@pure_quanta.q_cap(chips)';

PART_NAME
 C2593 'Q_CAP_C0402-0.01UF,50V,10%,X7R,CH31006KB18':
;

SECTION_NUMBER 1
 '@T6G_MB_LIB.T6G(SCH_1):PAGE266_I54@PURE_QUANTA.Q_CAP(CHIPS)':
 C_PATH='@t6g_mb_lib.t6g(sch_1):page266_i54@pure_quanta.q_cap(chips)';

PART_NAME
 C2592 'Q_CAP_C0402-0.01UF,50V,10%,X7R,CH31006KB18':
;

SECTION_NUMBER 1
 '@T6G_MB_LIB.T6G(SCH_1):PAGE266_I56@PURE_QUANTA.Q_CAP(CHIPS)':
 C_PATH='@t6g_mb_lib.t6g(sch_1):page266_i56@pure_quanta.q_cap(chips)';

PART_NAME
 C2591 'Q_CAP_C0402-0.01UF,50V,10%,X7R,CH31006KB18':
;

SECTION_NUMBER 1
 '@T6G_MB_LIB.T6G(SCH_1):PAGE266_I47@PURE_QUANTA.Q_CAP(CHIPS)':
 C_PATH='@t6g_mb_lib.t6g(sch_1):page266_i47@pure_quanta.q_cap(chips)';

PART_NAME
 C2590 'Q_CAP_C0402-0.01UF,50V,10%,X7R,CH31006KB18':
;

SECTION_NUMBER 1
 '@T6G_MB_LIB.T6G(SCH_1):PAGE266_I52@PURE_QUANTA.Q_CAP(CHIPS)':
 C_PATH='@t6g_mb_lib.t6g(sch_1):page266_i52@pure_quanta.q_cap(chips)';

PART_NAME
 C2589 'Q_CAP_C0402-0.01UF,50V,10%,X7R,CH31006KB18':
;

SECTION_NUMBER 1
 '@T6G_MB_LIB.T6G(SCH_1):PAGE266_I46@PURE_QUANTA.Q_CAP(CHIPS)':
 C_PATH='@t6g_mb_lib.t6g(sch_1):page266_i46@pure_quanta.q_cap(chips)';

PART_NAME
 C2588 'Q_CAP_C0402-0.01UF,50V,10%,X7R,CH31006KB18':
;

SECTION_NUMBER 1
 '@T6G_MB_LIB.T6G(SCH_1):PAGE266_I50@PURE_QUANTA.Q_CAP(CHIPS)':
 C_PATH='@t6g_mb_lib.t6g(sch_1):page266_i50@pure_quanta.q_cap(chips)';

PART_NAME
 C2586 'Q_CAP_C0402-0.01UF,50V,10%,X7R,CH31006KB18':
;

SECTION_NUMBER 1
 '@T6G_MB_LIB.T6G(SCH_1):PAGE266_I42@PURE_QUANTA.Q_CAP(CHIPS)':
 C_PATH='@t6g_mb_lib.t6g(sch_1):page266_i42@pure_quanta.q_cap(chips)';

PART_NAME
 C2585 'Q_CAP_C0402-0.01UF,50V,10%,X7R,CH31006KB18':
;

SECTION_NUMBER 1
 '@T6G_MB_LIB.T6G(SCH_1):PAGE266_I44@PURE_QUANTA.Q_CAP(CHIPS)':
 C_PATH='@t6g_mb_lib.t6g(sch_1):page266_i44@pure_quanta.q_cap(chips)';

PART_NAME
 C2584 'Q_CAP_C0402-0.01UF,50V,10%,X7R,CH31006KB18':
;

SECTION_NUMBER 1
 '@T6G_MB_LIB.T6G(SCH_1):PAGE266_I12@PURE_QUANTA.Q_CAP(CHIPS)':
 C_PATH='@t6g_mb_lib.t6g(sch_1):page266_i12@pure_quanta.q_cap(chips)';

PART_NAME
 C2583 'Q_CAP_C0402-0.01UF,50V,10%,X7R,CH31006KB18':
;

SECTION_NUMBER 1
 '@T6G_MB_LIB.T6G(SCH_1):PAGE266_I39@PURE_QUANTA.Q_CAP(CHIPS)':
 C_PATH='@t6g_mb_lib.t6g(sch_1):page266_i39@pure_quanta.q_cap(chips)';

PART_NAME
 C2582 'Q_CAP_C0402-0.01UF,50V,10%,X7R,CH31006KB18':
;

SECTION_NUMBER 1
 '@T6G_MB_LIB.T6G(SCH_1):PAGE266_I29@PURE_QUANTA.Q_CAP(CHIPS)':
 C_PATH='@t6g_mb_lib.t6g(sch_1):page266_i29@pure_quanta.q_cap(chips)';

PART_NAME
 C2581 'Q_CAP_C0402-0.01UF,50V,10%,X7R,CH31006KB18':
;

SECTION_NUMBER 1
 '@T6G_MB_LIB.T6G(SCH_1):PAGE266_I30@PURE_QUANTA.Q_CAP(CHIPS)':
 C_PATH='@t6g_mb_lib.t6g(sch_1):page266_i30@pure_quanta.q_cap(chips)';

PART_NAME
 C2578 'Q_CAP_C0402-0.01UF,50V,10%,X7R,CH31006KB18':
;

SECTION_NUMBER 1
 '@T6G_MB_LIB.T6G(SCH_1):PAGE266_I36@PURE_QUANTA.Q_CAP(CHIPS)':
 C_PATH='@t6g_mb_lib.t6g(sch_1):page266_i36@pure_quanta.q_cap(chips)';

PART_NAME
 U173 'M24128BWMN6TPA_SMLF-M24128BWMN6TP,IC,TMP_QAKE30Z00613':;

SECTION_NUMBER 1
 '@T6G_MB_LIB.T6G(SCH_1):PAGE272_I60@PURE_QUANTA.M24128BWMN6TPA(CHIPS)':
 C_PATH='@t6g_mb_lib.t6g(sch_1):page272_i60@pure_quanta.m24128bwmn6tpa(chips)';

PART_NAME
 U163 'TMP75AIDR-TMP75AIDR,SMLF,IC,AL000075061':;

SECTION_NUMBER 1
 '@T6G_MB_LIB.T6G(SCH_1):PAGE272_I21@PURE_QUANTA.TMP75AIDR(CHIPS)':
 C_PATH='@t6g_mb_lib.t6g(sch_1):page272_i21@pure_quanta.tmp75aidr(chips)';

PART_NAME
 U114 'TMP75AIDR-TMP75AIDR,SMLF,IC,AL000075061':;

SECTION_NUMBER 1
 '@T6G_MB_LIB.T6G(SCH_1):PAGE272_I59@PURE_QUANTA.TMP75AIDR(CHIPS)':
 C_PATH='@t6g_mb_lib.t6g(sch_1):page272_i59@pure_quanta.tmp75aidr(chips)';

PART_NAME
 R2883 'Q_RES_0402LF-1K,1%,1/16W,EMPTY,TMP_QCS21002FB24':;

SECTION_NUMBER 1
 '@T6G_MB_LIB.T6G(SCH_1):PAGE272_I48@PURE_QUANTA.Q_RES(CHIPS)':
 C_PATH='@t6g_mb_lib.t6g(sch_1):page272_i48@pure_quanta.q_res(chips)';

PART_NAME
 R2880 'Q_RES_0402LF-10K,1%,1/16W,EMPTY,TMP_QCS31002FB26':;

SECTION_NUMBER 1
 '@T6G_MB_LIB.T6G(SCH_1):PAGE272_I43@PURE_QUANTA.Q_RES(CHIPS)':
 C_PATH='@t6g_mb_lib.t6g(sch_1):page272_i43@pure_quanta.q_res(chips)';

PART_NAME
 R2868 'Q_RES_0402LF-1K,1%,1/16W,CHIP,TMP_QCS21002FB24':;

SECTION_NUMBER 1
 '@T6G_MB_LIB.T6G(SCH_1):PAGE272_I46@PURE_QUANTA.Q_RES(CHIPS)':
 C_PATH='@t6g_mb_lib.t6g(sch_1):page272_i46@pure_quanta.q_res(chips)';

PART_NAME
 R2859 'Q_RES_0402LF-1K,1%,1/16W,CHIP,TMP_QCS21002FB24':;

SECTION_NUMBER 1
 '@T6G_MB_LIB.T6G(SCH_1):PAGE272_I52@PURE_QUANTA.Q_RES(CHIPS)':
 C_PATH='@t6g_mb_lib.t6g(sch_1):page272_i52@pure_quanta.q_res(chips)';

PART_NAME
 R2854 'Q_RES_0402LF-10K,1%,1/16W,EMPTY,TMP_QCS31002FB26':;

SECTION_NUMBER 1
 '@T6G_MB_LIB.T6G(SCH_1):PAGE272_I55@PURE_QUANTA.Q_RES(CHIPS)':
 C_PATH='@t6g_mb_lib.t6g(sch_1):page272_i55@pure_quanta.q_res(chips)';

PART_NAME
 R2853 'Q_RES_0402LF-33,5%,1/16W,CHIP,CS03302JB29':;

SECTION_NUMBER 1
 '@T6G_MB_LIB.T6G(SCH_1):PAGE272_I19@PURE_QUANTA.Q_RES(CHIPS)':
 C_PATH='@t6g_mb_lib.t6g(sch_1):page272_i19@pure_quanta.q_res(chips)';

PART_NAME
 R1314 'Q_RES_0402LF-1K,1%,1/16W,EMPTY,TMP_QCS21002FB24':;

SECTION_NUMBER 1
 '@T6G_MB_LIB.T6G(SCH_1):PAGE272_I28@PURE_QUANTA.Q_RES(CHIPS)':
 C_PATH='@t6g_mb_lib.t6g(sch_1):page272_i28@pure_quanta.q_res(chips)';

PART_NAME
 R1312 'Q_RES_0402LF-1K,1%,1/16W,CHIP,TMP_QCS21002FB24':;

SECTION_NUMBER 1
 '@T6G_MB_LIB.T6G(SCH_1):PAGE272_I54@PURE_QUANTA.Q_RES(CHIPS)':
 C_PATH='@t6g_mb_lib.t6g(sch_1):page272_i54@pure_quanta.q_res(chips)';

PART_NAME
 R1311 'Q_RES_0402LF-1K,1%,1/16W,CHIP,TMP_QCS21002FB24':;

SECTION_NUMBER 1
 '@T6G_MB_LIB.T6G(SCH_1):PAGE272_I27@PURE_QUANTA.Q_RES(CHIPS)':
 C_PATH='@t6g_mb_lib.t6g(sch_1):page272_i27@pure_quanta.q_res(chips)';

PART_NAME
 R1308 'Q_RES_0402LF-10K,1%,1/16W,EMPTY,TMP_QCS31002FB26':;

SECTION_NUMBER 1
 '@T6G_MB_LIB.T6G(SCH_1):PAGE272_I49@PURE_QUANTA.Q_RES(CHIPS)':
 C_PATH='@t6g_mb_lib.t6g(sch_1):page272_i49@pure_quanta.q_res(chips)';

PART_NAME
 R1305 'Q_RES_0402LF-10K,1%,1/16W,EMPTY,TMP_QCS31002FB26':;

SECTION_NUMBER 1
 '@T6G_MB_LIB.T6G(SCH_1):PAGE272_I30@PURE_QUANTA.Q_RES(CHIPS)':
 C_PATH='@t6g_mb_lib.t6g(sch_1):page272_i30@pure_quanta.q_res(chips)';

PART_NAME
 R1304 'Q_RES_0402LF-10K,1%,1/16W,EMPTY,TMP_QCS31002FB26':;

SECTION_NUMBER 1
 '@T6G_MB_LIB.T6G(SCH_1):PAGE272_I34@PURE_QUANTA.Q_RES(CHIPS)':
 C_PATH='@t6g_mb_lib.t6g(sch_1):page272_i34@pure_quanta.q_res(chips)';

PART_NAME
 R1303 'Q_RES_0402LF-1K,1%,1/16W,CHIP,TMP_QCS21002FB24':;

SECTION_NUMBER 1
 '@T6G_MB_LIB.T6G(SCH_1):PAGE272_I6@PURE_QUANTA.Q_RES(CHIPS)':
 C_PATH='@t6g_mb_lib.t6g(sch_1):page272_i6@pure_quanta.q_res(chips)';

PART_NAME
 R1302 'Q_RES_0402LF-0,5%,1/16W,CHIP,CS00002JB38':;

SECTION_NUMBER 1
 '@T6G_MB_LIB.T6G(SCH_1):PAGE272_I4@PURE_QUANTA.Q_RES(CHIPS)':
 C_PATH='@t6g_mb_lib.t6g(sch_1):page272_i4@pure_quanta.q_res(chips)';

PART_NAME
 R732 'Q_RES_0402LF-10K,1%,1/16W,CHIP,TMP_QCS31002FB26':;

SECTION_NUMBER 1
 '@T6G_MB_LIB.T6G(SCH_1):PAGE272_I50@PURE_QUANTA.Q_RES(CHIPS)':
 C_PATH='@t6g_mb_lib.t6g(sch_1):page272_i50@pure_quanta.q_res(chips)';

PART_NAME
 R729 'Q_RES_0402LF-1K,1%,1/16W,CHIP,TMP_QCS21002FB24':;

SECTION_NUMBER 1
 '@T6G_MB_LIB.T6G(SCH_1):PAGE272_I33@PURE_QUANTA.Q_RES(CHIPS)':
 C_PATH='@t6g_mb_lib.t6g(sch_1):page272_i33@pure_quanta.q_res(chips)';

PART_NAME
 R726 'Q_RES_0402LF-0,5%,1/16W,CHIP,CS00002JB38':;

SECTION_NUMBER 1
 '@T6G_MB_LIB.T6G(SCH_1):PAGE272_I13@PURE_QUANTA.Q_RES(CHIPS)':
 C_PATH='@t6g_mb_lib.t6g(sch_1):page272_i13@pure_quanta.q_res(chips)';

PART_NAME
 R725 'Q_RES_0402LF-33,5%,1/16W,CHIP,CS03302JB29':;

SECTION_NUMBER 1
 '@T6G_MB_LIB.T6G(SCH_1):PAGE272_I12@PURE_QUANTA.Q_RES(CHIPS)':
 C_PATH='@t6g_mb_lib.t6g(sch_1):page272_i12@pure_quanta.q_res(chips)';

PART_NAME
 R721 'Q_RES_0402LF-10K,1%,1/16W,CHIP,TMP_QCS31002FB26':;

SECTION_NUMBER 1
 '@T6G_MB_LIB.T6G(SCH_1):PAGE272_I44@PURE_QUANTA.Q_RES(CHIPS)':
 C_PATH='@t6g_mb_lib.t6g(sch_1):page272_i44@pure_quanta.q_res(chips)';

PART_NAME
 R719 'Q_RES_0402LF-10K,1%,1/16W,EMPTY,TMP_QCS31002FB26':;

SECTION_NUMBER 1
 '@T6G_MB_LIB.T6G(SCH_1):PAGE272_I56@PURE_QUANTA.Q_RES(CHIPS)':
 C_PATH='@t6g_mb_lib.t6g(sch_1):page272_i56@pure_quanta.q_res(chips)';

PART_NAME
 R714 'Q_RES_0402LF-1K,1%,1/16W,CHIP,TMP_QCS21002FB24':;

SECTION_NUMBER 1
 '@T6G_MB_LIB.T6G(SCH_1):PAGE272_I24@PURE_QUANTA.Q_RES(CHIPS)':
 C_PATH='@t6g_mb_lib.t6g(sch_1):page272_i24@pure_quanta.q_res(chips)';

PART_NAME
 R712 'Q_RES_0402LF-1K,1%,1/16W,CHIP,TMP_QCS21002FB24':;

SECTION_NUMBER 1
 '@T6G_MB_LIB.T6G(SCH_1):PAGE272_I41@PURE_QUANTA.Q_RES(CHIPS)':
 C_PATH='@t6g_mb_lib.t6g(sch_1):page272_i41@pure_quanta.q_res(chips)';

PART_NAME
 R711 'Q_RES_0402LF-10K,1%,1/16W,EMPTY,TMP_QCS31002FB26':;

SECTION_NUMBER 1
 '@T6G_MB_LIB.T6G(SCH_1):PAGE272_I42@PURE_QUANTA.Q_RES(CHIPS)':
 C_PATH='@t6g_mb_lib.t6g(sch_1):page272_i42@pure_quanta.q_res(chips)';

PART_NAME
 R475 'Q_RES_0402LF-0,5%,1/16W,CHIP,CS00002JB38':;

SECTION_NUMBER 1
 '@T6G_MB_LIB.T6G(SCH_1):PAGE272_I3@PURE_QUANTA.Q_RES(CHIPS)':
 C_PATH='@t6g_mb_lib.t6g(sch_1):page272_i3@pure_quanta.q_res(chips)';

PART_NAME
 R460 'Q_RES_0402LF-33,5%,1/16W,CHIP,CS03302JB29':;

SECTION_NUMBER 1
 '@T6G_MB_LIB.T6G(SCH_1):PAGE272_I18@PURE_QUANTA.Q_RES(CHIPS)':
 C_PATH='@t6g_mb_lib.t6g(sch_1):page272_i18@pure_quanta.q_res(chips)';

PART_NAME
 JP30 'CONN3_210HP1030BR1-CONN3_210-HP1-030BR1,THLF,IO,DFHD03MS213':;

SECTION_NUMBER 1
 '@T6G_MB_LIB.T6G(SCH_1):PAGE272_I62@PURE_QUANTA.CONN3_210HP1030BR1(CHIPS)':
 C_PATH='@t6g_mb_lib.t6g(sch_1):page272_i62@pure_quanta.conn3_210hp1030br1(chips~
)';

PART_NAME
 C2536 'Q_CAP_0402-0.1UF,25V,10%,X7R,CH4104K1B00':;

SECTION_NUMBER 1
 '@T6G_MB_LIB.T6G(SCH_1):PAGE272_I35@PURE_QUANTA.Q_CAP(CHIPS)':
 C_PATH='@t6g_mb_lib.t6g(sch_1):page272_i35@pure_quanta.q_cap(chips)';

PART_NAME
 C2535 'Q_CAP_0402-0.1UF,25V,10%,X7R,CH4104K1B00':;

SECTION_NUMBER 1
 '@T6G_MB_LIB.T6G(SCH_1):PAGE272_I38@PURE_QUANTA.Q_CAP(CHIPS)':
 C_PATH='@t6g_mb_lib.t6g(sch_1):page272_i38@pure_quanta.q_cap(chips)';

PART_NAME
 C2534 'Q_CAP_0402-0.1UF,25V,10%,X7R,CH4104K1B00':;

SECTION_NUMBER 1
 '@T6G_MB_LIB.T6G(SCH_1):PAGE272_I15@PURE_QUANTA.Q_CAP(CHIPS)':
 C_PATH='@t6g_mb_lib.t6g(sch_1):page272_i15@pure_quanta.q_cap(chips)';

PART_NAME
 U100 'TPS259521DSGR-TPS259521DSGR,SMLF,IC,AL259521000':;

SECTION_NUMBER 1
 '@T6G_MB_LIB.T6G(SCH_1):PAGE153_I13@PURE_QUANTA.TPS259521DSGR(CHIPS)':
 C_PATH='@t6g_mb_lib.t6g(sch_1):page153_i13@pure_quanta.tps259521dsgr(chips)';

PART_NAME
 U99 'TPS259541DSGR-TPS259541DSGR,SMLF,IC,AL259541000':;

SECTION_NUMBER 1
 '@T6G_MB_LIB.T6G(SCH_1):PAGE153_I27@PURE_QUANTA.TPS259541DSGR(CHIPS)':
 C_PATH='@t6g_mb_lib.t6g(sch_1):page153_i27@pure_quanta.tps259541dsgr(chips)';

PART_NAME
 R1275 'Q_RES_0402LF-750,1%,1/16W,CHIP,CS17502FB19':;

SECTION_NUMBER 1
 '@T6G_MB_LIB.T6G(SCH_1):PAGE153_I18@PURE_QUANTA.Q_RES(CHIPS)':
 C_PATH='@t6g_mb_lib.t6g(sch_1):page153_i18@pure_quanta.q_res(chips)';

PART_NAME
 R1274 'Q_RES_0402LF-576,1%,1/16W,CHIP,CS15762FB26':;

SECTION_NUMBER 1
 '@T6G_MB_LIB.T6G(SCH_1):PAGE153_I34@PURE_QUANTA.Q_RES(CHIPS)':
 C_PATH='@t6g_mb_lib.t6g(sch_1):page153_i34@pure_quanta.q_res(chips)';

PART_NAME
 R1273 'Q_RES_0402LF-10K,5%,1/16W,CHIP,TMP_QCS31002JB28':;

SECTION_NUMBER 1
 '@T6G_MB_LIB.T6G(SCH_1):PAGE153_I10@PURE_QUANTA.Q_RES(CHIPS)':
 C_PATH='@t6g_mb_lib.t6g(sch_1):page153_i10@pure_quanta.q_res(chips)';

PART_NAME
 J214 'Q_SHORT_SM-EMPTY,SHORT7':;

SECTION_NUMBER 1
 '@T6G_MB_LIB.T6G(SCH_1):PAGE153_I8@PURE_QUANTA.Q_SHORT(CHIPS)':
 C_PATH='@t6g_mb_lib.t6g(sch_1):page153_i8@pure_quanta.q_short(chips)';

PART_NAME
 J213 'Q_SHORT_SM-EMPTY,SHORT7':;

SECTION_NUMBER 1
 '@T6G_MB_LIB.T6G(SCH_1):PAGE153_I9@PURE_QUANTA.Q_SHORT(CHIPS)':
 C_PATH='@t6g_mb_lib.t6g(sch_1):page153_i9@pure_quanta.q_short(chips)';

PART_NAME
 D44 'SCHOTTKY_AC-SS1040,SMLF,IC,BCSS1040005':;

SECTION_NUMBER 1
 '@T6G_MB_LIB.T6G(SCH_1):PAGE153_I29@PURE_QUANTA.SCHOTTKY_AC(CHIPS)':
 C_PATH='@t6g_mb_lib.t6g(sch_1):page153_i29@pure_quanta.schottky_ac(chips)';

PART_NAME
 D43 'DIODE_TVS-SMF13A,SMLF,IC,BCSMF13AZ01':;

SECTION_NUMBER 1
 '@T6G_MB_LIB.T6G(SCH_1):PAGE153_I20@PURE_QUANTA.DIODE_TVS(CHIPS)':
 C_PATH='@t6g_mb_lib.t6g(sch_1):page153_i20@pure_quanta.diode_tvs(chips)';

PART_NAME
 C2526 'Q_CAP_C0805-10UF,16V,10%,X6S,CH6103KEA00':;

SECTION_NUMBER 1
 '@T6G_MB_LIB.T6G(SCH_1):PAGE153_I15@PURE_QUANTA.Q_CAP(CHIPS)':
 C_PATH='@t6g_mb_lib.t6g(sch_1):page153_i15@pure_quanta.q_cap(chips)';

PART_NAME
 C2525 'Q_CAP_C0805-10UF,16V,10%,X6S,CH6103KEA00':;

SECTION_NUMBER 1
 '@T6G_MB_LIB.T6G(SCH_1):PAGE153_I31@PURE_QUANTA.Q_CAP(CHIPS)':
 C_PATH='@t6g_mb_lib.t6g(sch_1):page153_i31@pure_quanta.q_cap(chips)';

PART_NAME
 C2524 'Q_CAP_0402-0.1UF,25V,10%,X7R,CH4104K1B00':;

SECTION_NUMBER 1
 '@T6G_MB_LIB.T6G(SCH_1):PAGE153_I4@PURE_QUANTA.Q_CAP(CHIPS)':
 C_PATH='@t6g_mb_lib.t6g(sch_1):page153_i4@pure_quanta.q_cap(chips)';

PART_NAME
 C2523 'Q_CAP_0402-0.1UF,25V,10%,X7R,CH4104K1B00':;

SECTION_NUMBER 1
 '@T6G_MB_LIB.T6G(SCH_1):PAGE153_I23@PURE_QUANTA.Q_CAP(CHIPS)':
 C_PATH='@t6g_mb_lib.t6g(sch_1):page153_i23@pure_quanta.q_cap(chips)';

PART_NAME
 C2522 'Q_CAP_C0402-39NF,16V,10%,X7R,CH3393K1B00':;

SECTION_NUMBER 1
 '@T6G_MB_LIB.T6G(SCH_1):PAGE153_I26@PURE_QUANTA.Q_CAP(CHIPS)':
 C_PATH='@t6g_mb_lib.t6g(sch_1):page153_i26@pure_quanta.q_cap(chips)';

PART_NAME
 C2521 'Q_CAP_C0603-0.15UF,10V,10%,X7R,CH41502K909':;

SECTION_NUMBER 1
 '@T6G_MB_LIB.T6G(SCH_1):PAGE153_I6@PURE_QUANTA.Q_CAP(CHIPS)':
 C_PATH='@t6g_mb_lib.t6g(sch_1):page153_i6@pure_quanta.q_cap(chips)';

PART_NAME
 U95 'TPS3808G18DBVR-TPS3808G18DBVR,SMLF,IC,AL003808003':;

SECTION_NUMBER 1
 '@T6G_MB_LIB.T6G(SCH_1):PAGE151_I64@PURE_QUANTA.TPS3808G18DBVR(CHIPS)':
 C_PATH='@t6g_mb_lib.t6g(sch_1):page151_i64@pure_quanta.tps3808g18dbvr(chips)';

PART_NAME
 U94 'SN74LVC2G07DCKR_SMLF-SN74LVC2G07DCKR,IC,AL002G07006':;

SECTION_NUMBER 1
 '@T6G_MB_LIB.T6G(SCH_1):PAGE151_I36@PURE_QUANTA.SN74LVC2G07DCKR(CHIPS)':
 C_PATH='@t6g_mb_lib.t6g(sch_1):page151_i36@pure_quanta.sn74lvc2g07dckr(chips)';

PART_NAME
 U93 'SN74LVC1G17DCKR-SN74LVC1G17DCKR,SMLF,IC,AL1G0017003':;

SECTION_NUMBER 1
 '@T6G_MB_LIB.T6G(SCH_1):PAGE151_I34@PURE_QUANTA.SN74LVC1G17DCKR(CHIPS)':
 C_PATH='@t6g_mb_lib.t6g(sch_1):page151_i34@pure_quanta.sn74lvc1g17dckr(chips)';

PART_NAME
 R3611 'Q_RES_0402LF-0,5%,1/16W,CHIP,CS00002JB38':;

SECTION_NUMBER 1
 '@T6G_MB_LIB.T6G(SCH_1):PAGE151_I129@PURE_QUANTA.Q_RES(CHIPS)':
 C_PATH='@t6g_mb_lib.t6g(sch_1):page151_i129@pure_quanta.q_res(chips)';

PART_NAME
 R2778 'Q_RES_0402LF-10K,1%,1/16W,CHIP,TMP_QCS31002FB26':;

SECTION_NUMBER 1
 '@T6G_MB_LIB.T6G(SCH_1):PAGE151_I124@PURE_QUANTA.Q_RES(CHIPS)':
 C_PATH='@t6g_mb_lib.t6g(sch_1):page151_i124@pure_quanta.q_res(chips)';

PART_NAME
 R2776 'Q_RES_0402LF-10K,1%,1/16W,CHIP,TMP_QCS31002FB26':;

SECTION_NUMBER 1
 '@T6G_MB_LIB.T6G(SCH_1):PAGE151_I121@PURE_QUANTA.Q_RES(CHIPS)':
 C_PATH='@t6g_mb_lib.t6g(sch_1):page151_i121@pure_quanta.q_res(chips)';

PART_NAME
 R1916 'Q_RES_0402LF-10K,1%,1/16W,CHIP,TMP_QCS31002FB26':;

SECTION_NUMBER 1
 '@T6G_MB_LIB.T6G(SCH_1):PAGE151_I125@PURE_QUANTA.Q_RES(CHIPS)':
 C_PATH='@t6g_mb_lib.t6g(sch_1):page151_i125@pure_quanta.q_res(chips)';

PART_NAME
 R1914 'Q_RES_0402LF-10K,1%,1/16W,CHIP,TMP_QCS31002FB26':;

SECTION_NUMBER 1
 '@T6G_MB_LIB.T6G(SCH_1):PAGE151_I123@PURE_QUANTA.Q_RES(CHIPS)':
 C_PATH='@t6g_mb_lib.t6g(sch_1):page151_i123@pure_quanta.q_res(chips)';

PART_NAME
 R1252 'Q_RES_0402LF-10K,5%,1/16W,CHIP,TMP_QCS31002JB28':;

SECTION_NUMBER 1
 '@T6G_MB_LIB.T6G(SCH_1):PAGE151_I100@PURE_QUANTA.Q_RES(CHIPS)':
 C_PATH='@t6g_mb_lib.t6g(sch_1):page151_i100@pure_quanta.q_res(chips)';

PART_NAME
 R1251 'Q_RES_0402LF-100,5%,1/16W,CHIP,TMP_QCS11002JB32':;

SECTION_NUMBER 1
 '@T6G_MB_LIB.T6G(SCH_1):PAGE151_I97@PURE_QUANTA.Q_RES(CHIPS)':
 C_PATH='@t6g_mb_lib.t6g(sch_1):page151_i97@pure_quanta.q_res(chips)';

PART_NAME
 R1250 'Q_RES_0402LF-10K,5%,1/16W,CHIP,TMP_QCS31002JB28':;

SECTION_NUMBER 1
 '@T6G_MB_LIB.T6G(SCH_1):PAGE151_I95@PURE_QUANTA.Q_RES(CHIPS)':
 C_PATH='@t6g_mb_lib.t6g(sch_1):page151_i95@pure_quanta.q_res(chips)';

PART_NAME
 R1248 'Q_RES_0402LF-0,5%,1/16W,CHIP,CS00002JB38':;

SECTION_NUMBER 1
 '@T6G_MB_LIB.T6G(SCH_1):PAGE151_I68@PURE_QUANTA.Q_RES(CHIPS)':
 C_PATH='@t6g_mb_lib.t6g(sch_1):page151_i68@pure_quanta.q_res(chips)';

PART_NAME
 R1245 'Q_RES_0402LF-0,5%,1/16W,CHIP,CS00002JB38':;

SECTION_NUMBER 1
 '@T6G_MB_LIB.T6G(SCH_1):PAGE151_I69@PURE_QUANTA.Q_RES(CHIPS)':
 C_PATH='@t6g_mb_lib.t6g(sch_1):page151_i69@pure_quanta.q_res(chips)';

PART_NAME
 R1240 'Q_RES_0402LF-10K,5%,1/16W,CHIP,TMP_QCS31002JB28':;

SECTION_NUMBER 1
 '@T6G_MB_LIB.T6G(SCH_1):PAGE151_I72@PURE_QUANTA.Q_RES(CHIPS)':
 C_PATH='@t6g_mb_lib.t6g(sch_1):page151_i72@pure_quanta.q_res(chips)';

PART_NAME
 R431 'Q_RES_0402LF-0,5%,1/16W,CHIP,CS00002JB38':;

SECTION_NUMBER 1
 '@T6G_MB_LIB.T6G(SCH_1):PAGE151_I102@PURE_QUANTA.Q_RES(CHIPS)':
 C_PATH='@t6g_mb_lib.t6g(sch_1):page151_i102@pure_quanta.q_res(chips)';

PART_NAME
 R419 'Q_RES_0402LF-0,5%,1/16W,CHIP,CS00002JB38':;

SECTION_NUMBER 1
 '@T6G_MB_LIB.T6G(SCH_1):PAGE151_I70@PURE_QUANTA.Q_RES(CHIPS)':
 C_PATH='@t6g_mb_lib.t6g(sch_1):page151_i70@pure_quanta.q_res(chips)';

PART_NAME
 R416 'Q_RES_0402LF-0,5%,1/16W,CHIP,CS00002JB38':;

SECTION_NUMBER 1
 '@T6G_MB_LIB.T6G(SCH_1):PAGE151_I74@PURE_QUANTA.Q_RES(CHIPS)':
 C_PATH='@t6g_mb_lib.t6g(sch_1):page151_i74@pure_quanta.q_res(chips)';

PART_NAME
 R415 'Q_RES_0402LF-0,5%,1/16W,CHIP,CS00002JB38':;

SECTION_NUMBER 1
 '@T6G_MB_LIB.T6G(SCH_1):PAGE151_I75@PURE_QUANTA.Q_RES(CHIPS)':
 C_PATH='@t6g_mb_lib.t6g(sch_1):page151_i75@pure_quanta.q_res(chips)';

PART_NAME
 R414 'Q_RES_0402LF-0,5%,1/16W,CHIP,CS00002JB38':;

SECTION_NUMBER 1
 '@T6G_MB_LIB.T6G(SCH_1):PAGE151_I78@PURE_QUANTA.Q_RES(CHIPS)':
 C_PATH='@t6g_mb_lib.t6g(sch_1):page151_i78@pure_quanta.q_res(chips)';

PART_NAME
 R413 'Q_RES_0402LF-0,5%,1/16W,CHIP,CS00002JB38':;

SECTION_NUMBER 1
 '@T6G_MB_LIB.T6G(SCH_1):PAGE151_I79@PURE_QUANTA.Q_RES(CHIPS)':
 C_PATH='@t6g_mb_lib.t6g(sch_1):page151_i79@pure_quanta.q_res(chips)';

PART_NAME
 R412 'Q_RES_0402LF-10K,5%,1/16W,CHIP,TMP_QCS31002JB28':;

SECTION_NUMBER 1
 '@T6G_MB_LIB.T6G(SCH_1):PAGE151_I90@PURE_QUANTA.Q_RES(CHIPS)':
 C_PATH='@t6g_mb_lib.t6g(sch_1):page151_i90@pure_quanta.q_res(chips)';

PART_NAME
 R411 'Q_RES_0402LF-4.7K,5%,1/16W,CHIP,TMP_QCS24702JB38':;

SECTION_NUMBER 1
 '@T6G_MB_LIB.T6G(SCH_1):PAGE151_I76@PURE_QUANTA.Q_RES(CHIPS)':
 C_PATH='@t6g_mb_lib.t6g(sch_1):page151_i76@pure_quanta.q_res(chips)';

PART_NAME
 R410 'Q_RES_0402LF-4.53K,1%,1/16W,CHIP,TMP_QCS24532FB08':;

SECTION_NUMBER 1
 '@T6G_MB_LIB.T6G(SCH_1):PAGE151_I53@PURE_QUANTA.Q_RES(CHIPS)':
 C_PATH='@t6g_mb_lib.t6g(sch_1):page151_i53@pure_quanta.q_res(chips)';

PART_NAME
 R409 'Q_RES_0402LF-25.5K,1%,1/16W,CHIP,CS32552FB11':;

SECTION_NUMBER 1
 '@T6G_MB_LIB.T6G(SCH_1):PAGE151_I54@PURE_QUANTA.Q_RES(CHIPS)':
 C_PATH='@t6g_mb_lib.t6g(sch_1):page151_i54@pure_quanta.q_res(chips)';

PART_NAME
 R408 'Q_RES_0402LF-267K,1%,1/16W,CHIP,CS42672FB16':;

SECTION_NUMBER 1
 '@T6G_MB_LIB.T6G(SCH_1):PAGE151_I16@PURE_QUANTA.Q_RES(CHIPS)':
 C_PATH='@t6g_mb_lib.t6g(sch_1):page151_i16@pure_quanta.q_res(chips)';

PART_NAME
 R407 'Q_RES_0402LF-10K,5%,1/16W,CHIP,TMP_QCS31002JB28':;

SECTION_NUMBER 1
 '@T6G_MB_LIB.T6G(SCH_1):PAGE151_I24@PURE_QUANTA.Q_RES(CHIPS)':
 C_PATH='@t6g_mb_lib.t6g(sch_1):page151_i24@pure_quanta.q_res(chips)';

PART_NAME
 R406 'Q_RES_0402LF-10K,5%,1/16W,EMPTY,TMP_QCS31002JB28':;

SECTION_NUMBER 1
 '@T6G_MB_LIB.T6G(SCH_1):PAGE151_I23@PURE_QUANTA.Q_RES(CHIPS)':
 C_PATH='@t6g_mb_lib.t6g(sch_1):page151_i23@pure_quanta.q_res(chips)';

PART_NAME
 R404 'Q_RES_0402LF-10K,5%,1/16W,CHIP,TMP_QCS31002JB28':;

SECTION_NUMBER 1
 '@T6G_MB_LIB.T6G(SCH_1):PAGE151_I26@PURE_QUANTA.Q_RES(CHIPS)':
 C_PATH='@t6g_mb_lib.t6g(sch_1):page151_i26@pure_quanta.q_res(chips)';

PART_NAME
 R402 'Q_RES_0402LF-10K,5%,1/16W,CHIP,TMP_QCS31002JB28':;

SECTION_NUMBER 1
 '@T6G_MB_LIB.T6G(SCH_1):PAGE151_I45@PURE_QUANTA.Q_RES(CHIPS)':
 C_PATH='@t6g_mb_lib.t6g(sch_1):page151_i45@pure_quanta.q_res(chips)';

PART_NAME
 Q83 'MOSFET_NCH_DUAL-2N7002KDW,SMLF,IC,BAM70020047':;

SECTION_NUMBER 1
 '@T6G_MB_LIB.T6G(SCH_1):PAGE151_I89@PURE_QUANTA.MOSFET_NCH_DUAL(CHIPS)':
 C_PATH='@t6g_mb_lib.t6g(sch_1):page151_i89@pure_quanta.mosfet_nch_dual(chips)';

SECTION_NUMBER 2
 '@T6G_MB_LIB.T6G(SCH_1):PAGE151_I93@PURE_QUANTA.MOSFET_NCH_DUAL(CHIPS)':
 C_PATH='@t6g_mb_lib.t6g(sch_1):page151_i93@pure_quanta.mosfet_nch_dual(chips)';

PART_NAME
 Q82 'MOSFET_NCH_DUAL-2N7002KDW,SMLF,IC,BAM70020047':;

SECTION_NUMBER 1
 '@T6G_MB_LIB.T6G(SCH_1):PAGE151_I41@PURE_QUANTA.MOSFET_NCH_DUAL(CHIPS)':
 C_PATH='@t6g_mb_lib.t6g(sch_1):page151_i41@pure_quanta.mosfet_nch_dual(chips)';

SECTION_NUMBER 2
 '@T6G_MB_LIB.T6G(SCH_1):PAGE151_I40@PURE_QUANTA.MOSFET_NCH_DUAL(CHIPS)':
 C_PATH='@t6g_mb_lib.t6g(sch_1):page151_i40@pure_quanta.mosfet_nch_dual(chips)';

PART_NAME
 Q67 'MOSFET_NCH_DUAL-2N7002KDW,SMLF,IC,BAM70020047':;

SECTION_NUMBER 1
 '@T6G_MB_LIB.T6G(SCH_1):PAGE151_I43@PURE_QUANTA.MOSFET_NCH_DUAL(CHIPS)':
 C_PATH='@t6g_mb_lib.t6g(sch_1):page151_i43@pure_quanta.mosfet_nch_dual(chips)';

SECTION_NUMBER 2
 '@T6G_MB_LIB.T6G(SCH_1):PAGE151_I44@PURE_QUANTA.MOSFET_NCH_DUAL(CHIPS)':
 C_PATH='@t6g_mb_lib.t6g(sch_1):page151_i44@pure_quanta.mosfet_nch_dual(chips)';

PART_NAME
 D42 'Q_DIODE_SMLF-SDMK0340L-7-F,IC,BC000340033':;

SECTION_NUMBER 1
 '@T6G_MB_LIB.T6G(SCH_1):PAGE151_I31@PURE_QUANTA.Q_DIODE(CHIPS)':
 C_PATH='@t6g_mb_lib.t6g(sch_1):page151_i31@pure_quanta.q_diode(chips)';

PART_NAME
 D40 'Q_DIODE_SMLF-SDMK0340L-7-F,IC,BC000340033':;

SECTION_NUMBER 1
 '@T6G_MB_LIB.T6G(SCH_1):PAGE151_I17@PURE_QUANTA.Q_DIODE(CHIPS)':
 C_PATH='@t6g_mb_lib.t6g(sch_1):page151_i17@pure_quanta.q_diode(chips)';

PART_NAME
 D39 'Q_DIODE_SMLF-SDMK0340L-7-F,IC,BC000340033':;

SECTION_NUMBER 1
 '@T6G_MB_LIB.T6G(SCH_1):PAGE151_I18@PURE_QUANTA.Q_DIODE(CHIPS)':
 C_PATH='@t6g_mb_lib.t6g(sch_1):page151_i18@pure_quanta.q_diode(chips)';

PART_NAME
 D38 'Q_DIODE_SMLF-SDMK0340L-7-F,IC,BC000340033':;

SECTION_NUMBER 1
 '@T6G_MB_LIB.T6G(SCH_1):PAGE151_I19@PURE_QUANTA.Q_DIODE(CHIPS)':
 C_PATH='@t6g_mb_lib.t6g(sch_1):page151_i19@pure_quanta.q_diode(chips)';

PART_NAME
 D37 'Q_DIODE_SMLF-SDMK0340L-7-F,IC,BC000340033':;

SECTION_NUMBER 1
 '@T6G_MB_LIB.T6G(SCH_1):PAGE151_I20@PURE_QUANTA.Q_DIODE(CHIPS)':
 C_PATH='@t6g_mb_lib.t6g(sch_1):page151_i20@pure_quanta.q_diode(chips)';

PART_NAME
 C2891 'Q_CAP_0402-1000PF,50V,5%,EMPTY,TMP_QCH21006JB10':;

SECTION_NUMBER 1
 '@T6G_MB_LIB.T6G(SCH_1):PAGE151_I130@PURE_QUANTA.Q_CAP(CHIPS)':
 C_PATH='@t6g_mb_lib.t6g(sch_1):page151_i130@pure_quanta.q_cap(chips)';

PART_NAME
 C2517 'Q_CAP_0402-0.1UF,25V,10%,X7R,CH4104K1B00':;

SECTION_NUMBER 1
 '@T6G_MB_LIB.T6G(SCH_1):PAGE151_I67@PURE_QUANTA.Q_CAP(CHIPS)':
 C_PATH='@t6g_mb_lib.t6g(sch_1):page151_i67@pure_quanta.q_cap(chips)';

PART_NAME
 C2516 'Q_CAP_0402-2200PF,50V,10%,X7R,TMP_QCH22206KB16':;

SECTION_NUMBER 1
 '@T6G_MB_LIB.T6G(SCH_1):PAGE151_I60@PURE_QUANTA.Q_CAP(CHIPS)':
 C_PATH='@t6g_mb_lib.t6g(sch_1):page151_i60@pure_quanta.q_cap(chips)';

PART_NAME
 C2515 'Q_CAP_0402-0.1UF,25V,10%,X7R,CH4104K1B00':;

SECTION_NUMBER 1
 '@T6G_MB_LIB.T6G(SCH_1):PAGE151_I63@PURE_QUANTA.Q_CAP(CHIPS)':
 C_PATH='@t6g_mb_lib.t6g(sch_1):page151_i63@pure_quanta.q_cap(chips)';

PART_NAME
 C2514 'Q_CAP_0402-2200PF,50V,10%,X7R,TMP_QCH22206KB16':;

SECTION_NUMBER 1
 '@T6G_MB_LIB.T6G(SCH_1):PAGE151_I58@PURE_QUANTA.Q_CAP(CHIPS)':
 C_PATH='@t6g_mb_lib.t6g(sch_1):page151_i58@pure_quanta.q_cap(chips)';

PART_NAME
 C2513 'Q_CAP_0402-1000PF,50V,5%,X7R,TMP_QCH21006JB10':;

SECTION_NUMBER 1
 '@T6G_MB_LIB.T6G(SCH_1):PAGE151_I61@PURE_QUANTA.Q_CAP(CHIPS)':
 C_PATH='@t6g_mb_lib.t6g(sch_1):page151_i61@pure_quanta.q_cap(chips)';

PART_NAME
 C2512 'Q_CAP_0402-0.1UF,25V,10%,X7R,CH4104K1B00':;

SECTION_NUMBER 1
 '@T6G_MB_LIB.T6G(SCH_1):PAGE151_I38@PURE_QUANTA.Q_CAP(CHIPS)':
 C_PATH='@t6g_mb_lib.t6g(sch_1):page151_i38@pure_quanta.q_cap(chips)';

PART_NAME
 C2511 'Q_CAP_C0603-4.7UF,25V,10%,X6S,CH5474KE906':;

SECTION_NUMBER 1
 '@T6G_MB_LIB.T6G(SCH_1):PAGE151_I30@PURE_QUANTA.Q_CAP(CHIPS)':
 C_PATH='@t6g_mb_lib.t6g(sch_1):page151_i30@pure_quanta.q_cap(chips)';

PART_NAME
 R392 'Q_RES_0603LF-1,1%,1/10W,CHIP,CS-1003F920':
;

SECTION_NUMBER 1
 '@T6G_MB_LIB.T6G(SCH_1):PAGE213_I122@PURE_QUANTA.Q_RES(CHIPS)':
 C_PATH='@t6g_mb_lib.t6g(sch_1):page213_i122@pure_quanta.q_res(chips)';

PART_NAME
 R391 'Q_RES_0603LF-1,1%,1/10W,CHIP,CS-1003F920':
;

SECTION_NUMBER 1
 '@T6G_MB_LIB.T6G(SCH_1):PAGE213_I97@PURE_QUANTA.Q_RES(CHIPS)':
 C_PATH='@t6g_mb_lib.t6g(sch_1):page213_i97@pure_quanta.q_res(chips)';

PART_NAME
 R390 'Q_RES_0603LF-1,1%,1/10W,CHIP,CS-1003F920':
;

SECTION_NUMBER 1
 '@T6G_MB_LIB.T6G(SCH_1):PAGE213_I67@PURE_QUANTA.Q_RES(CHIPS)':
 C_PATH='@t6g_mb_lib.t6g(sch_1):page213_i67@pure_quanta.q_res(chips)';

PART_NAME
 L100 'Q_INDUCTOR_SMLF-MMZ2012S601AT/500MA,IND,CX12S601003':;

SECTION_NUMBER 1
 '@T6G_MB_LIB.T6G(SCH_1):PAGE213_I130@PURE_QUANTA.Q_INDUCTOR(CHIPS)':
 C_PATH='@t6g_mb_lib.t6g(sch_1):page213_i130@pure_quanta.q_inductor(chips)';

PART_NAME
 L99 'Q_INDUCTOR_SMLF-MMZ2012S601AT/500MA,IND,CX12S601003':;

SECTION_NUMBER 1
 '@T6G_MB_LIB.T6G(SCH_1):PAGE213_I129@PURE_QUANTA.Q_INDUCTOR(CHIPS)':
 C_PATH='@t6g_mb_lib.t6g(sch_1):page213_i129@pure_quanta.q_inductor(chips)';

PART_NAME
 L98 'Q_INDUCTOR_SMLF-MMZ2012S601AT/500MA,IND,CX12S601003':;

SECTION_NUMBER 1
 '@T6G_MB_LIB.T6G(SCH_1):PAGE213_I128@PURE_QUANTA.Q_INDUCTOR(CHIPS)':
 C_PATH='@t6g_mb_lib.t6g(sch_1):page213_i128@pure_quanta.q_inductor(chips)';

PART_NAME
 C2481 'Q_CAP_0402-0.1UF,25V,10%,X7R,CH4104K1B00':
;

SECTION_NUMBER 1
 '@T6G_MB_LIB.T6G(SCH_1):PAGE213_I120@PURE_QUANTA.Q_CAP(CHIPS)':
 C_PATH='@t6g_mb_lib.t6g(sch_1):page213_i120@pure_quanta.q_cap(chips)';

PART_NAME
 C2480 'Q_CAP_0402-0.1UF,25V,10%,X7R,CH4104K1B00':
;

SECTION_NUMBER 1
 '@T6G_MB_LIB.T6G(SCH_1):PAGE213_I94@PURE_QUANTA.Q_CAP(CHIPS)':
 C_PATH='@t6g_mb_lib.t6g(sch_1):page213_i94@pure_quanta.q_cap(chips)';

PART_NAME
 C2479 'Q_CAP_0402-0.1UF,25V,10%,X7R,CH4104K1B00':
;

SECTION_NUMBER 1
 '@T6G_MB_LIB.T6G(SCH_1):PAGE213_I91@PURE_QUANTA.Q_CAP(CHIPS)':
 C_PATH='@t6g_mb_lib.t6g(sch_1):page213_i91@pure_quanta.q_cap(chips)';

PART_NAME
 C2478 'Q_CAP_C0402-1UF,25V,10%,X6S,CH5104KEB02':
;

SECTION_NUMBER 1
 '@T6G_MB_LIB.T6G(SCH_1):PAGE213_I121@PURE_QUANTA.Q_CAP(CHIPS)':
 C_PATH='@t6g_mb_lib.t6g(sch_1):page213_i121@pure_quanta.q_cap(chips)';

PART_NAME
 C2477 'Q_CAP_C0402-1UF,25V,10%,X6S,CH5104KEB02':
;

SECTION_NUMBER 1
 '@T6G_MB_LIB.T6G(SCH_1):PAGE213_I95@PURE_QUANTA.Q_CAP(CHIPS)':
 C_PATH='@t6g_mb_lib.t6g(sch_1):page213_i95@pure_quanta.q_cap(chips)';

PART_NAME
 C2476 'Q_CAP_C0402-1UF,25V,10%,X6S,CH5104KEB02':
;

SECTION_NUMBER 1
 '@T6G_MB_LIB.T6G(SCH_1):PAGE213_I90@PURE_QUANTA.Q_CAP(CHIPS)':
 C_PATH='@t6g_mb_lib.t6g(sch_1):page213_i90@pure_quanta.q_cap(chips)';

PART_NAME
 C2475 'Q_CAP_C0402-1UF,25V,10%,X6S,CH5104KEB02':
;

SECTION_NUMBER 1
 '@T6G_MB_LIB.T6G(SCH_1):PAGE213_I102@PURE_QUANTA.Q_CAP(CHIPS)':
 C_PATH='@t6g_mb_lib.t6g(sch_1):page213_i102@pure_quanta.q_cap(chips)';

PART_NAME
 C2474 'Q_CAP_C0402-1UF,25V,10%,X6S,CH5104KEB02':
;

SECTION_NUMBER 1
 '@T6G_MB_LIB.T6G(SCH_1):PAGE213_I38@PURE_QUANTA.Q_CAP(CHIPS)':
 C_PATH='@t6g_mb_lib.t6g(sch_1):page213_i38@pure_quanta.q_cap(chips)';

PART_NAME
 C2473 'Q_CAP_C0402-1UF,25V,10%,X6S,CH5104KEB02':
;

SECTION_NUMBER 1
 '@T6G_MB_LIB.T6G(SCH_1):PAGE213_I115@PURE_QUANTA.Q_CAP(CHIPS)':
 C_PATH='@t6g_mb_lib.t6g(sch_1):page213_i115@pure_quanta.q_cap(chips)';

PART_NAME
 C2472 'Q_CAP_C0603-10UF,6.3V,20%,X6S,CH6101ME900':
;

SECTION_NUMBER 1
 '@T6G_MB_LIB.T6G(SCH_1):PAGE213_I116@PURE_QUANTA.Q_CAP(CHIPS)':
 C_PATH='@t6g_mb_lib.t6g(sch_1):page213_i116@pure_quanta.q_cap(chips)';

PART_NAME
 C2468 'Q_CAP_0402-0.1UF,25V,10%,X7R,CH4104K1B00':
;

SECTION_NUMBER 1
 '@T6G_MB_LIB.T6G(SCH_1):PAGE213_I22@PURE_QUANTA.Q_CAP(CHIPS)':
 C_PATH='@t6g_mb_lib.t6g(sch_1):page213_i22@pure_quanta.q_cap(chips)';

PART_NAME
 C2467 'Q_CAP_0402-0.1UF,25V,10%,X7R,CH4104K1B00':
;

SECTION_NUMBER 1
 '@T6G_MB_LIB.T6G(SCH_1):PAGE213_I100@PURE_QUANTA.Q_CAP(CHIPS)':
 C_PATH='@t6g_mb_lib.t6g(sch_1):page213_i100@pure_quanta.q_cap(chips)';

PART_NAME
 C2466 'Q_CAP_0402-0.1UF,25V,10%,X7R,CH4104K1B00':
;

SECTION_NUMBER 1
 '@T6G_MB_LIB.T6G(SCH_1):PAGE213_I23@PURE_QUANTA.Q_CAP(CHIPS)':
 C_PATH='@t6g_mb_lib.t6g(sch_1):page213_i23@pure_quanta.q_cap(chips)';

PART_NAME
 C2465 'Q_CAP_0402-0.1UF,25V,10%,X7R,CH4104K1B00':
;

SECTION_NUMBER 1
 '@T6G_MB_LIB.T6G(SCH_1):PAGE213_I124@PURE_QUANTA.Q_CAP(CHIPS)':
 C_PATH='@t6g_mb_lib.t6g(sch_1):page213_i124@pure_quanta.q_cap(chips)';

PART_NAME
 C2464 'Q_CAP_0402-0.1UF,25V,10%,X7R,CH4104K1B00':
;

SECTION_NUMBER 1
 '@T6G_MB_LIB.T6G(SCH_1):PAGE213_I127@PURE_QUANTA.Q_CAP(CHIPS)':
 C_PATH='@t6g_mb_lib.t6g(sch_1):page213_i127@pure_quanta.q_cap(chips)';

PART_NAME
 C2463 'Q_CAP_0402-0.1UF,25V,10%,X7R,CH4104K1B00':
;

SECTION_NUMBER 1
 '@T6G_MB_LIB.T6G(SCH_1):PAGE213_I112@PURE_QUANTA.Q_CAP(CHIPS)':
 C_PATH='@t6g_mb_lib.t6g(sch_1):page213_i112@pure_quanta.q_cap(chips)';

PART_NAME
 C2462 'Q_CAP_0402-0.1UF,25V,10%,X7R,CH4104K1B00':
;

SECTION_NUMBER 1
 '@T6G_MB_LIB.T6G(SCH_1):PAGE213_I113@PURE_QUANTA.Q_CAP(CHIPS)':
 C_PATH='@t6g_mb_lib.t6g(sch_1):page213_i113@pure_quanta.q_cap(chips)';

PART_NAME
 C2461 'Q_CAP_C0603-10UF,6.3V,20%,X6S,CH6101ME900':
;

SECTION_NUMBER 1
 '@T6G_MB_LIB.T6G(SCH_1):PAGE213_I103@PURE_QUANTA.Q_CAP(CHIPS)':
 C_PATH='@t6g_mb_lib.t6g(sch_1):page213_i103@pure_quanta.q_cap(chips)';

PART_NAME
 C2460 'Q_CAP_C0603-10UF,6.3V,20%,X6S,CH6101ME900':
;

SECTION_NUMBER 1
 '@T6G_MB_LIB.T6G(SCH_1):PAGE213_I41@PURE_QUANTA.Q_CAP(CHIPS)':
 C_PATH='@t6g_mb_lib.t6g(sch_1):page213_i41@pure_quanta.q_cap(chips)';

PART_NAME
 U6 '74LVC07APW_SMTLF-74LVC07APW,74LVC07APW,IC,ALLVC007K36':;

SECTION_NUMBER 1
 '@T6G_MB_LIB.T6G(SCH_1):PAGE96_I18@PURE_QUANTA.74LVC07APW(CHIPS)':
 C_PATH='@t6g_mb_lib.t6g(sch_1):page96_i18@pure_quanta.\74lvc07apw\(chips)';

SECTION_NUMBER 2
 '@T6G_MB_LIB.T6G(SCH_1):PAGE96_I20@PURE_QUANTA.74LVC07APW(CHIPS)':
 C_PATH='@t6g_mb_lib.t6g(sch_1):page96_i20@pure_quanta.\74lvc07apw\(chips)';

SECTION_NUMBER 3
 '@T6G_MB_LIB.T6G(SCH_1):PAGE96_I25@PURE_QUANTA.74LVC07APW(CHIPS)':
 C_PATH='@t6g_mb_lib.t6g(sch_1):page96_i25@pure_quanta.\74lvc07apw\(chips)';

SECTION_NUMBER 4
 '@T6G_MB_LIB.T6G(SCH_1):PAGE96_I26@PURE_QUANTA.74LVC07APW(CHIPS)':
 C_PATH='@t6g_mb_lib.t6g(sch_1):page96_i26@pure_quanta.\74lvc07apw\(chips)';

SECTION_NUMBER 5
 '@T6G_MB_LIB.T6G(SCH_1):PAGE96_I47@PURE_QUANTA.74LVC07APW(CHIPS)':
 C_PATH='@t6g_mb_lib.t6g(sch_1):page96_i47@pure_quanta.\74lvc07apw\(chips)';

SECTION_NUMBER 6
 '@T6G_MB_LIB.T6G(SCH_1):PAGE96_I48@PURE_QUANTA.74LVC07APW(CHIPS)':
 C_PATH='@t6g_mb_lib.t6g(sch_1):page96_i48@pure_quanta.\74lvc07apw\(chips)';

PART_NAME
 R2452 'Q_RES_0402LF-100,1%,1/16W,CHIP,TMP_QCS11002FB22':;

SECTION_NUMBER 1
 '@T6G_MB_LIB.T6G(SCH_1):PAGE96_I13@PURE_QUANTA.Q_RES(CHIPS)':
 C_PATH='@t6g_mb_lib.t6g(sch_1):page96_i13@pure_quanta.q_res(chips)';

PART_NAME
 R2444 'Q_RES_0402LF-0,5%,1/16W,EMPTY,CS00002JB38':;

SECTION_NUMBER 1
 '@T6G_MB_LIB.T6G(SCH_1):PAGE96_I51@PURE_QUANTA.Q_RES(CHIPS)':
 C_PATH='@t6g_mb_lib.t6g(sch_1):page96_i51@pure_quanta.q_res(chips)';

PART_NAME
 R158 'Q_RES_0402LF-33,5%,1/16W,CHIP,CS03302JB29':;

SECTION_NUMBER 1
 '@T6G_MB_LIB.T6G(SCH_1):PAGE96_I44@PURE_QUANTA.Q_RES(CHIPS)':
 C_PATH='@t6g_mb_lib.t6g(sch_1):page96_i44@pure_quanta.q_res(chips)';

PART_NAME
 R157 'Q_RES_0402LF-100,1%,1/16W,EMPTY,TMP_QCS11002FB22':;

SECTION_NUMBER 1
 '@T6G_MB_LIB.T6G(SCH_1):PAGE96_I58@PURE_QUANTA.Q_RES(CHIPS)':
 C_PATH='@t6g_mb_lib.t6g(sch_1):page96_i58@pure_quanta.q_res(chips)';

PART_NAME
 R156 'Q_RES_0402LF-33,5%,1/16W,CHIP,CS03302JB29':;

SECTION_NUMBER 1
 '@T6G_MB_LIB.T6G(SCH_1):PAGE96_I42@PURE_QUANTA.Q_RES(CHIPS)':
 C_PATH='@t6g_mb_lib.t6g(sch_1):page96_i42@pure_quanta.q_res(chips)';

PART_NAME
 R155 'Q_RES_0402LF-100,1%,1/16W,EMPTY,TMP_QCS11002FB22':;

SECTION_NUMBER 1
 '@T6G_MB_LIB.T6G(SCH_1):PAGE96_I56@PURE_QUANTA.Q_RES(CHIPS)':
 C_PATH='@t6g_mb_lib.t6g(sch_1):page96_i56@pure_quanta.q_res(chips)';

PART_NAME
 R154 'Q_RES_0402LF-100,1%,1/16W,EMPTY,TMP_QCS11002FB22':;

SECTION_NUMBER 1
 '@T6G_MB_LIB.T6G(SCH_1):PAGE96_I24@PURE_QUANTA.Q_RES(CHIPS)':
 C_PATH='@t6g_mb_lib.t6g(sch_1):page96_i24@pure_quanta.q_res(chips)';

PART_NAME
 R153 'Q_RES_0402LF-100,1%,1/16W,CHIP,TMP_QCS11002FB22':;

SECTION_NUMBER 1
 '@T6G_MB_LIB.T6G(SCH_1):PAGE96_I23@PURE_QUANTA.Q_RES(CHIPS)':
 C_PATH='@t6g_mb_lib.t6g(sch_1):page96_i23@pure_quanta.q_res(chips)';

PART_NAME
 R152 'Q_RES_0402LF-100,1%,1/16W,EMPTY,TMP_QCS11002FB22':;

SECTION_NUMBER 1
 '@T6G_MB_LIB.T6G(SCH_1):PAGE96_I22@PURE_QUANTA.Q_RES(CHIPS)':
 C_PATH='@t6g_mb_lib.t6g(sch_1):page96_i22@pure_quanta.q_res(chips)';

PART_NAME
 R151 'Q_RES_0402LF-100,1%,1/16W,CHIP,TMP_QCS11002FB22':;

SECTION_NUMBER 1
 '@T6G_MB_LIB.T6G(SCH_1):PAGE96_I21@PURE_QUANTA.Q_RES(CHIPS)':
 C_PATH='@t6g_mb_lib.t6g(sch_1):page96_i21@pure_quanta.q_res(chips)';

PART_NAME
 R150 'Q_RES_0402LF-100,1%,1/16W,EMPTY,TMP_QCS11002FB22':;

SECTION_NUMBER 1
 '@T6G_MB_LIB.T6G(SCH_1):PAGE96_I14@PURE_QUANTA.Q_RES(CHIPS)':
 C_PATH='@t6g_mb_lib.t6g(sch_1):page96_i14@pure_quanta.q_res(chips)';

PART_NAME
 R136 'Q_RES_0402LF-100,1%,1/16W,EMPTY,TMP_QCS11002FB22':;

SECTION_NUMBER 1
 '@T6G_MB_LIB.T6G(SCH_1):PAGE96_I12@PURE_QUANTA.Q_RES(CHIPS)':
 C_PATH='@t6g_mb_lib.t6g(sch_1):page96_i12@pure_quanta.q_res(chips)';

PART_NAME
 R135 'Q_RES_0402LF-100,1%,1/16W,CHIP,TMP_QCS11002FB22':;

SECTION_NUMBER 1
 '@T6G_MB_LIB.T6G(SCH_1):PAGE96_I11@PURE_QUANTA.Q_RES(CHIPS)':
 C_PATH='@t6g_mb_lib.t6g(sch_1):page96_i11@pure_quanta.q_res(chips)';

PART_NAME
 R134 'Q_RES_0402LF-0,5%,1/16W,EMPTY,CS00002JB38':;

SECTION_NUMBER 1
 '@T6G_MB_LIB.T6G(SCH_1):PAGE96_I46@PURE_QUANTA.Q_RES(CHIPS)':
 C_PATH='@t6g_mb_lib.t6g(sch_1):page96_i46@pure_quanta.q_res(chips)';

PART_NAME
 R133 'Q_RES_0402LF-0,5%,1/16W,EMPTY,CS00002JB38':;

SECTION_NUMBER 1
 '@T6G_MB_LIB.T6G(SCH_1):PAGE96_I45@PURE_QUANTA.Q_RES(CHIPS)':
 C_PATH='@t6g_mb_lib.t6g(sch_1):page96_i45@pure_quanta.q_res(chips)';

PART_NAME
 R132 'Q_RES_0402LF-0,5%,1/16W,CHIP,CS00002JB38':;

SECTION_NUMBER 1
 '@T6G_MB_LIB.T6G(SCH_1):PAGE96_I52@PURE_QUANTA.Q_RES(CHIPS)':
 C_PATH='@t6g_mb_lib.t6g(sch_1):page96_i52@pure_quanta.q_res(chips)';

PART_NAME
 R130 'Q_RES_0402LF-0,5%,1/16W,CHIP,CS00002JB38':;

SECTION_NUMBER 1
 '@T6G_MB_LIB.T6G(SCH_1):PAGE96_I50@PURE_QUANTA.Q_RES(CHIPS)':
 C_PATH='@t6g_mb_lib.t6g(sch_1):page96_i50@pure_quanta.q_res(chips)';

PART_NAME
 R129 'Q_RES_0402LF-0,5%,1/16W,EMPTY,CS00002JB38':;

SECTION_NUMBER 1
 '@T6G_MB_LIB.T6G(SCH_1):PAGE96_I49@PURE_QUANTA.Q_RES(CHIPS)':
 C_PATH='@t6g_mb_lib.t6g(sch_1):page96_i49@pure_quanta.q_res(chips)';

PART_NAME
 R128 'Q_RES_0402LF-0,5%,1/16W,CHIP,CS00002JB38':;

SECTION_NUMBER 1
 '@T6G_MB_LIB.T6G(SCH_1):PAGE96_I34@PURE_QUANTA.Q_RES(CHIPS)':
 C_PATH='@t6g_mb_lib.t6g(sch_1):page96_i34@pure_quanta.q_res(chips)';

PART_NAME
 R127 'Q_RES_0402LF-33,5%,1/16W,EMPTY,CS03302JB29':;

SECTION_NUMBER 1
 '@T6G_MB_LIB.T6G(SCH_1):PAGE96_I33@PURE_QUANTA.Q_RES(CHIPS)':
 C_PATH='@t6g_mb_lib.t6g(sch_1):page96_i33@pure_quanta.q_res(chips)';

PART_NAME
 R126 'Q_RES_0402LF-0,5%,1/16W,CHIP,CS00002JB38':;

SECTION_NUMBER 1
 '@T6G_MB_LIB.T6G(SCH_1):PAGE96_I32@PURE_QUANTA.Q_RES(CHIPS)':
 C_PATH='@t6g_mb_lib.t6g(sch_1):page96_i32@pure_quanta.q_res(chips)';

PART_NAME
 R125 'Q_RES_0402LF-33,5%,1/16W,EMPTY,CS03302JB29':;

SECTION_NUMBER 1
 '@T6G_MB_LIB.T6G(SCH_1):PAGE96_I31@PURE_QUANTA.Q_RES(CHIPS)':
 C_PATH='@t6g_mb_lib.t6g(sch_1):page96_i31@pure_quanta.q_res(chips)';

PART_NAME
 R124 'Q_RES_0402LF-0,5%,1/16W,CHIP,CS00002JB38':;

SECTION_NUMBER 1
 '@T6G_MB_LIB.T6G(SCH_1):PAGE96_I30@PURE_QUANTA.Q_RES(CHIPS)':
 C_PATH='@t6g_mb_lib.t6g(sch_1):page96_i30@pure_quanta.q_res(chips)';

PART_NAME
 R123 'Q_RES_0402LF-33,5%,1/16W,EMPTY,CS03302JB29':;

SECTION_NUMBER 1
 '@T6G_MB_LIB.T6G(SCH_1):PAGE96_I29@PURE_QUANTA.Q_RES(CHIPS)':
 C_PATH='@t6g_mb_lib.t6g(sch_1):page96_i29@pure_quanta.q_res(chips)';

PART_NAME
 R122 'Q_RES_0402LF-0,5%,1/16W,CHIP,CS00002JB38':;

SECTION_NUMBER 1
 '@T6G_MB_LIB.T6G(SCH_1):PAGE96_I28@PURE_QUANTA.Q_RES(CHIPS)':
 C_PATH='@t6g_mb_lib.t6g(sch_1):page96_i28@pure_quanta.q_res(chips)';

PART_NAME
 R121 'Q_RES_0402LF-33,5%,1/16W,EMPTY,CS03302JB29':;

SECTION_NUMBER 1
 '@T6G_MB_LIB.T6G(SCH_1):PAGE96_I27@PURE_QUANTA.Q_RES(CHIPS)':
 C_PATH='@t6g_mb_lib.t6g(sch_1):page96_i27@pure_quanta.q_res(chips)';

PART_NAME
 C2447 'Q_CAP_0402-0.1UF,25V,10%,X7R,CH4104K1B00':;

SECTION_NUMBER 1
 '@T6G_MB_LIB.T6G(SCH_1):PAGE96_I16@PURE_QUANTA.Q_CAP(CHIPS)':
 C_PATH='@t6g_mb_lib.t6g(sch_1):page96_i16@pure_quanta.q_cap(chips)';

PART_NAME
 U74 'MOSFET_N_SMLF-BSS138K,BSS138K,IC,BAM138K0000':;

SECTION_NUMBER 1
 '@T6G_MB_LIB.T6G(SCH_1):PAGE322_I34@PURE_QUANTA.MOSFET_N(CHIPS)':
 C_PATH='@t6g_mb_lib.t6g(sch_1):page322_i34@pure_quanta.mosfet_n(chips)';

PART_NAME
 R2381 'Q_RES_0402LF-26.1K,1%,1/16W,CHIP,CS32612FB09':;

SECTION_NUMBER 1
 '@T6G_MB_LIB.T6G(SCH_1):PAGE322_I27@PURE_QUANTA.Q_RES(CHIPS)':
 C_PATH='@t6g_mb_lib.t6g(sch_1):page322_i27@pure_quanta.q_res(chips)';

PART_NAME
 R2380 'Q_RES_0402LF-0,5%,1/16W,CHIP,CS00002JB38':;

SECTION_NUMBER 1
 '@T6G_MB_LIB.T6G(SCH_1):PAGE322_I40@PURE_QUANTA.Q_RES(CHIPS)':
 C_PATH='@t6g_mb_lib.t6g(sch_1):page322_i40@pure_quanta.q_res(chips)';

PART_NAME
 R2374 'Q_RES_0402LF-2K,1%,1/16W,CHIP,TMP_QCS22002FB19':;

SECTION_NUMBER 1
 '@T6G_MB_LIB.T6G(SCH_1):PAGE322_I12@PURE_QUANTA.Q_RES(CHIPS)':
 C_PATH='@t6g_mb_lib.t6g(sch_1):page322_i12@pure_quanta.q_res(chips)';

PART_NAME
 R2367 'Q_RES_0402LF-10K,1%,1/16W,EMPTY,TMP_QCS31002FB26':;

SECTION_NUMBER 1
 '@T6G_MB_LIB.T6G(SCH_1):PAGE322_I18@PURE_QUANTA.Q_RES(CHIPS)':
 C_PATH='@t6g_mb_lib.t6g(sch_1):page322_i18@pure_quanta.q_res(chips)';

PART_NAME
 PU80 'MPQ8633AGLEC807Z-MPQ8633AGLE-C807-Z,SMLF,IC,AL008633007':;

SECTION_NUMBER 1
 '@T6G_MB_LIB.T6G(SCH_1):PAGE322_I15@PURE_QUANTA.MPQ8633AGLEC807Z(CHIPS)':
 C_PATH='@t6g_mb_lib.t6g(sch_1):page322_i15@pure_quanta.mpq8633aglec807z(chips)';

PART_NAME
 PR1340 'Q_RES_0402LF-36K,1%,1/16W,CHIP,CS33602FB15':;

SECTION_NUMBER 1
 '@T6G_MB_LIB.T6G(SCH_1):PAGE322_I29@PURE_QUANTA.Q_RES(CHIPS)':
 C_PATH='@t6g_mb_lib.t6g(sch_1):page322_i29@pure_quanta.q_res(chips)';

PART_NAME
 PR1339 'Q_RES_0402LF-9.31K,1%,1/16W,CHIP,CS29312FB13':;

SECTION_NUMBER 1
 '@T6G_MB_LIB.T6G(SCH_1):PAGE322_I14@PURE_QUANTA.Q_RES(CHIPS)':
 C_PATH='@t6g_mb_lib.t6g(sch_1):page322_i14@pure_quanta.q_res(chips)';

PART_NAME
 PR1338 'Q_RES_0402LF-0,5%,1/16W,CHIP,CS00002JB38':;

SECTION_NUMBER 1
 '@T6G_MB_LIB.T6G(SCH_1):PAGE322_I8@PURE_QUANTA.Q_RES(CHIPS)':
 C_PATH='@t6g_mb_lib.t6g(sch_1):page322_i8@pure_quanta.q_res(chips)';

PART_NAME
 PR1314 'Q_RES_0402LF-18.2K,0.1%,1/16W,CHIP,CS31822BB00':;

SECTION_NUMBER 1
 '@T6G_MB_LIB.T6G(SCH_1):PAGE322_I26@PURE_QUANTA.Q_RES(CHIPS)':
 C_PATH='@t6g_mb_lib.t6g(sch_1):page322_i26@pure_quanta.q_res(chips)';

PART_NAME
 PR1313 'Q_RES_0402LF-10K,1%,1/16W,CHIP,TMP_QCS31002FB26':;

SECTION_NUMBER 1
 '@T6G_MB_LIB.T6G(SCH_1):PAGE322_I23@PURE_QUANTA.Q_RES(CHIPS)':
 C_PATH='@t6g_mb_lib.t6g(sch_1):page322_i23@pure_quanta.q_res(chips)';

PART_NAME
 PL119 'Q_INDUCTOR_SMLF-1UH,IND,CV-10B0MZ13':;

SECTION_NUMBER 1
 '@T6G_MB_LIB.T6G(SCH_1):PAGE322_I41@PURE_QUANTA.Q_INDUCTOR(CHIPS)':
 C_PATH='@t6g_mb_lib.t6g(sch_1):page322_i41@pure_quanta.q_inductor(chips)';

PART_NAME
 PC1771 'Q_CAPP_THLF-560UF,6.3V,20%,OSCON,CC75601MD18':;

SECTION_NUMBER 1
 '@T6G_MB_LIB.T6G(SCH_1):PAGE322_I36@PURE_QUANTA.Q_CAPP(CHIPS)':
 C_PATH='@t6g_mb_lib.t6g(sch_1):page322_i36@pure_quanta.q_capp(chips)';

PART_NAME
 PC1270 'Q_CAP_0805-22UF,4V,20%,X6S,TMP_QCH622KMEA01':;

SECTION_NUMBER 1
 '@T6G_MB_LIB.T6G(SCH_1):PAGE322_I35@PURE_QUANTA.Q_CAP(CHIPS)':
 C_PATH='@t6g_mb_lib.t6g(sch_1):page322_i35@pure_quanta.q_cap(chips)';

PART_NAME
 PC1269 'Q_CAP_0805-22UF,4V,20%,X6S,TMP_QCH622KMEA01':;

SECTION_NUMBER 1
 '@T6G_MB_LIB.T6G(SCH_1):PAGE322_I32@PURE_QUANTA.Q_CAP(CHIPS)':
 C_PATH='@t6g_mb_lib.t6g(sch_1):page322_i32@pure_quanta.q_cap(chips)';

PART_NAME
 PC1268 'Q_CAP_0805-22UF,4V,20%,X6S,TMP_QCH622KMEA01':;

SECTION_NUMBER 1
 '@T6G_MB_LIB.T6G(SCH_1):PAGE322_I31@PURE_QUANTA.Q_CAP(CHIPS)':
 C_PATH='@t6g_mb_lib.t6g(sch_1):page322_i31@pure_quanta.q_cap(chips)';

PART_NAME
 PC1267 'Q_CAP_0402-0.1UF,25V,10%,X7R,CH4104K1B00':;

SECTION_NUMBER 1
 '@T6G_MB_LIB.T6G(SCH_1):PAGE322_I30@PURE_QUANTA.Q_CAP(CHIPS)':
 C_PATH='@t6g_mb_lib.t6g(sch_1):page322_i30@pure_quanta.q_cap(chips)';

PART_NAME
 PC1266 'Q_CAP_0402-100PF,50V,5%,NPO,CH11006JB00':;

SECTION_NUMBER 1
 '@T6G_MB_LIB.T6G(SCH_1):PAGE322_I28@PURE_QUANTA.Q_CAP(CHIPS)':
 C_PATH='@t6g_mb_lib.t6g(sch_1):page322_i28@pure_quanta.q_cap(chips)';

PART_NAME
 PC1265 'Q_CAP_0402-0.22UF,16V,10%,X7R,CH4223K1B00':;

SECTION_NUMBER 1
 '@T6G_MB_LIB.T6G(SCH_1):PAGE322_I22@PURE_QUANTA.Q_CAP(CHIPS)':
 C_PATH='@t6g_mb_lib.t6g(sch_1):page322_i22@pure_quanta.q_cap(chips)';

PART_NAME
 PC1264 'Q_CAP_0402-0.1UF,25V,10%,X7R,CH4104K1B00':;

SECTION_NUMBER 1
 '@T6G_MB_LIB.T6G(SCH_1):PAGE322_I17@PURE_QUANTA.Q_CAP(CHIPS)':
 C_PATH='@t6g_mb_lib.t6g(sch_1):page322_i17@pure_quanta.q_cap(chips)';

PART_NAME
 PC1262 'Q_CAP_0402-0.1UF,25V,10%,X7R,CH4104K1B00':;

SECTION_NUMBER 1
 '@T6G_MB_LIB.T6G(SCH_1):PAGE322_I21@PURE_QUANTA.Q_CAP(CHIPS)':
 C_PATH='@t6g_mb_lib.t6g(sch_1):page322_i21@pure_quanta.q_cap(chips)';

PART_NAME
 PC1261 'Q_CAP_C0805-22UF,16V,20%,X6S,CH6223MEA00':;

SECTION_NUMBER 1
 '@T6G_MB_LIB.T6G(SCH_1):PAGE322_I20@PURE_QUANTA.Q_CAP(CHIPS)':
 C_PATH='@t6g_mb_lib.t6g(sch_1):page322_i20@pure_quanta.q_cap(chips)';

PART_NAME
 PC1260 'Q_CAP_C0805-22UF,16V,20%,X6S,CH6223MEA00':;

SECTION_NUMBER 1
 '@T6G_MB_LIB.T6G(SCH_1):PAGE322_I19@PURE_QUANTA.Q_CAP(CHIPS)':
 C_PATH='@t6g_mb_lib.t6g(sch_1):page322_i19@pure_quanta.q_cap(chips)';

PART_NAME
 PC1259 'Q_CAP_C0805-22UF,16V,20%,X6S,CH6223MEA00':;

SECTION_NUMBER 1
 '@T6G_MB_LIB.T6G(SCH_1):PAGE322_I4@PURE_QUANTA.Q_CAP(CHIPS)':
 C_PATH='@t6g_mb_lib.t6g(sch_1):page322_i4@pure_quanta.q_cap(chips)';

PART_NAME
 PC644 'Q_CAP_C0402-1UF,25V,10%,X6S,CH5104KEB02':;

SECTION_NUMBER 1
 '@T6G_MB_LIB.T6G(SCH_1):PAGE322_I7@PURE_QUANTA.Q_CAP(CHIPS)':
 C_PATH='@t6g_mb_lib.t6g(sch_1):page322_i7@pure_quanta.q_cap(chips)';

PART_NAME
 C2446 'Q_CAP_0402-1000PF,50V,5%,X7R,TMP_QCH21006JB10':;

SECTION_NUMBER 1
 '@T6G_MB_LIB.T6G(SCH_1):PAGE322_I39@PURE_QUANTA.Q_CAP(CHIPS)':
 C_PATH='@t6g_mb_lib.t6g(sch_1):page322_i39@pure_quanta.q_cap(chips)';

PART_NAME
 C2445 'Q_CAP_0402-1000PF,50V,5%,EMPTY,TMP_QCH21006JB10':;

SECTION_NUMBER 1
 '@T6G_MB_LIB.T6G(SCH_1):PAGE322_I11@PURE_QUANTA.Q_CAP(CHIPS)':
 C_PATH='@t6g_mb_lib.t6g(sch_1):page322_i11@pure_quanta.q_cap(chips)';

PART_NAME
 R1735 'Q_RES_0402LF-100,1%,1/16W,CHIP,TMP_QCS11002FB22':;

SECTION_NUMBER 1
 '@T6G_MB_LIB.T6G(SCH_1):PAGE301_I25@PURE_QUANTA.Q_RES(CHIPS)':
 C_PATH='@t6g_mb_lib.t6g(sch_1):page301_i25@pure_quanta.q_res(chips)';

PART_NAME
 R1717 'Q_RES_0402LF-49.9     ,1%  ,1/16W,CHIP,CS04992FB31':;

SECTION_NUMBER 1
 '@T6G_MB_LIB.T6G(SCH_1):PAGE301_I26@PURE_QUANTA.Q_RES(CHIPS)':
 C_PATH='@t6g_mb_lib.t6g(sch_1):page301_i26@pure_quanta.q_res(chips)';

PART_NAME
 PU35 'ISL69260IRAZT-ISL69260IRAZ-T,SMLF,IC,AL069260000':;

SECTION_NUMBER 1
 '@T6G_MB_LIB.T6G(SCH_1):PAGE301_I51@PURE_QUANTA.ISL69260IRAZT(CHIPS)':
 C_PATH='@t6g_mb_lib.t6g(sch_1):page301_i51@pure_quanta.isl69260irazt(chips)';

PART_NAME
 PR1390 'Q_RES_0402LF-49.9     ,1%  ,1/16W,CHIP,CS04992FB31':;

SECTION_NUMBER 1
 '@T6G_MB_LIB.T6G(SCH_1):PAGE301_I9@PURE_QUANTA.Q_RES(CHIPS)':
 C_PATH='@t6g_mb_lib.t6g(sch_1):page301_i9@pure_quanta.q_res(chips)',
 CDSVAR_REPCELL_MPS='pure_quanta|Q_res',
 VAR_0_MPS='VALUE|15K|TOLERANCE|1%|WATTAGE|1/16W|PACK_TYPE|0402LF|MATERIAL|CHIP|~
PART_NUMBER|TMP_QCS31502FB24|STANDARD|End of Design|LIFECYCLE|Comp-Approve|PART_~
NUMBER|CS31502FB24|JEDEC_TYPE|R0402|ALT_SYMBOLS|(R0402-0201)|VALUE|15K|TOL|1%|WA~
TTAGE|1/16W |CLASS|DISCRETE|DESCRIPTION|RES CHIP 15K 1/16W +-1% (0402)|COMPONENT~
_TYPE|CHIP0402|LEAD_LENGTH||DFM_EXCLUSION||DAY||VARIANT_DEVICE_TYPE|Q_RES-15K,1%~
,1/16W,0402LF,CHIP';

PART_NAME
 PR1380 'Q_RES_0402LF-49.9     ,1%  ,1/16W,CHIP,CS04992FB31':;

SECTION_NUMBER 1
 '@T6G_MB_LIB.T6G(SCH_1):PAGE301_I10@PURE_QUANTA.Q_RES(CHIPS)':
 C_PATH='@t6g_mb_lib.t6g(sch_1):page301_i10@pure_quanta.q_res(chips)',
 CDSVAR_REPCELL_MPS='pure_quanta|Q_res',
 VAR_0_MPS='VALUE|49.9     |TOLERANCE|1%  |WATTAGE|1/16W|PACK_TYPE|0402LF|MATERI~
AL|EMPTY|PART_NUMBER|CS04992FB31|STANDARD|End of Design|LIFECYCLE|Comp-Approve|P~
ART_NUMBER|CS04992FB31|JEDEC_TYPE|R0402|ALT_SYMBOLS|(R0402-0201)|VALUE|49.9|TOL|~
1%|WATTAGE|1/16W |CLASS|IO|DESCRIPTION|RES CHIP 49.9 1/16W +-1% (0402)|COMPONENT~
_TYPE|CHIP0402|LEAD_LENGTH||DFM_EXCLUSION||DAY|20100716|VARIANT_DEVICE_TYPE|Q_RE~
S-49.9     ,1%  ,1/16W,040';

PART_NAME
 PR1311 'Q_RES_0402LF-0,5%,1/16W,CHIP,CS00002JB38':;

SECTION_NUMBER 1
 '@T6G_MB_LIB.T6G(SCH_1):PAGE301_I58@PURE_QUANTA.Q_RES(CHIPS)':
 C_PATH='@t6g_mb_lib.t6g(sch_1):page301_i58@pure_quanta.q_res(chips)',
 CDSVAR_REPCELL_MPS='pure_quanta|Q_res',
 VAR_0_MPS='VALUE|0|TOLERANCE|5%|WATTAGE|1/16W|PACK_TYPE|0402LF|MATERIAL|EMPTY|P~
ART_NUMBER|CS00002JB38|STANDARD|End of Design|LIFECYCLE|Comp-Approve|PART_NUMBER~
|CS00002JB38|JEDEC_TYPE|R0402|ALT_SYMBOLS|(R0402-0201)|VALUE|0|TOL|5%|WATTAGE|1/~
16W|CLASS|IO|DESCRIPTION|RESISTOR CHIP 0 1/16W +-5%(0402)|COMPONENT_TYPE|CHIP040~
2|LEAD_LENGTH||DFM_EXCLUSION||DAY|20100618|VARIANT_DEVICE_TYPE|Q_RES-0,5%,1/16W,~
0402LF,EMPTY,';

PART_NAME
 PR634 'Q_RES_0402LF-10K,1%,1/16W,EMPTY,CS31002FB08':;

SECTION_NUMBER 1
 '@T6G_MB_LIB.T6G(SCH_1):PAGE301_I57@PURE_QUANTA.Q_RES(CHIPS)':
 C_PATH='@t6g_mb_lib.t6g(sch_1):page301_i57@pure_quanta.q_res(chips)',
 CDSVAR_REPCELL_MPS='pure_quanta|Q_res',
 VAR_0_MPS='VALUE|10K|TOLERANCE|1%|WATTAGE|1/16W|PACK_TYPE|0402LF|MATERIAL|CHIP|~
PART_NUMBER|CS31002FB08|STANDARD|End of Design|LIFECYCLE|Comp-Approve|PART_NUMBE~
R|CS31002FB08|JEDEC_TYPE|R0402|ALT_SYMBOLS|(R0402-0201)|VALUE|10K|TOL|1%|WATTAGE~
|1/16W|CLASS|DISCRETE|DESCRIPTION|RES CHIP 10K 1/16W +-1%(0402)EF|COMPONENT_TYPE~
|CHIPR0402|LEAD_LENGTH||DFM_EXCLUSION||DAY|20180208|VARIANT_DEVICE_TYPE|Q_RES-10~
K,1%,1/16W,0402LF,CHIP';

PART_NAME
 PR592 'Q_RES_0402LF-100,1%,1/16W,CHIP,TMP_QCS11002FB22':;

SECTION_NUMBER 1
 '@T6G_MB_LIB.T6G(SCH_1):PAGE301_I33@PURE_QUANTA.Q_RES(CHIPS)':
 C_PATH='@t6g_mb_lib.t6g(sch_1):page301_i33@pure_quanta.q_res(chips)';

PART_NAME
 PR591 'Q_RES_0402LF-100,1%,1/16W,CHIP,TMP_QCS11002FB22':;

SECTION_NUMBER 1
 '@T6G_MB_LIB.T6G(SCH_1):PAGE301_I78@PURE_QUANTA.Q_RES(CHIPS)':
 C_PATH='@t6g_mb_lib.t6g(sch_1):page301_i78@pure_quanta.q_res(chips)';

PART_NAME
 PR409 'Q_RES_0402LF-0,5%,1/16W,EMPTY,CS00002JB38':;

SECTION_NUMBER 1
 '@T6G_MB_LIB.T6G(SCH_1):PAGE301_I59@PURE_QUANTA.Q_RES(CHIPS)':
 C_PATH='@t6g_mb_lib.t6g(sch_1):page301_i59@pure_quanta.q_res(chips)',
 CDSVAR_REPCELL_MPS='pure_quanta|Q_res',
 VAR_0_MPS='VALUE|0|TOLERANCE|5%|WATTAGE|1/16W|PACK_TYPE|0402LF|MATERIAL|CHIP|PA~
RT_NUMBER|CS00002JB38|STANDARD|End of Design|LIFECYCLE|Comp-Approve|PART_NUMBER|~
CS00002JB38|JEDEC_TYPE|R0402|ALT_SYMBOLS|(R0402-0201)|VALUE|0|TOL|5%|WATTAGE|1/1~
6W|CLASS|DISCRETE|DESCRIPTION|RESISTOR CHIP 0 1/16W +-5%(0402)|COMPONENT_TYPE|CH~
IP0402|LEAD_LENGTH||DFM_EXCLUSION||DAY|20100618|VARIANT_DEVICE_TYPE|Q_RES-0,5%,1~
/16W,0402LF,CHIP,C';

PART_NAME
 PR378 'Q_RES_0402LF-1K,1%,1/16W,CHIP,TMP_QCS21002FB24':;

SECTION_NUMBER 1
 '@T6G_MB_LIB.T6G(SCH_1):PAGE301_I60@PURE_QUANTA.Q_RES(CHIPS)':
 C_PATH='@t6g_mb_lib.t6g(sch_1):page301_i60@pure_quanta.q_res(chips)';

PART_NAME
 PR375 'Q_RES_0402LF-1,1%,1/16W,CHIP,CS-1002FB23':;

SECTION_NUMBER 1
 '@T6G_MB_LIB.T6G(SCH_1):PAGE301_I72@PURE_QUANTA.Q_RES(CHIPS)':
 C_PATH='@t6g_mb_lib.t6g(sch_1):page301_i72@pure_quanta.q_res(chips)';

PART_NAME
 PR373 'Q_RES_0402LF-1K,1%,1/16W,EMPTY,TMP_QCS21002FB24':;

SECTION_NUMBER 1
 '@T6G_MB_LIB.T6G(SCH_1):PAGE301_I46@PURE_QUANTA.Q_RES(CHIPS)':
 C_PATH='@t6g_mb_lib.t6g(sch_1):page301_i46@pure_quanta.q_res(chips)',
 CDSVAR_REPCELL_MPS='pure_quanta|Q_res',
 VAR_0_MPS='VALUE|1K|TOLERANCE|1%|WATTAGE|1/16W|PACK_TYPE|0402LF|MATERIAL|CHIP|P~
ART_NUMBER|TMP_QCS21002FB24|STANDARD|End of Design|LIFECYCLE|Comp-Approve|PART_N~
UMBER|CS21002FB24|JEDEC_TYPE|R0402|ALT_SYMBOLS|(R0402-0201)|VALUE|1K|TOL|1%|WATT~
AGE|1/16W|CLASS|DISCRETE|DESCRIPTION|RES CHIP 1K 1/16W +-1% (0402)|COMPONENT_TYP~
E|CHIP0402|LEAD_LENGTH||DFM_EXCLUSION||DAY||VARIANT_DEVICE_TYPE|Q_RES-1K,1%,1/16~
W,0402LF,CHIP,';

PART_NAME
 PR372 'Q_RES_0402LF-1K,1%,1/16W,CHIP,TMP_QCS21002FB24':;

SECTION_NUMBER 1
 '@T6G_MB_LIB.T6G(SCH_1):PAGE301_I17@PURE_QUANTA.Q_RES(CHIPS)':
 C_PATH='@t6g_mb_lib.t6g(sch_1):page301_i17@pure_quanta.q_res(chips)';

PART_NAME
 PR371 'Q_RES_0402LF-0,5%,1/16W,CHIP,CS00002JB38':;

SECTION_NUMBER 1
 '@T6G_MB_LIB.T6G(SCH_1):PAGE301_I41@PURE_QUANTA.Q_RES(CHIPS)':
 C_PATH='@t6g_mb_lib.t6g(sch_1):page301_i41@pure_quanta.q_res(chips)';

PART_NAME
 PR370 'Q_RES_0402LF-1K,1%,1/16W,CHIP,TMP_QCS21002FB24':;

SECTION_NUMBER 1
 '@T6G_MB_LIB.T6G(SCH_1):PAGE301_I15@PURE_QUANTA.Q_RES(CHIPS)':
 C_PATH='@t6g_mb_lib.t6g(sch_1):page301_i15@pure_quanta.q_res(chips)';

PART_NAME
 PR369 'Q_RES_0402LF-1K,1%,1/16W,EMPTY,TMP_QCS21002FB24':;

SECTION_NUMBER 1
 '@T6G_MB_LIB.T6G(SCH_1):PAGE301_I12@PURE_QUANTA.Q_RES(CHIPS)':
 C_PATH='@t6g_mb_lib.t6g(sch_1):page301_i12@pure_quanta.q_res(chips)',
 CDSVAR_REPCELL_MPS='pure_quanta|Q_res',
 VAR_0_MPS='VALUE|0|TOLERANCE|5%|WATTAGE|1/16W|PACK_TYPE|0402LF|MATERIAL|CHIP|PA~
RT_NUMBER|CS00002JB38|STANDARD|End of Design|LIFECYCLE|Comp-Approve|PART_NUMBER|~
CS00002JB38|JEDEC_TYPE|R0402|ALT_SYMBOLS|(R0402-0201)|VALUE|0|TOL|5%|WATTAGE|1/1~
6W|CLASS|DISCRETE|DESCRIPTION|RESISTOR CHIP 0 1/16W +-5%(0402)|COMPONENT_TYPE|CH~
IP0402|LEAD_LENGTH||DFM_EXCLUSION||DAY|20100618|VARIANT_DEVICE_TYPE|Q_RES-0,5%,1~
/16W,0402LF,CHIP,C';

PART_NAME
 PR368 'Q_RES_0402LF-0,5%,1/16W,CHIP,CS00002JB38':;

SECTION_NUMBER 1
 '@T6G_MB_LIB.T6G(SCH_1):PAGE301_I36@PURE_QUANTA.Q_RES(CHIPS)':
 C_PATH='@t6g_mb_lib.t6g(sch_1):page301_i36@pure_quanta.q_res(chips)';

PART_NAME
 PR367 'Q_RES_0402LF-0,5%,1/16W,CHIP,CS00002JB38':;

SECTION_NUMBER 1
 '@T6G_MB_LIB.T6G(SCH_1):PAGE301_I35@PURE_QUANTA.Q_RES(CHIPS)':
 C_PATH='@t6g_mb_lib.t6g(sch_1):page301_i35@pure_quanta.q_res(chips)';

PART_NAME
 PR366 'Q_RES_0402LF-0,5%,1/16W,CHIP,CS00002JB38':;

SECTION_NUMBER 1
 '@T6G_MB_LIB.T6G(SCH_1):PAGE301_I38@PURE_QUANTA.Q_RES(CHIPS)':
 C_PATH='@t6g_mb_lib.t6g(sch_1):page301_i38@pure_quanta.q_res(chips)';

PART_NAME
 PR365 'Q_RES_0402LF-0,5%,1/16W,CHIP,CS00002JB38':;

SECTION_NUMBER 1
 '@T6G_MB_LIB.T6G(SCH_1):PAGE301_I37@PURE_QUANTA.Q_RES(CHIPS)':
 C_PATH='@t6g_mb_lib.t6g(sch_1):page301_i37@pure_quanta.q_res(chips)';

PART_NAME
 PR364 'Q_RES_0402LF-150,1%,1/16W,CHIP,TMP_QCS11502FB21':;

SECTION_NUMBER 1
 '@T6G_MB_LIB.T6G(SCH_1):PAGE301_I39@PURE_QUANTA.Q_RES(CHIPS)':
 C_PATH='@t6g_mb_lib.t6g(sch_1):page301_i39@pure_quanta.q_res(chips)';

PART_NAME
 PR363 'Q_RES_0402LF-0,5%,1/16W,CHIP,CS00002JB38':;

SECTION_NUMBER 1
 '@T6G_MB_LIB.T6G(SCH_1):PAGE301_I40@PURE_QUANTA.Q_RES(CHIPS)':
 C_PATH='@t6g_mb_lib.t6g(sch_1):page301_i40@pure_quanta.q_res(chips)';

PART_NAME
 PR362 'Q_RES_0402LF-0,5%,1/16W,CHIP,CS00002JB38':;

SECTION_NUMBER 1
 '@T6G_MB_LIB.T6G(SCH_1):PAGE301_I44@PURE_QUANTA.Q_RES(CHIPS)':
 C_PATH='@t6g_mb_lib.t6g(sch_1):page301_i44@pure_quanta.q_res(chips)';

PART_NAME
 PR361 'Q_RES_0402LF-1K,1%,1/16W,CHIP,TMP_QCS21002FB24':;

SECTION_NUMBER 1
 '@T6G_MB_LIB.T6G(SCH_1):PAGE301_I43@PURE_QUANTA.Q_RES(CHIPS)':
 C_PATH='@t6g_mb_lib.t6g(sch_1):page301_i43@pure_quanta.q_res(chips)';

PART_NAME
 PR358 'Q_RES_0402LF-4.64K,0.5%,1/16W,CHIP,CS24642DB00':;

SECTION_NUMBER 1
 '@T6G_MB_LIB.T6G(SCH_1):PAGE301_I6@PURE_QUANTA.Q_RES(CHIPS)':
 C_PATH='@t6g_mb_lib.t6g(sch_1):page301_i6@pure_quanta.q_res(chips)',
 CDSVAR_REPCELL_MPS='pure_quanta|Q_res',
 VAR_0_MPS='VALUE|0|TOLERANCE|5%|WATTAGE|1/16W|PACK_TYPE|0402LF|MATERIAL|CHIP|PA~
RT_NUMBER|CS00002JB38|STANDARD|End of Design|LIFECYCLE|Comp-Approve|PART_NUMBER|~
CS00002JB38|JEDEC_TYPE|R0402|ALT_SYMBOLS|(R0402-0201)|VALUE|0|TOL|5%|WATTAGE|1/1~
6W|CLASS|DISCRETE|DESCRIPTION|RESISTOR CHIP 0 1/16W +-5%(0402)|COMPONENT_TYPE|CH~
IP0402|LEAD_LENGTH||DFM_EXCLUSION||DAY|20100618|VARIANT_DEVICE_TYPE|Q_RES-0,5%,1~
/16W,0402LF,CHIP,C';

PART_NAME
 PR357 'Q_RES_0402LF-28K,1%,1/16W,EMPTY,CS32802FB05':;

SECTION_NUMBER 1
 '@T6G_MB_LIB.T6G(SCH_1):PAGE301_I7@PURE_QUANTA.Q_RES(CHIPS)':
 C_PATH='@t6g_mb_lib.t6g(sch_1):page301_i7@pure_quanta.q_res(chips)';

PART_NAME
 PJ54 'Q_SHORT_SM-EMPTY,SHORT6':;

SECTION_NUMBER 1
 '@T6G_MB_LIB.T6G(SCH_1):PAGE301_I79@PURE_QUANTA.Q_SHORT(CHIPS)':
 C_PATH='@t6g_mb_lib.t6g(sch_1):page301_i79@pure_quanta.q_short(chips)';

PART_NAME
 PC1196 'Q_CAP_C0402-1UF,16V,10%,X6S,CH5103KEB01':;

SECTION_NUMBER 1
 '@T6G_MB_LIB.T6G(SCH_1):PAGE301_I64@PURE_QUANTA.Q_CAP(CHIPS)':
 C_PATH='@t6g_mb_lib.t6g(sch_1):page301_i64@pure_quanta.q_cap(chips)';

PART_NAME
 PC813 'Q_CAP_C0402-1UF,16V,10%,X6S,CH5103KEB01':;

SECTION_NUMBER 1
 '@T6G_MB_LIB.T6G(SCH_1):PAGE301_I49@PURE_QUANTA.Q_CAP(CHIPS)':
 C_PATH='@t6g_mb_lib.t6g(sch_1):page301_i49@pure_quanta.q_cap(chips)',
 CDSVAR_REPCELL_MPS='pure_quanta|Q_cap',
 VAR_0_MPS='VALUE|1UF|VOLTAGE|16V|TOLERANCE|10%|PACK_TYPE|C0402|MATERIAL|EMPTY|P~
ART_NUMBER|CH5103KEB01|STANDARD||LIFECYCLE||ASS_PART||PART_NUMBER|CH5103KEB01|JE~
DEC_TYPE|C0402|ALT_SYMBOLS|(C0402-0201)|VALUE|NA|RATED_VOLTAGE|16V|TOL|10%|CLASS~
|IO|DESCRIPTION|CAP CHIP 1UF 16V(10%,X6S,0402)|COMPONENT_TYPE|CHIP0402|LEAD_LENG~
TH||LPID||DATE|20140828|VARIANT_DEVICE_TYPE|Q_CAP-1UF,16V,10%,C0402,EMPTY,';

PART_NAME
 PC632 'Q_CAP_C0402-1UF,16V,10%,X6S,CH5103KEB01':;

SECTION_NUMBER 1
 '@T6G_MB_LIB.T6G(SCH_1):PAGE301_I66@PURE_QUANTA.Q_CAP(CHIPS)':
 C_PATH='@t6g_mb_lib.t6g(sch_1):page301_i66@pure_quanta.q_cap(chips)';

PART_NAME
 PC631 'Q_CAP_0402-470PF,50V,10%,X7R,TMP_QCH14706KB18':;

SECTION_NUMBER 1
 '@T6G_MB_LIB.T6G(SCH_1):PAGE301_I55@PURE_QUANTA.Q_CAP(CHIPS)':
 C_PATH='@t6g_mb_lib.t6g(sch_1):page301_i55@pure_quanta.q_cap(chips)',
 CDSVAR_REPCELL_MPS='pure_quanta|Q_cap',
 VAR_0_MPS='VALUE|0.01UF|VOLTAGE|25V|TOLERANCE|10%|PACK_TYPE|0402|MATERIAL|X7R|P~
ART_NUMBER|TMP_QCH31004KB17|STANDARD|End of Design|LIFECYCLE|Comp-Approve|ASS_PA~
RT||PART_NUMBER|CH31004KB17|JEDEC_TYPE|C0402|ALT_SYMBOLS|(C0402-0201)|VALUE|0.01~
UF|RATED_VOLTAGE|25V|TOL|10%|CLASS|DISCRETE|DESCRIPTION|CAP CHIP 0.01U 25V(+-10%~
,X7R,0402)|COMPONENT_TYPE|CHIP0402|LEAD_LENGTH||LPID||DATE|20100528|VARIANT_DEVI~
CE_TYPE|Q_CAP-0.01UF,25V,10%,0402,X7R,';

PART_NAME
 PC630 'Q_CAP_0402-4.7UF,6.3V,20%,X6S,CH5471MEB01':;

SECTION_NUMBER 1
 '@T6G_MB_LIB.T6G(SCH_1):PAGE301_I63@PURE_QUANTA.Q_CAP(CHIPS)':
 C_PATH='@t6g_mb_lib.t6g(sch_1):page301_i63@pure_quanta.q_cap(chips)',
 CDSVAR_REPCELL_MPS='pure_quanta|Q_cap',
 VAR_0_MPS='VALUE|4.7UF|VOLTAGE|6.3V|TOLERANCE|20%|PACK_TYPE|0402|MATERIAL|EMPTY~
|PART_NUMBER|CH5471MEB01|STANDARD||LIFECYCLE||ASS_PART||PART_NUMBER|CH5471MEB01|~
JEDEC_TYPE|C0402|ALT_SYMBOLS|(C0402_OCTAGON,C0402_OCTAGONXA,C0402-0201)|VALUE|NA~
|RATED_VOLTAGE|6.3V|TOL|20%|CLASS|IO|DESCRIPTION|CAP CHIP 4.7UF 6.3V(+-20%,X6S,0~
402)|COMPONENT_TYPE|CHIP0402|LEAD_LENGTH||LPID||DATE|20151211|VARIANT_DEVICE_TYP~
E|Q_CAP-4.7UF,6.3V,20%,0402,EMPT';

PART_NAME
 PC629 'Q_CAP_C0402-100NF,50V,10%,EMPTY,CH4106K1B01':;

SECTION_NUMBER 1
 '@T6G_MB_LIB.T6G(SCH_1):PAGE301_I65@PURE_QUANTA.Q_CAP(CHIPS)':
 C_PATH='@t6g_mb_lib.t6g(sch_1):page301_i65@pure_quanta.q_cap(chips)';

PART_NAME
 PC628 'Q_CAP_0402-0.1UF,25V,10%,X7R,CH4104K1B00':;

SECTION_NUMBER 1
 '@T6G_MB_LIB.T6G(SCH_1):PAGE301_I48@PURE_QUANTA.Q_CAP(CHIPS)':
 C_PATH='@t6g_mb_lib.t6g(sch_1):page301_i48@pure_quanta.q_cap(chips)';

PART_NAME
 PC627 'Q_CAP_0402-3300PF,50V,10%,X7R,TMP_QCH2336K1B12':;

SECTION_NUMBER 1
 '@T6G_MB_LIB.T6G(SCH_1):PAGE301_I18@PURE_QUANTA.Q_CAP(CHIPS)':
 C_PATH='@t6g_mb_lib.t6g(sch_1):page301_i18@pure_quanta.q_cap(chips)',
 CDSVAR_REPCELL_MPS='pure_quanta|Q_cap',
 VAR_0_MPS='VALUE|3300PF|VOLTAGE|50V|TOLERANCE|10%|PACK_TYPE|C0402|MATERIAL|EMPT~
Y|PART_NUMBER|CH2336K1B06|STANDARD||LIFECYCLE||ASS_PART||PART_NUMBER|CH2336K1B06~
|JEDEC_TYPE|C0402|ALT_SYMBOLS|(C0402-0201)|VALUE|NA|RATED_VOLTAGE|50V|TOL|10%|CL~
ASS|IO|DESCRIPTION|CAP CHIP 3300P 50V(+-10%,X7R,0402)MUR|COMPONENT_TYPE|CHIP0402~
|LEAD_LENGTH||LPID||DATE|20150617|VARIANT_DEVICE_TYPE|Q_CAP-3300PF,50V,10%,C0402~
,EMP';

PART_NAME
 PC626 'Q_CAP_0402-1000PF,50V,5%,EMPTY,TMP_QCH21006JB10':;

SECTION_NUMBER 1
 '@T6G_MB_LIB.T6G(SCH_1):PAGE301_I45@PURE_QUANTA.Q_CAP(CHIPS)':
 C_PATH='@t6g_mb_lib.t6g(sch_1):page301_i45@pure_quanta.q_cap(chips)';

PART_NAME
 PC624 'Q_CAP_0402-0.1UF,25V,10%,X7R,CH4104K1B00':;

SECTION_NUMBER 1
 '@T6G_MB_LIB.T6G(SCH_1):PAGE301_I13@PURE_QUANTA.Q_CAP(CHIPS)':
 C_PATH='@t6g_mb_lib.t6g(sch_1):page301_i13@pure_quanta.q_cap(chips)',
 CDSVAR_REPCELL_MPS='pure_quanta|Q_cap',
 VAR_0_MPS='VALUE|0.1UF|VOLTAGE|25V|TOLERANCE|10%|PACK_TYPE|0402|MATERIAL|EMPTY|~
PART_NUMBER|CH4104K1B00|STANDARD||LIFECYCLE||ASS_PART||PART_NUMBER|CH4104K1B00|J~
EDEC_TYPE|C0402|ALT_SYMBOLS|(C0402_OCTAGONXA,C0402-0201)|VALUE|NA|RATED_VOLTAGE|~
25V|TOL|10%|CLASS|IO|DESCRIPTION|CAP CHIP 0.1U 25V(+-10%,X7R,0402)|COMPONENT_TYP~
E|CHIP0402|LEAD_LENGTH||LPID||DATE|20160113|VARIANT_DEVICE_TYPE|Q_CAP-0.1UF,25V,~
10%,0402,EMPTY';

PART_NAME
 C2444 'Q_CAP_0402-0.1UF,25V,10%,X7R,CH4104K1B00':;

SECTION_NUMBER 1
 '@T6G_MB_LIB.T6G(SCH_1):PAGE301_I24@PURE_QUANTA.Q_CAP(CHIPS)':
 C_PATH='@t6g_mb_lib.t6g(sch_1):page301_i24@pure_quanta.q_cap(chips)';

PART_NAME
 C2443 'Q_CAP_C0402-10UF,4V,20%,X6S,CH610KMEB09':;

SECTION_NUMBER 1
 '@T6G_MB_LIB.T6G(SCH_1):PAGE301_I20@PURE_QUANTA.Q_CAP(CHIPS)':
 C_PATH='@t6g_mb_lib.t6g(sch_1):page301_i20@pure_quanta.q_cap(chips)';

PART_NAME
 U5 '74LVC07APW_SMTLF-74LVC07APW,74LVC07APW,IC,ALLVC007K36':;

SECTION_NUMBER 1
 '@T6G_MB_LIB.T6G(SCH_1):PAGE95_I106@PURE_QUANTA.74LVC07APW(CHIPS)':
 C_PATH='@t6g_mb_lib.t6g(sch_1):page95_i106@pure_quanta.\74lvc07apw\(chips)';

SECTION_NUMBER 2
 '@T6G_MB_LIB.T6G(SCH_1):PAGE95_I108@PURE_QUANTA.74LVC07APW(CHIPS)':
 C_PATH='@t6g_mb_lib.t6g(sch_1):page95_i108@pure_quanta.\74lvc07apw\(chips)';

SECTION_NUMBER 3
 '@T6G_MB_LIB.T6G(SCH_1):PAGE95_I107@PURE_QUANTA.74LVC07APW(CHIPS)':
 C_PATH='@t6g_mb_lib.t6g(sch_1):page95_i107@pure_quanta.\74lvc07apw\(chips)';

SECTION_NUMBER 4
 '@T6G_MB_LIB.T6G(SCH_1):PAGE95_I109@PURE_QUANTA.74LVC07APW(CHIPS)':
 C_PATH='@t6g_mb_lib.t6g(sch_1):page95_i109@pure_quanta.\74lvc07apw\(chips)';

SECTION_NUMBER 5
 '@T6G_MB_LIB.T6G(SCH_1):PAGE95_I120@PURE_QUANTA.74LVC07APW(CHIPS)':
 C_PATH='@t6g_mb_lib.t6g(sch_1):page95_i120@pure_quanta.\74lvc07apw\(chips)';

SECTION_NUMBER 6
 '@T6G_MB_LIB.T6G(SCH_1):PAGE95_I121@PURE_QUANTA.74LVC07APW(CHIPS)':
 C_PATH='@t6g_mb_lib.t6g(sch_1):page95_i121@pure_quanta.\74lvc07apw\(chips)';

PART_NAME
 R2063 'Q_RES_0402LF-0,5%,1/16W,EMPTY,CS00002JB38':;

SECTION_NUMBER 1
 '@T6G_MB_LIB.T6G(SCH_1):PAGE95_I136@PURE_QUANTA.Q_RES(CHIPS)':
 C_PATH='@t6g_mb_lib.t6g(sch_1):page95_i136@pure_quanta.q_res(chips)';

PART_NAME
 R2056 'Q_RES_0402LF-0,5%,1/16W,EMPTY,CS00002JB38':;

SECTION_NUMBER 1
 '@T6G_MB_LIB.T6G(SCH_1):PAGE95_I134@PURE_QUANTA.Q_RES(CHIPS)':
 C_PATH='@t6g_mb_lib.t6g(sch_1):page95_i134@pure_quanta.q_res(chips)';

PART_NAME
 R186 'Q_RES_0402LF-33,5%,1/16W,CHIP,CS03302JB29':;

SECTION_NUMBER 1
 '@T6G_MB_LIB.T6G(SCH_1):PAGE95_I117@PURE_QUANTA.Q_RES(CHIPS)':
 C_PATH='@t6g_mb_lib.t6g(sch_1):page95_i117@pure_quanta.q_res(chips)';

PART_NAME
 R185 'Q_RES_0402LF-100,1%,1/16W,EMPTY,TMP_QCS11002FB22':;

SECTION_NUMBER 1
 '@T6G_MB_LIB.T6G(SCH_1):PAGE95_I143@PURE_QUANTA.Q_RES(CHIPS)':
 C_PATH='@t6g_mb_lib.t6g(sch_1):page95_i143@pure_quanta.q_res(chips)';

PART_NAME
 R184 'Q_RES_0402LF-33,5%,1/16W,CHIP,CS03302JB29':;

SECTION_NUMBER 1
 '@T6G_MB_LIB.T6G(SCH_1):PAGE95_I115@PURE_QUANTA.Q_RES(CHIPS)':
 C_PATH='@t6g_mb_lib.t6g(sch_1):page95_i115@pure_quanta.q_res(chips)';

PART_NAME
 R183 'Q_RES_0402LF-100,1%,1/16W,EMPTY,TMP_QCS11002FB22':;

SECTION_NUMBER 1
 '@T6G_MB_LIB.T6G(SCH_1):PAGE95_I141@PURE_QUANTA.Q_RES(CHIPS)':
 C_PATH='@t6g_mb_lib.t6g(sch_1):page95_i141@pure_quanta.q_res(chips)';

PART_NAME
 R182 'Q_RES_0402LF-100,1%,1/16W,EMPTY,TMP_QCS11002FB22':;

SECTION_NUMBER 1
 '@T6G_MB_LIB.T6G(SCH_1):PAGE95_I100@PURE_QUANTA.Q_RES(CHIPS)':
 C_PATH='@t6g_mb_lib.t6g(sch_1):page95_i100@pure_quanta.q_res(chips)';

PART_NAME
 R181 'Q_RES_0402LF-100,1%,1/16W,CHIP,TMP_QCS11002FB22':;

SECTION_NUMBER 1
 '@T6G_MB_LIB.T6G(SCH_1):PAGE95_I101@PURE_QUANTA.Q_RES(CHIPS)':
 C_PATH='@t6g_mb_lib.t6g(sch_1):page95_i101@pure_quanta.q_res(chips)';

PART_NAME
 R180 'Q_RES_0402LF-100,1%,1/16W,EMPTY,TMP_QCS11002FB22':;

SECTION_NUMBER 1
 '@T6G_MB_LIB.T6G(SCH_1):PAGE95_I99@PURE_QUANTA.Q_RES(CHIPS)':
 C_PATH='@t6g_mb_lib.t6g(sch_1):page95_i99@pure_quanta.q_res(chips)';

PART_NAME
 R179 'Q_RES_0402LF-100,1%,1/16W,CHIP,TMP_QCS11002FB22':;

SECTION_NUMBER 1
 '@T6G_MB_LIB.T6G(SCH_1):PAGE95_I98@PURE_QUANTA.Q_RES(CHIPS)':
 C_PATH='@t6g_mb_lib.t6g(sch_1):page95_i98@pure_quanta.q_res(chips)';

PART_NAME
 R178 'Q_RES_0402LF-100,1%,1/16W,EMPTY,TMP_QCS11002FB22':;

SECTION_NUMBER 1
 '@T6G_MB_LIB.T6G(SCH_1):PAGE95_I97@PURE_QUANTA.Q_RES(CHIPS)':
 C_PATH='@t6g_mb_lib.t6g(sch_1):page95_i97@pure_quanta.q_res(chips)';

PART_NAME
 R177 'Q_RES_0402LF-100,1%,1/16W,CHIP,TMP_QCS11002FB22':;

SECTION_NUMBER 1
 '@T6G_MB_LIB.T6G(SCH_1):PAGE95_I94@PURE_QUANTA.Q_RES(CHIPS)':
 C_PATH='@t6g_mb_lib.t6g(sch_1):page95_i94@pure_quanta.q_res(chips)';

PART_NAME
 R176 'Q_RES_0402LF-100,1%,1/16W,EMPTY,TMP_QCS11002FB22':;

SECTION_NUMBER 1
 '@T6G_MB_LIB.T6G(SCH_1):PAGE95_I92@PURE_QUANTA.Q_RES(CHIPS)':
 C_PATH='@t6g_mb_lib.t6g(sch_1):page95_i92@pure_quanta.q_res(chips)';

PART_NAME
 R175 'Q_RES_0402LF-100,1%,1/16W,CHIP,TMP_QCS11002FB22':;

SECTION_NUMBER 1
 '@T6G_MB_LIB.T6G(SCH_1):PAGE95_I93@PURE_QUANTA.Q_RES(CHIPS)':
 C_PATH='@t6g_mb_lib.t6g(sch_1):page95_i93@pure_quanta.q_res(chips)';

PART_NAME
 R174 'Q_RES_0402LF-0,5%,1/16W,EMPTY,CS00002JB38':;

SECTION_NUMBER 1
 '@T6G_MB_LIB.T6G(SCH_1):PAGE95_I119@PURE_QUANTA.Q_RES(CHIPS)':
 C_PATH='@t6g_mb_lib.t6g(sch_1):page95_i119@pure_quanta.q_res(chips)';

PART_NAME
 R173 'Q_RES_0402LF-0,5%,1/16W,EMPTY,CS00002JB38':;

SECTION_NUMBER 1
 '@T6G_MB_LIB.T6G(SCH_1):PAGE95_I118@PURE_QUANTA.Q_RES(CHIPS)':
 C_PATH='@t6g_mb_lib.t6g(sch_1):page95_i118@pure_quanta.q_res(chips)';

PART_NAME
 R171 'Q_RES_0402LF-0,5%,1/16W,CHIP,CS00002JB38':;

SECTION_NUMBER 1
 '@T6G_MB_LIB.T6G(SCH_1):PAGE95_I137@PURE_QUANTA.Q_RES(CHIPS)':
 C_PATH='@t6g_mb_lib.t6g(sch_1):page95_i137@pure_quanta.q_res(chips)';

PART_NAME
 R168 'Q_RES_0402LF-0,5%,1/16W,CHIP,CS00002JB38':;

SECTION_NUMBER 1
 '@T6G_MB_LIB.T6G(SCH_1):PAGE95_I135@PURE_QUANTA.Q_RES(CHIPS)':
 C_PATH='@t6g_mb_lib.t6g(sch_1):page95_i135@pure_quanta.q_res(chips)';

PART_NAME
 R166 'Q_RES_0402LF-0,5%,1/16W,CHIP,CS00002JB38':;

SECTION_NUMBER 1
 '@T6G_MB_LIB.T6G(SCH_1):PAGE95_I133@PURE_QUANTA.Q_RES(CHIPS)':
 C_PATH='@t6g_mb_lib.t6g(sch_1):page95_i133@pure_quanta.q_res(chips)';

PART_NAME
 R165 'Q_RES_0402LF-33,5%,1/16W,EMPTY,CS03302JB29':;

SECTION_NUMBER 1
 '@T6G_MB_LIB.T6G(SCH_1):PAGE95_I128@PURE_QUANTA.Q_RES(CHIPS)':
 C_PATH='@t6g_mb_lib.t6g(sch_1):page95_i128@pure_quanta.q_res(chips)';

PART_NAME
 R164 'Q_RES_0402LF-0,5%,1/16W,CHIP,CS00002JB38':;

SECTION_NUMBER 1
 '@T6G_MB_LIB.T6G(SCH_1):PAGE95_I127@PURE_QUANTA.Q_RES(CHIPS)':
 C_PATH='@t6g_mb_lib.t6g(sch_1):page95_i127@pure_quanta.q_res(chips)';

PART_NAME
 R163 'Q_RES_0402LF-33,5%,1/16W,EMPTY,CS03302JB29':;

SECTION_NUMBER 1
 '@T6G_MB_LIB.T6G(SCH_1):PAGE95_I126@PURE_QUANTA.Q_RES(CHIPS)':
 C_PATH='@t6g_mb_lib.t6g(sch_1):page95_i126@pure_quanta.q_res(chips)';

PART_NAME
 R162 'Q_RES_0402LF-0,5%,1/16W,CHIP,CS00002JB38':;

SECTION_NUMBER 1
 '@T6G_MB_LIB.T6G(SCH_1):PAGE95_I125@PURE_QUANTA.Q_RES(CHIPS)':
 C_PATH='@t6g_mb_lib.t6g(sch_1):page95_i125@pure_quanta.q_res(chips)';

PART_NAME
 R161 'Q_RES_0402LF-33,5%,1/16W,EMPTY,CS03302JB29':;

SECTION_NUMBER 1
 '@T6G_MB_LIB.T6G(SCH_1):PAGE95_I124@PURE_QUANTA.Q_RES(CHIPS)':
 C_PATH='@t6g_mb_lib.t6g(sch_1):page95_i124@pure_quanta.q_res(chips)';

PART_NAME
 R160 'Q_RES_0402LF-0,5%,1/16W,CHIP,CS00002JB38':;

SECTION_NUMBER 1
 '@T6G_MB_LIB.T6G(SCH_1):PAGE95_I123@PURE_QUANTA.Q_RES(CHIPS)':
 C_PATH='@t6g_mb_lib.t6g(sch_1):page95_i123@pure_quanta.q_res(chips)';

PART_NAME
 R159 'Q_RES_0402LF-33,5%,1/16W,EMPTY,CS03302JB29':;

SECTION_NUMBER 1
 '@T6G_MB_LIB.T6G(SCH_1):PAGE95_I122@PURE_QUANTA.Q_RES(CHIPS)':
 C_PATH='@t6g_mb_lib.t6g(sch_1):page95_i122@pure_quanta.q_res(chips)';

PART_NAME
 C2442 'Q_CAP_0402-0.1UF,25V,10%,X7R,CH4104K1B00':;

SECTION_NUMBER 1
 '@T6G_MB_LIB.T6G(SCH_1):PAGE95_I104@PURE_QUANTA.Q_CAP(CHIPS)':
 C_PATH='@t6g_mb_lib.t6g(sch_1):page95_i104@pure_quanta.q_cap(chips)';

PART_NAME
 U174 'NC7SB3157_SMLF-NC7SB3157P6X,NC7SB3157P6X,IC,ALSB3157000':;

SECTION_NUMBER 1
 '@T6G_MB_LIB.T6G(SCH_1):PAGE195_I191@PURE_QUANTA.NC7SB3157(CHIPS)':
 C_PATH='@t6g_mb_lib.t6g(sch_1):page195_i191@pure_quanta.nc7sb3157(chips)';

PART_NAME
 U60 'NC7SB3157_SMLF-NC7SB3157P6X,NC7SB3157P6X,IC,ALSB3157000':;

SECTION_NUMBER 1
 '@T6G_MB_LIB.T6G(SCH_1):PAGE195_I189@PURE_QUANTA.NC7SB3157(CHIPS)':
 C_PATH='@t6g_mb_lib.t6g(sch_1):page195_i189@pure_quanta.nc7sb3157(chips)';

PART_NAME
 R1941 'Q_RES_0402LF-49.9     ,1%  ,1/16W,CHIP,CS04992FB31':;

SECTION_NUMBER 1
 '@T6G_MB_LIB.T6G(SCH_1):PAGE195_I176@PURE_QUANTA.Q_RES(CHIPS)':
 C_PATH='@t6g_mb_lib.t6g(sch_1):page195_i176@pure_quanta.q_res(chips)';

PART_NAME
 R1940 'Q_RES_0402LF-220,1%,1/16W,EMPTY,TMP_QCS12202FB14':;

SECTION_NUMBER 1
 '@T6G_MB_LIB.T6G(SCH_1):PAGE195_I199@PURE_QUANTA.Q_RES(CHIPS)':
 C_PATH='@t6g_mb_lib.t6g(sch_1):page195_i199@pure_quanta.q_res(chips)';

PART_NAME
 R1939 'Q_RES_0402LF-220,1%,1/16W,EMPTY,TMP_QCS12202FB14':;

SECTION_NUMBER 1
 '@T6G_MB_LIB.T6G(SCH_1):PAGE195_I206@PURE_QUANTA.Q_RES(CHIPS)':
 C_PATH='@t6g_mb_lib.t6g(sch_1):page195_i206@pure_quanta.q_res(chips)';

PART_NAME
 R1938 'Q_RES_0402LF-220,1%,1/16W,EMPTY,TMP_QCS12202FB14':;

SECTION_NUMBER 1
 '@T6G_MB_LIB.T6G(SCH_1):PAGE195_I165@PURE_QUANTA.Q_RES(CHIPS)':
 C_PATH='@t6g_mb_lib.t6g(sch_1):page195_i165@pure_quanta.q_res(chips)';

PART_NAME
 R1937 'Q_RES_0402LF-220,1%,1/16W,EMPTY,TMP_QCS12202FB14':;

SECTION_NUMBER 1
 '@T6G_MB_LIB.T6G(SCH_1):PAGE195_I207@PURE_QUANTA.Q_RES(CHIPS)':
 C_PATH='@t6g_mb_lib.t6g(sch_1):page195_i207@pure_quanta.q_res(chips)';

PART_NAME
 R1936 'Q_RES_0402LF-33,5%,1/16W,CHIP,CS03302JB29':;

SECTION_NUMBER 1
 '@T6G_MB_LIB.T6G(SCH_1):PAGE195_I205@PURE_QUANTA.Q_RES(CHIPS)':
 C_PATH='@t6g_mb_lib.t6g(sch_1):page195_i205@pure_quanta.q_res(chips)';

PART_NAME
 R1935 'Q_RES_0402LF-56,1%,1/16W,CHIP,TMP_QCS05602FB15':;

SECTION_NUMBER 1
 '@T6G_MB_LIB.T6G(SCH_1):PAGE195_I212@PURE_QUANTA.Q_RES(CHIPS)':
 C_PATH='@t6g_mb_lib.t6g(sch_1):page195_i212@pure_quanta.q_res(chips)';

PART_NAME
 R1934 'Q_RES_0402LF-56,1%,1/16W,CHIP,TMP_QCS05602FB15':;

SECTION_NUMBER 1
 '@T6G_MB_LIB.T6G(SCH_1):PAGE195_I211@PURE_QUANTA.Q_RES(CHIPS)':
 C_PATH='@t6g_mb_lib.t6g(sch_1):page195_i211@pure_quanta.q_res(chips)';

PART_NAME
 R1933 'Q_RES_0402LF-56,1%,1/16W,CHIP,TMP_QCS05602FB15':;

SECTION_NUMBER 1
 '@T6G_MB_LIB.T6G(SCH_1):PAGE195_I209@PURE_QUANTA.Q_RES(CHIPS)':
 C_PATH='@t6g_mb_lib.t6g(sch_1):page195_i209@pure_quanta.q_res(chips)';

PART_NAME
 R1932 'Q_RES_0402LF-56,1%,1/16W,CHIP,TMP_QCS05602FB15':;

SECTION_NUMBER 1
 '@T6G_MB_LIB.T6G(SCH_1):PAGE195_I210@PURE_QUANTA.Q_RES(CHIPS)':
 C_PATH='@t6g_mb_lib.t6g(sch_1):page195_i210@pure_quanta.q_res(chips)';

PART_NAME
 R1931 'Q_RES_0402LF-56,1%,1/16W,CHIP,TMP_QCS05602FB15':;

SECTION_NUMBER 1
 '@T6G_MB_LIB.T6G(SCH_1):PAGE195_I208@PURE_QUANTA.Q_RES(CHIPS)':
 C_PATH='@t6g_mb_lib.t6g(sch_1):page195_i208@pure_quanta.q_res(chips)';

PART_NAME
 R1750 'Q_RES_0402LF-1K,1%,1/16W,CHIP,TMP_QCS21002FB24':;

SECTION_NUMBER 1
 '@T6G_MB_LIB.T6G(SCH_1):PAGE195_I220@PURE_QUANTA.Q_RES(CHIPS)':
 C_PATH='@t6g_mb_lib.t6g(sch_1):page195_i220@pure_quanta.q_res(chips)';

PART_NAME
 R1749 'Q_RES_0402LF-10K,1%,1/16W,EMPTY,TMP_QCS31002FB26':;

SECTION_NUMBER 1
 '@T6G_MB_LIB.T6G(SCH_1):PAGE195_I221@PURE_QUANTA.Q_RES(CHIPS)':
 C_PATH='@t6g_mb_lib.t6g(sch_1):page195_i221@pure_quanta.q_res(chips)';

PART_NAME
 R1748 'Q_RES_0402LF-0,5%,1/16W,CHIP,CS00002JB38':;

SECTION_NUMBER 1
 '@T6G_MB_LIB.T6G(SCH_1):PAGE195_I177@PURE_QUANTA.Q_RES(CHIPS)':
 C_PATH='@t6g_mb_lib.t6g(sch_1):page195_i177@pure_quanta.q_res(chips)';

PART_NAME
 R1214 'Q_RES_0402LF-0,5%,1/16W,CHIP,CS00002JB38':;

SECTION_NUMBER 1
 '@T6G_MB_LIB.T6G(SCH_1):PAGE195_I201@PURE_QUANTA.Q_RES(CHIPS)':
 C_PATH='@t6g_mb_lib.t6g(sch_1):page195_i201@pure_quanta.q_res(chips)';

PART_NAME
 R1213 'Q_RES_0402LF-33,5%,1/16W,CHIP,CS03302JB29':;

SECTION_NUMBER 1
 '@T6G_MB_LIB.T6G(SCH_1):PAGE195_I197@PURE_QUANTA.Q_RES(CHIPS)':
 C_PATH='@t6g_mb_lib.t6g(sch_1):page195_i197@pure_quanta.q_res(chips)';

PART_NAME
 R1212 'Q_RES_0402LF-33,5%,1/16W,CHIP,CS03302JB29':;

SECTION_NUMBER 1
 '@T6G_MB_LIB.T6G(SCH_1):PAGE195_I196@PURE_QUANTA.Q_RES(CHIPS)':
 C_PATH='@t6g_mb_lib.t6g(sch_1):page195_i196@pure_quanta.q_res(chips)';

PART_NAME
 R1211 'Q_RES_0402LF-33,5%,1/16W,CHIP,CS03302JB29':;

SECTION_NUMBER 1
 '@T6G_MB_LIB.T6G(SCH_1):PAGE195_I195@PURE_QUANTA.Q_RES(CHIPS)':
 C_PATH='@t6g_mb_lib.t6g(sch_1):page195_i195@pure_quanta.q_res(chips)';

PART_NAME
 R1210 'Q_RES_0402LF-33,5%,1/16W,CHIP,CS03302JB29':;

SECTION_NUMBER 1
 '@T6G_MB_LIB.T6G(SCH_1):PAGE195_I194@PURE_QUANTA.Q_RES(CHIPS)':
 C_PATH='@t6g_mb_lib.t6g(sch_1):page195_i194@pure_quanta.q_res(chips)';

PART_NAME
 R1209 'Q_RES_0402LF-33,5%,1/16W,CHIP,CS03302JB29':;

SECTION_NUMBER 1
 '@T6G_MB_LIB.T6G(SCH_1):PAGE195_I193@PURE_QUANTA.Q_RES(CHIPS)':
 C_PATH='@t6g_mb_lib.t6g(sch_1):page195_i193@pure_quanta.q_res(chips)';

PART_NAME
 R1208 'Q_RES_0402LF-220,1%,1/16W,EMPTY,TMP_QCS12202FB14':;

SECTION_NUMBER 1
 '@T6G_MB_LIB.T6G(SCH_1):PAGE195_I166@PURE_QUANTA.Q_RES(CHIPS)':
 C_PATH='@t6g_mb_lib.t6g(sch_1):page195_i166@pure_quanta.q_res(chips)';

PART_NAME
 C2436 'Q_CAP_0402-0.1UF,25V,10%,X7R,CH4104K1B00':;

SECTION_NUMBER 1
 '@T6G_MB_LIB.T6G(SCH_1):PAGE195_I185@PURE_QUANTA.Q_CAP(CHIPS)':
 C_PATH='@t6g_mb_lib.t6g(sch_1):page195_i185@pure_quanta.q_cap(chips)';

PART_NAME
 C2435 'Q_CAP_0402-0.1UF,25V,10%,X7R,CH4104K1B00':;

SECTION_NUMBER 1
 '@T6G_MB_LIB.T6G(SCH_1):PAGE195_I173@PURE_QUANTA.Q_CAP(CHIPS)':
 C_PATH='@t6g_mb_lib.t6g(sch_1):page195_i173@pure_quanta.q_cap(chips)';

PART_NAME
 C2434 'Q_CAP_C0402-1UF,25V,10%,X6S,CH5104KEB02':;

SECTION_NUMBER 1
 '@T6G_MB_LIB.T6G(SCH_1):PAGE195_I187@PURE_QUANTA.Q_CAP(CHIPS)':
 C_PATH='@t6g_mb_lib.t6g(sch_1):page195_i187@pure_quanta.q_cap(chips)';

PART_NAME
 C2433 'Q_CAP_C0402-1UF,25V,10%,X6S,CH5104KEB02':;

SECTION_NUMBER 1
 '@T6G_MB_LIB.T6G(SCH_1):PAGE195_I175@PURE_QUANTA.Q_CAP(CHIPS)':
 C_PATH='@t6g_mb_lib.t6g(sch_1):page195_i175@pure_quanta.q_cap(chips)';

PART_NAME
 R1899 'Q_RES_0402LF-2K,1%,1/16W,CHIP,TMP_QCS22002FB19':;

SECTION_NUMBER 1
 '@T6G_MB_LIB.T6G(SCH_1):PAGE244_I82@PURE_QUANTA.Q_RES(CHIPS)':
 C_PATH='@t6g_mb_lib.t6g(sch_1):page244_i82@pure_quanta.q_res(chips)';

PART_NAME
 R1898 'Q_RES_0402LF-2K,1%,1/16W,CHIP,TMP_QCS22002FB19':;

SECTION_NUMBER 1
 '@T6G_MB_LIB.T6G(SCH_1):PAGE244_I83@PURE_QUANTA.Q_RES(CHIPS)':
 C_PATH='@t6g_mb_lib.t6g(sch_1):page244_i83@pure_quanta.q_res(chips)';

PART_NAME
 R1897 'Q_RES_0402LF-2K,1%,1/16W,CHIP,TMP_QCS22002FB19':;

SECTION_NUMBER 1
 '@T6G_MB_LIB.T6G(SCH_1):PAGE244_I81@PURE_QUANTA.Q_RES(CHIPS)':
 C_PATH='@t6g_mb_lib.t6g(sch_1):page244_i81@pure_quanta.q_res(chips)';

PART_NAME
 R1896 'Q_RES_0402LF-2K,1%,1/16W,CHIP,TMP_QCS22002FB19':;

SECTION_NUMBER 1
 '@T6G_MB_LIB.T6G(SCH_1):PAGE244_I80@PURE_QUANTA.Q_RES(CHIPS)':
 C_PATH='@t6g_mb_lib.t6g(sch_1):page244_i80@pure_quanta.q_res(chips)';

PART_NAME
 R1895 'Q_RES_0402LF-2K,1%,1/16W,CHIP,TMP_QCS22002FB19':;

SECTION_NUMBER 1
 '@T6G_MB_LIB.T6G(SCH_1):PAGE244_I78@PURE_QUANTA.Q_RES(CHIPS)':
 C_PATH='@t6g_mb_lib.t6g(sch_1):page244_i78@pure_quanta.q_res(chips)';

PART_NAME
 R1894 'Q_RES_0402LF-2K,1%,1/16W,CHIP,TMP_QCS22002FB19':;

SECTION_NUMBER 1
 '@T6G_MB_LIB.T6G(SCH_1):PAGE244_I79@PURE_QUANTA.Q_RES(CHIPS)':
 C_PATH='@t6g_mb_lib.t6g(sch_1):page244_i79@pure_quanta.q_res(chips)';

PART_NAME
 R1893 'Q_RES_0402LF-2K,1%,1/16W,CHIP,TMP_QCS22002FB19':;

SECTION_NUMBER 1
 '@T6G_MB_LIB.T6G(SCH_1):PAGE244_I77@PURE_QUANTA.Q_RES(CHIPS)':
 C_PATH='@t6g_mb_lib.t6g(sch_1):page244_i77@pure_quanta.q_res(chips)';

PART_NAME
 R1892 'Q_RES_0402LF-2K,1%,1/16W,CHIP,TMP_QCS22002FB19':;

SECTION_NUMBER 1
 '@T6G_MB_LIB.T6G(SCH_1):PAGE244_I76@PURE_QUANTA.Q_RES(CHIPS)':
 C_PATH='@t6g_mb_lib.t6g(sch_1):page244_i76@pure_quanta.q_res(chips)';

PART_NAME
 R1891 'Q_RES_0402LF-2K,1%,1/16W,CHIP,TMP_QCS22002FB19':;

SECTION_NUMBER 1
 '@T6G_MB_LIB.T6G(SCH_1):PAGE244_I75@PURE_QUANTA.Q_RES(CHIPS)':
 C_PATH='@t6g_mb_lib.t6g(sch_1):page244_i75@pure_quanta.q_res(chips)';

PART_NAME
 R1890 'Q_RES_0402LF-2K,1%,1/16W,CHIP,TMP_QCS22002FB19':;

SECTION_NUMBER 1
 '@T6G_MB_LIB.T6G(SCH_1):PAGE244_I23@PURE_QUANTA.Q_RES(CHIPS)':
 C_PATH='@t6g_mb_lib.t6g(sch_1):page244_i23@pure_quanta.q_res(chips)';

PART_NAME
 R1889 'Q_RES_0402LF-2K,1%,1/16W,CHIP,TMP_QCS22002FB19':;

SECTION_NUMBER 1
 '@T6G_MB_LIB.T6G(SCH_1):PAGE244_I22@PURE_QUANTA.Q_RES(CHIPS)':
 C_PATH='@t6g_mb_lib.t6g(sch_1):page244_i22@pure_quanta.q_res(chips)';

PART_NAME
 R1888 'Q_RES_0402LF-2K,1%,1/16W,CHIP,TMP_QCS22002FB19':;

SECTION_NUMBER 1
 '@T6G_MB_LIB.T6G(SCH_1):PAGE244_I21@PURE_QUANTA.Q_RES(CHIPS)':
 C_PATH='@t6g_mb_lib.t6g(sch_1):page244_i21@pure_quanta.q_res(chips)';

PART_NAME
 R1887 'Q_RES_0402LF-2K,1%,1/16W,CHIP,TMP_QCS22002FB19':;

SECTION_NUMBER 1
 '@T6G_MB_LIB.T6G(SCH_1):PAGE244_I20@PURE_QUANTA.Q_RES(CHIPS)':
 C_PATH='@t6g_mb_lib.t6g(sch_1):page244_i20@pure_quanta.q_res(chips)';

PART_NAME
 R1886 'Q_RES_0402LF-2K,1%,1/16W,CHIP,TMP_QCS22002FB19':;

SECTION_NUMBER 1
 '@T6G_MB_LIB.T6G(SCH_1):PAGE244_I19@PURE_QUANTA.Q_RES(CHIPS)':
 C_PATH='@t6g_mb_lib.t6g(sch_1):page244_i19@pure_quanta.q_res(chips)';

PART_NAME
 R1885 'Q_RES_0402LF-2K,1%,1/16W,CHIP,TMP_QCS22002FB19':;

SECTION_NUMBER 1
 '@T6G_MB_LIB.T6G(SCH_1):PAGE244_I18@PURE_QUANTA.Q_RES(CHIPS)':
 C_PATH='@t6g_mb_lib.t6g(sch_1):page244_i18@pure_quanta.q_res(chips)';

PART_NAME
 R1884 'Q_RES_0402LF-2K,1%,1/16W,CHIP,TMP_QCS22002FB19':;

SECTION_NUMBER 1
 '@T6G_MB_LIB.T6G(SCH_1):PAGE244_I17@PURE_QUANTA.Q_RES(CHIPS)':
 C_PATH='@t6g_mb_lib.t6g(sch_1):page244_i17@pure_quanta.q_res(chips)';

PART_NAME
 R1883 'Q_RES_0402LF-2K,1%,1/16W,CHIP,TMP_QCS22002FB19':;

SECTION_NUMBER 1
 '@T6G_MB_LIB.T6G(SCH_1):PAGE244_I15@PURE_QUANTA.Q_RES(CHIPS)':
 C_PATH='@t6g_mb_lib.t6g(sch_1):page244_i15@pure_quanta.q_res(chips)';

PART_NAME
 R1882 'Q_RES_0402LF-2K,1%,1/16W,CHIP,TMP_QCS22002FB19':;

SECTION_NUMBER 1
 '@T6G_MB_LIB.T6G(SCH_1):PAGE244_I13@PURE_QUANTA.Q_RES(CHIPS)':
 C_PATH='@t6g_mb_lib.t6g(sch_1):page244_i13@pure_quanta.q_res(chips)';

PART_NAME
 R1881 'Q_RES_0402LF-2K,1%,1/16W,CHIP,TMP_QCS22002FB19':;

SECTION_NUMBER 1
 '@T6G_MB_LIB.T6G(SCH_1):PAGE244_I12@PURE_QUANTA.Q_RES(CHIPS)':
 C_PATH='@t6g_mb_lib.t6g(sch_1):page244_i12@pure_quanta.q_res(chips)';

PART_NAME
 R1880 'Q_RES_0402LF-2K,1%,1/16W,CHIP,TMP_QCS22002FB19':;

SECTION_NUMBER 1
 '@T6G_MB_LIB.T6G(SCH_1):PAGE244_I10@PURE_QUANTA.Q_RES(CHIPS)':
 C_PATH='@t6g_mb_lib.t6g(sch_1):page244_i10@pure_quanta.q_res(chips)';

PART_NAME
 R1879 'Q_RES_0402LF-2K,1%,1/16W,CHIP,TMP_QCS22002FB19':;

SECTION_NUMBER 1
 '@T6G_MB_LIB.T6G(SCH_1):PAGE244_I11@PURE_QUANTA.Q_RES(CHIPS)':
 C_PATH='@t6g_mb_lib.t6g(sch_1):page244_i11@pure_quanta.q_res(chips)';

PART_NAME
 R1878 'Q_RES_0402LF-2K,1%,1/16W,CHIP,TMP_QCS22002FB19':;

SECTION_NUMBER 1
 '@T6G_MB_LIB.T6G(SCH_1):PAGE244_I8@PURE_QUANTA.Q_RES(CHIPS)':
 C_PATH='@t6g_mb_lib.t6g(sch_1):page244_i8@pure_quanta.q_res(chips)';

PART_NAME
 R1877 'Q_RES_0402LF-2K,1%,1/16W,CHIP,TMP_QCS22002FB19':;

SECTION_NUMBER 1
 '@T6G_MB_LIB.T6G(SCH_1):PAGE244_I9@PURE_QUANTA.Q_RES(CHIPS)':
 C_PATH='@t6g_mb_lib.t6g(sch_1):page244_i9@pure_quanta.q_res(chips)';

PART_NAME
 R1876 'Q_RES_0402LF-2K,1%,1/16W,CHIP,TMP_QCS22002FB19':;

SECTION_NUMBER 1
 '@T6G_MB_LIB.T6G(SCH_1):PAGE244_I7@PURE_QUANTA.Q_RES(CHIPS)':
 C_PATH='@t6g_mb_lib.t6g(sch_1):page244_i7@pure_quanta.q_res(chips)';

PART_NAME
 R1875 'Q_RES_0402LF-2K,1%,1/16W,CHIP,TMP_QCS22002FB19':;

SECTION_NUMBER 1
 '@T6G_MB_LIB.T6G(SCH_1):PAGE244_I6@PURE_QUANTA.Q_RES(CHIPS)':
 C_PATH='@t6g_mb_lib.t6g(sch_1):page244_i6@pure_quanta.q_res(chips)';

PART_NAME
 R1874 'Q_RES_0402LF-2K,1%,1/16W,CHIP,TMP_QCS22002FB19':;

SECTION_NUMBER 1
 '@T6G_MB_LIB.T6G(SCH_1):PAGE244_I5@PURE_QUANTA.Q_RES(CHIPS)':
 C_PATH='@t6g_mb_lib.t6g(sch_1):page244_i5@pure_quanta.q_res(chips)';

PART_NAME
 R1873 'Q_RES_0402LF-2K,1%,1/16W,CHIP,TMP_QCS22002FB19':;

SECTION_NUMBER 1
 '@T6G_MB_LIB.T6G(SCH_1):PAGE244_I3@PURE_QUANTA.Q_RES(CHIPS)':
 C_PATH='@t6g_mb_lib.t6g(sch_1):page244_i3@pure_quanta.q_res(chips)';

PART_NAME
 R1872 'Q_RES_0402LF-2K,1%,1/16W,CHIP,TMP_QCS22002FB19':;

SECTION_NUMBER 1
 '@T6G_MB_LIB.T6G(SCH_1):PAGE244_I4@PURE_QUANTA.Q_RES(CHIPS)':
 C_PATH='@t6g_mb_lib.t6g(sch_1):page244_i4@pure_quanta.q_res(chips)';

PART_NAME
 R1871 'Q_RES_0402LF-2K,1%,1/16W,CHIP,TMP_QCS22002FB19':;

SECTION_NUMBER 1
 '@T6G_MB_LIB.T6G(SCH_1):PAGE244_I2@PURE_QUANTA.Q_RES(CHIPS)':
 C_PATH='@t6g_mb_lib.t6g(sch_1):page244_i2@pure_quanta.q_res(chips)';

PART_NAME
 R1870 'Q_RES_0402LF-2K,1%,1/16W,CHIP,TMP_QCS22002FB19':;

SECTION_NUMBER 1
 '@T6G_MB_LIB.T6G(SCH_1):PAGE244_I1@PURE_QUANTA.Q_RES(CHIPS)':
 C_PATH='@t6g_mb_lib.t6g(sch_1):page244_i1@pure_quanta.q_res(chips)';

PART_NAME
 R1869 'Q_RES_0402LF-1K,1%,1/16W,CHIP,TMP_QCS21002FB24':;

SECTION_NUMBER 1
 '@T6G_MB_LIB.T6G(SCH_1):PAGE244_I104@PURE_QUANTA.Q_RES(CHIPS)':
 C_PATH='@t6g_mb_lib.t6g(sch_1):page244_i104@pure_quanta.q_res(chips)';

PART_NAME
 R1868 'Q_RES_0402LF-1K,1%,1/16W,CHIP,TMP_QCS21002FB24':;

SECTION_NUMBER 1
 '@T6G_MB_LIB.T6G(SCH_1):PAGE244_I102@PURE_QUANTA.Q_RES(CHIPS)':
 C_PATH='@t6g_mb_lib.t6g(sch_1):page244_i102@pure_quanta.q_res(chips)';

PART_NAME
 R1867 'Q_RES_0402LF-1K,1%,1/16W,CHIP,TMP_QCS21002FB24':;

SECTION_NUMBER 1
 '@T6G_MB_LIB.T6G(SCH_1):PAGE244_I103@PURE_QUANTA.Q_RES(CHIPS)':
 C_PATH='@t6g_mb_lib.t6g(sch_1):page244_i103@pure_quanta.q_res(chips)';

PART_NAME
 R1866 'Q_RES_0402LF-10K,1%,1/16W,CHIP,TMP_QCS31002FB26':;

SECTION_NUMBER 1
 '@T6G_MB_LIB.T6G(SCH_1):PAGE244_I100@PURE_QUANTA.Q_RES(CHIPS)':
 C_PATH='@t6g_mb_lib.t6g(sch_1):page244_i100@pure_quanta.q_res(chips)';

PART_NAME
 R1865 'Q_RES_0402LF-10K,1%,1/16W,CHIP,TMP_QCS31002FB26':;

SECTION_NUMBER 1
 '@T6G_MB_LIB.T6G(SCH_1):PAGE244_I99@PURE_QUANTA.Q_RES(CHIPS)':
 C_PATH='@t6g_mb_lib.t6g(sch_1):page244_i99@pure_quanta.q_res(chips)';

PART_NAME
 R1864 'Q_RES_0402LF-1K,1%,1/16W,CHIP,TMP_QCS21002FB24':;

SECTION_NUMBER 1
 '@T6G_MB_LIB.T6G(SCH_1):PAGE244_I98@PURE_QUANTA.Q_RES(CHIPS)':
 C_PATH='@t6g_mb_lib.t6g(sch_1):page244_i98@pure_quanta.q_res(chips)';

PART_NAME
 R1863 'Q_RES_0402LF-10K,1%,1/16W,EMPTY,TMP_QCS31002FB26':;

SECTION_NUMBER 1
 '@T6G_MB_LIB.T6G(SCH_1):PAGE244_I97@PURE_QUANTA.Q_RES(CHIPS)':
 C_PATH='@t6g_mb_lib.t6g(sch_1):page244_i97@pure_quanta.q_res(chips)';

PART_NAME
 R1862 'Q_RES_0402LF-10K,1%,1/16W,EMPTY,TMP_QCS31002FB26':;

SECTION_NUMBER 1
 '@T6G_MB_LIB.T6G(SCH_1):PAGE244_I96@PURE_QUANTA.Q_RES(CHIPS)':
 C_PATH='@t6g_mb_lib.t6g(sch_1):page244_i96@pure_quanta.q_res(chips)';

PART_NAME
 R1861 'Q_RES_0402LF-10K,1%,1/16W,EMPTY,TMP_QCS31002FB26':;

SECTION_NUMBER 1
 '@T6G_MB_LIB.T6G(SCH_1):PAGE244_I73@PURE_QUANTA.Q_RES(CHIPS)':
 C_PATH='@t6g_mb_lib.t6g(sch_1):page244_i73@pure_quanta.q_res(chips)';

PART_NAME
 R1860 'Q_RES_0402LF-1K,1%,1/16W,EMPTY,TMP_QCS21002FB24':;

SECTION_NUMBER 1
 '@T6G_MB_LIB.T6G(SCH_1):PAGE244_I72@PURE_QUANTA.Q_RES(CHIPS)':
 C_PATH='@t6g_mb_lib.t6g(sch_1):page244_i72@pure_quanta.q_res(chips)';

PART_NAME
 R1859 'Q_RES_0402LF-10K,1%,1/16W,EMPTY,TMP_QCS31002FB26':;

SECTION_NUMBER 1
 '@T6G_MB_LIB.T6G(SCH_1):PAGE244_I71@PURE_QUANTA.Q_RES(CHIPS)':
 C_PATH='@t6g_mb_lib.t6g(sch_1):page244_i71@pure_quanta.q_res(chips)';

PART_NAME
 R1858 'Q_RES_0402LF-1K,1%,1/16W,CHIP,TMP_QCS21002FB24':;

SECTION_NUMBER 1
 '@T6G_MB_LIB.T6G(SCH_1):PAGE244_I70@PURE_QUANTA.Q_RES(CHIPS)':
 C_PATH='@t6g_mb_lib.t6g(sch_1):page244_i70@pure_quanta.q_res(chips)';

PART_NAME
 R1853 'Q_RES_0402LF-1K,1%,1/16W,CHIP,TMP_QCS21002FB24':;

SECTION_NUMBER 1
 '@T6G_MB_LIB.T6G(SCH_1):PAGE244_I69@PURE_QUANTA.Q_RES(CHIPS)':
 C_PATH='@t6g_mb_lib.t6g(sch_1):page244_i69@pure_quanta.q_res(chips)';

PART_NAME
 R1851 'Q_RES_0402LF-10K,1%,1/16W,EMPTY,TMP_QCS31002FB26':;

SECTION_NUMBER 1
 '@T6G_MB_LIB.T6G(SCH_1):PAGE244_I63@PURE_QUANTA.Q_RES(CHIPS)':
 C_PATH='@t6g_mb_lib.t6g(sch_1):page244_i63@pure_quanta.q_res(chips)';

PART_NAME
 R1849 'Q_RES_0402LF-10K,1%,1/16W,CHIP,TMP_QCS31002FB26':;

SECTION_NUMBER 1
 '@T6G_MB_LIB.T6G(SCH_1):PAGE244_I62@PURE_QUANTA.Q_RES(CHIPS)':
 C_PATH='@t6g_mb_lib.t6g(sch_1):page244_i62@pure_quanta.q_res(chips)';

PART_NAME
 R1848 'Q_RES_0402LF-10K,1%,1/16W,CHIP,TMP_QCS31002FB26':;

SECTION_NUMBER 1
 '@T6G_MB_LIB.T6G(SCH_1):PAGE244_I61@PURE_QUANTA.Q_RES(CHIPS)':
 C_PATH='@t6g_mb_lib.t6g(sch_1):page244_i61@pure_quanta.q_res(chips)';

PART_NAME
 R1847 'Q_RES_0402LF-10K,1%,1/16W,CHIP,TMP_QCS31002FB26':;

SECTION_NUMBER 1
 '@T6G_MB_LIB.T6G(SCH_1):PAGE244_I60@PURE_QUANTA.Q_RES(CHIPS)':
 C_PATH='@t6g_mb_lib.t6g(sch_1):page244_i60@pure_quanta.q_res(chips)';

PART_NAME
 R1846 'Q_RES_0402LF-10K,1%,1/16W,CHIP,TMP_QCS31002FB26':;

SECTION_NUMBER 1
 '@T6G_MB_LIB.T6G(SCH_1):PAGE244_I59@PURE_QUANTA.Q_RES(CHIPS)':
 C_PATH='@t6g_mb_lib.t6g(sch_1):page244_i59@pure_quanta.q_res(chips)';

PART_NAME
 R1844 'Q_RES_0402LF-10K,1%,1/16W,CHIP,TMP_QCS31002FB26':;

SECTION_NUMBER 1
 '@T6G_MB_LIB.T6G(SCH_1):PAGE244_I58@PURE_QUANTA.Q_RES(CHIPS)':
 C_PATH='@t6g_mb_lib.t6g(sch_1):page244_i58@pure_quanta.q_res(chips)';

PART_NAME
 R1843 'Q_RES_0402LF-150,1%,1/16W,CHIP,TMP_QCS11502FB21':;

SECTION_NUMBER 1
 '@T6G_MB_LIB.T6G(SCH_1):PAGE244_I57@PURE_QUANTA.Q_RES(CHIPS)':
 C_PATH='@t6g_mb_lib.t6g(sch_1):page244_i57@pure_quanta.q_res(chips)';

PART_NAME
 R1842 'Q_RES_0402LF-150,1%,1/16W,CHIP,TMP_QCS11502FB21':;

SECTION_NUMBER 1
 '@T6G_MB_LIB.T6G(SCH_1):PAGE244_I56@PURE_QUANTA.Q_RES(CHIPS)':
 C_PATH='@t6g_mb_lib.t6g(sch_1):page244_i56@pure_quanta.q_res(chips)';

PART_NAME
 R1836 'Q_RES_0402LF-150,1%,1/16W,CHIP,TMP_QCS11502FB21':;

SECTION_NUMBER 1
 '@T6G_MB_LIB.T6G(SCH_1):PAGE244_I55@PURE_QUANTA.Q_RES(CHIPS)':
 C_PATH='@t6g_mb_lib.t6g(sch_1):page244_i55@pure_quanta.q_res(chips)';

PART_NAME
 R1835 'Q_RES_0402LF-100,1%,1/16W,CHIP,TMP_QCS11002FB22':;

SECTION_NUMBER 1
 '@T6G_MB_LIB.T6G(SCH_1):PAGE244_I53@PURE_QUANTA.Q_RES(CHIPS)':
 C_PATH='@t6g_mb_lib.t6g(sch_1):page244_i53@pure_quanta.q_res(chips)';

PART_NAME
 R1834 'Q_RES_0402LF-100,1%,1/16W,CHIP,TMP_QCS11002FB22':;

SECTION_NUMBER 1
 '@T6G_MB_LIB.T6G(SCH_1):PAGE244_I54@PURE_QUANTA.Q_RES(CHIPS)':
 C_PATH='@t6g_mb_lib.t6g(sch_1):page244_i54@pure_quanta.q_res(chips)';

PART_NAME
 R1825 'Q_RES_0402LF-100,1%,1/16W,CHIP,TMP_QCS11002FB22':;

SECTION_NUMBER 1
 '@T6G_MB_LIB.T6G(SCH_1):PAGE244_I51@PURE_QUANTA.Q_RES(CHIPS)':
 C_PATH='@t6g_mb_lib.t6g(sch_1):page244_i51@pure_quanta.q_res(chips)';

PART_NAME
 R1811 'Q_RES_0402LF-100,1%,1/16W,CHIP,TMP_QCS11002FB22':;

SECTION_NUMBER 1
 '@T6G_MB_LIB.T6G(SCH_1):PAGE244_I52@PURE_QUANTA.Q_RES(CHIPS)':
 C_PATH='@t6g_mb_lib.t6g(sch_1):page244_i52@pure_quanta.q_res(chips)';

PART_NAME
 R1808 'Q_RES_0402LF-100,1%,1/16W,CHIP,TMP_QCS11002FB22':;

SECTION_NUMBER 1
 '@T6G_MB_LIB.T6G(SCH_1):PAGE244_I50@PURE_QUANTA.Q_RES(CHIPS)':
 C_PATH='@t6g_mb_lib.t6g(sch_1):page244_i50@pure_quanta.q_res(chips)';

PART_NAME
 R1807 'Q_RES_0402LF-100,1%,1/16W,CHIP,TMP_QCS11002FB22':;

SECTION_NUMBER 1
 '@T6G_MB_LIB.T6G(SCH_1):PAGE244_I49@PURE_QUANTA.Q_RES(CHIPS)':
 C_PATH='@t6g_mb_lib.t6g(sch_1):page244_i49@pure_quanta.q_res(chips)';

PART_NAME
 R1805 'Q_RES_0402LF-1K,1%,1/16W,CHIP,TMP_QCS21002FB24':;

SECTION_NUMBER 1
 '@T6G_MB_LIB.T6G(SCH_1):PAGE244_I144@PURE_QUANTA.Q_RES(CHIPS)':
 C_PATH='@t6g_mb_lib.t6g(sch_1):page244_i144@pure_quanta.q_res(chips)';

PART_NAME
 R1804 'Q_RES_0402LF-10K,1%,1/16W,CHIP,TMP_QCS31002FB26':;

SECTION_NUMBER 1
 '@T6G_MB_LIB.T6G(SCH_1):PAGE244_I143@PURE_QUANTA.Q_RES(CHIPS)':
 C_PATH='@t6g_mb_lib.t6g(sch_1):page244_i143@pure_quanta.q_res(chips)';

PART_NAME
 R1803 'Q_RES_0402LF-10K,1%,1/16W,CHIP,TMP_QCS31002FB26':;

SECTION_NUMBER 1
 '@T6G_MB_LIB.T6G(SCH_1):PAGE244_I142@PURE_QUANTA.Q_RES(CHIPS)':
 C_PATH='@t6g_mb_lib.t6g(sch_1):page244_i142@pure_quanta.q_res(chips)';

PART_NAME
 R1802 'Q_RES_0402LF-10K,1%,1/16W,CHIP,TMP_QCS31002FB26':;

SECTION_NUMBER 1
 '@T6G_MB_LIB.T6G(SCH_1):PAGE244_I140@PURE_QUANTA.Q_RES(CHIPS)':
 C_PATH='@t6g_mb_lib.t6g(sch_1):page244_i140@pure_quanta.q_res(chips)';

PART_NAME
 R1800 'Q_RES_0402LF-10K,1%,1/16W,CHIP,TMP_QCS31002FB26':;

SECTION_NUMBER 1
 '@T6G_MB_LIB.T6G(SCH_1):PAGE244_I141@PURE_QUANTA.Q_RES(CHIPS)':
 C_PATH='@t6g_mb_lib.t6g(sch_1):page244_i141@pure_quanta.q_res(chips)';

PART_NAME
 R1799 'Q_RES_0402LF-10K,1%,1/16W,CHIP,TMP_QCS31002FB26':;

SECTION_NUMBER 1
 '@T6G_MB_LIB.T6G(SCH_1):PAGE244_I139@PURE_QUANTA.Q_RES(CHIPS)':
 C_PATH='@t6g_mb_lib.t6g(sch_1):page244_i139@pure_quanta.q_res(chips)';

PART_NAME
 R1796 'Q_RES_0402LF-10K,1%,1/16W,CHIP,TMP_QCS31002FB26':;

SECTION_NUMBER 1
 '@T6G_MB_LIB.T6G(SCH_1):PAGE244_I137@PURE_QUANTA.Q_RES(CHIPS)':
 C_PATH='@t6g_mb_lib.t6g(sch_1):page244_i137@pure_quanta.q_res(chips)';

PART_NAME
 R1795 'Q_RES_0402LF-10K,1%,1/16W,CHIP,TMP_QCS31002FB26':;

SECTION_NUMBER 1
 '@T6G_MB_LIB.T6G(SCH_1):PAGE244_I136@PURE_QUANTA.Q_RES(CHIPS)':
 C_PATH='@t6g_mb_lib.t6g(sch_1):page244_i136@pure_quanta.q_res(chips)';

PART_NAME
 R1794 'Q_RES_0402LF-10K,1%,1/16W,CHIP,TMP_QCS31002FB26':;

SECTION_NUMBER 1
 '@T6G_MB_LIB.T6G(SCH_1):PAGE244_I121@PURE_QUANTA.Q_RES(CHIPS)':
 C_PATH='@t6g_mb_lib.t6g(sch_1):page244_i121@pure_quanta.q_res(chips)';

PART_NAME
 R1793 'Q_RES_0402LF-10K,1%,1/16W,CHIP,TMP_QCS31002FB26':;

SECTION_NUMBER 1
 '@T6G_MB_LIB.T6G(SCH_1):PAGE244_I120@PURE_QUANTA.Q_RES(CHIPS)':
 C_PATH='@t6g_mb_lib.t6g(sch_1):page244_i120@pure_quanta.q_res(chips)';

PART_NAME
 R1792 'Q_RES_0402LF-10K,1%,1/16W,CHIP,TMP_QCS31002FB26':;

SECTION_NUMBER 1
 '@T6G_MB_LIB.T6G(SCH_1):PAGE244_I119@PURE_QUANTA.Q_RES(CHIPS)':
 C_PATH='@t6g_mb_lib.t6g(sch_1):page244_i119@pure_quanta.q_res(chips)';

PART_NAME
 R1791 'Q_RES_0402LF-1K,1%,1/16W,EMPTY,TMP_QCS21002FB24':;

SECTION_NUMBER 1
 '@T6G_MB_LIB.T6G(SCH_1):PAGE244_I147@PURE_QUANTA.Q_RES(CHIPS)':
 C_PATH='@t6g_mb_lib.t6g(sch_1):page244_i147@pure_quanta.q_res(chips)';

PART_NAME
 R1790 'Q_RES_0402LF-10K,1%,1/16W,CHIP,TMP_QCS31002FB26':;

SECTION_NUMBER 1
 '@T6G_MB_LIB.T6G(SCH_1):PAGE244_I145@PURE_QUANTA.Q_RES(CHIPS)':
 C_PATH='@t6g_mb_lib.t6g(sch_1):page244_i145@pure_quanta.q_res(chips)';

PART_NAME
 R1742 'Q_RES_0402LF-10K,1%,1/16W,EMPTY,TMP_QCS31002FB26':;

SECTION_NUMBER 1
 '@T6G_MB_LIB.T6G(SCH_1):PAGE244_I95@PURE_QUANTA.Q_RES(CHIPS)':
 C_PATH='@t6g_mb_lib.t6g(sch_1):page244_i95@pure_quanta.q_res(chips)';

PART_NAME
 R1741 'Q_RES_0402LF-1K,1%,1/16W,CHIP,TMP_QCS21002FB24':;

SECTION_NUMBER 1
 '@T6G_MB_LIB.T6G(SCH_1):PAGE244_I68@PURE_QUANTA.Q_RES(CHIPS)':
 C_PATH='@t6g_mb_lib.t6g(sch_1):page244_i68@pure_quanta.q_res(chips)';

PART_NAME
 R1489 'Q_RES_0402LF-10K,1%,1/16W,CHIP,TMP_QCS31002FB26':;

SECTION_NUMBER 1
 '@T6G_MB_LIB.T6G(SCH_1):PAGE244_I138@PURE_QUANTA.Q_RES(CHIPS)':
 C_PATH='@t6g_mb_lib.t6g(sch_1):page244_i138@pure_quanta.q_res(chips)';

PART_NAME
 R1389 'Q_RES_0402LF-2K,1%,1/16W,CHIP,TMP_QCS22002FB19':;

SECTION_NUMBER 1
 '@T6G_MB_LIB.T6G(SCH_1):PAGE244_I16@PURE_QUANTA.Q_RES(CHIPS)':
 C_PATH='@t6g_mb_lib.t6g(sch_1):page244_i16@pure_quanta.q_res(chips)';

PART_NAME
 R1388 'Q_RES_0402LF-2K,1%,1/16W,CHIP,TMP_QCS22002FB19':;

SECTION_NUMBER 1
 '@T6G_MB_LIB.T6G(SCH_1):PAGE244_I14@PURE_QUANTA.Q_RES(CHIPS)':
 C_PATH='@t6g_mb_lib.t6g(sch_1):page244_i14@pure_quanta.q_res(chips)';

PART_NAME
 R922 'Q_RES_0402LF-10K,1%,1/16W,CHIP,TMP_QCS31002FB26':;

SECTION_NUMBER 1
 '@T6G_MB_LIB.T6G(SCH_1):PAGE244_I118@PURE_QUANTA.Q_RES(CHIPS)':
 C_PATH='@t6g_mb_lib.t6g(sch_1):page244_i118@pure_quanta.q_res(chips)';

PART_NAME
 R921 'Q_RES_0402LF-10K,1%,1/16W,CHIP,TMP_QCS31002FB26':;

SECTION_NUMBER 1
 '@T6G_MB_LIB.T6G(SCH_1):PAGE244_I117@PURE_QUANTA.Q_RES(CHIPS)':
 C_PATH='@t6g_mb_lib.t6g(sch_1):page244_i117@pure_quanta.q_res(chips)';

PART_NAME
 R397 'Q_RES_0402LF-10K,1%,1/16W,CHIP,TMP_QCS31002FB26':;

SECTION_NUMBER 1
 '@T6G_MB_LIB.T6G(SCH_1):PAGE244_I101@PURE_QUANTA.Q_RES(CHIPS)':
 C_PATH='@t6g_mb_lib.t6g(sch_1):page244_i101@pure_quanta.q_res(chips)';

PART_NAME
 R393 'Q_RES_0402LF-1K,1%,1/16W,EMPTY,TMP_QCS21002FB24':;

SECTION_NUMBER 1
 '@T6G_MB_LIB.T6G(SCH_1):PAGE244_I94@PURE_QUANTA.Q_RES(CHIPS)':
 C_PATH='@t6g_mb_lib.t6g(sch_1):page244_i94@pure_quanta.q_res(chips)';

PART_NAME
 R141 'Q_RES_0402LF-10K,1%,1/16W,EMPTY,TMP_QCS31002FB26':;

SECTION_NUMBER 1
 '@T6G_MB_LIB.T6G(SCH_1):PAGE244_I67@PURE_QUANTA.Q_RES(CHIPS)':
 C_PATH='@t6g_mb_lib.t6g(sch_1):page244_i67@pure_quanta.q_res(chips)';

PART_NAME
 R140 'Q_RES_0402LF-10K,1%,1/16W,EMPTY,TMP_QCS31002FB26':;

SECTION_NUMBER 1
 '@T6G_MB_LIB.T6G(SCH_1):PAGE244_I66@PURE_QUANTA.Q_RES(CHIPS)':
 C_PATH='@t6g_mb_lib.t6g(sch_1):page244_i66@pure_quanta.q_res(chips)';

PART_NAME
 R139 'Q_RES_0402LF-10K,1%,1/16W,CHIP,TMP_QCS31002FB26':;

SECTION_NUMBER 1
 '@T6G_MB_LIB.T6G(SCH_1):PAGE244_I65@PURE_QUANTA.Q_RES(CHIPS)':
 C_PATH='@t6g_mb_lib.t6g(sch_1):page244_i65@pure_quanta.q_res(chips)';

PART_NAME
 C2418 'Q_CAP_0402-100PF,50V,5%,X7R,CH11006JB18':;

SECTION_NUMBER 1
 '@T6G_MB_LIB.T6G(SCH_1):PAGE244_I170@PURE_QUANTA.Q_CAP(CHIPS)':
 C_PATH='@t6g_mb_lib.t6g(sch_1):page244_i170@pure_quanta.q_cap(chips)';

PART_NAME
 C2417 'Q_CAP_0402-100PF,50V,5%,X7R,CH11006JB18':;

SECTION_NUMBER 1
 '@T6G_MB_LIB.T6G(SCH_1):PAGE244_I171@PURE_QUANTA.Q_CAP(CHIPS)':
 C_PATH='@t6g_mb_lib.t6g(sch_1):page244_i171@pure_quanta.q_cap(chips)';

PART_NAME
 U196 'SN74LVC1G3157DCKR-SN74LVC1G3157DCKR,SMLF,IC,AL1G3157001':;

SECTION_NUMBER 1
 '@T6G_MB_LIB.T6G(SCH_1):PAGE257_I47@PURE_QUANTA.SN74LVC1G3157DCKR(CHIPS)':
 C_PATH='@s6q_mb_lib.s6q(sch_1):page257_i47@pure_quanta.sn74lvc1g3157dckr(chips)~
';

PART_NAME
 U192 'SN74LVC1G17DCKR-SN74LVC1G17DCKR,SMLF,IC,AL1G0017003':;

SECTION_NUMBER 1
 '@T6G_MB_LIB.T6G(SCH_1):PAGE257_I25@PURE_QUANTA.SN74LVC1G17DCKR(CHIPS)':
 C_PATH='@t6g_mb_lib.t6g(sch_1):page257_i25@pure_quanta.sn74lvc1g17dckr(chips)';

PART_NAME
 U78 '74LVC1G07GW-74LVC1G07GW,SMLF,IC,ALVC1G07002':;

SECTION_NUMBER 1
 '@T6G_MB_LIB.T6G(SCH_1):PAGE257_I39@PURE_QUANTA.74LVC1G07GW(CHIPS)':
 C_PATH='@t6g_mb_lib.t6g(sch_1):page257_i39@pure_quanta.\74lvc1g07gw\(chips)';

PART_NAME
 U19 'SN74LVC1G17DCKR-SN74LVC1G17DCKR,SMLF,IC,AL1G0017003':;

SECTION_NUMBER 1
 '@T6G_MB_LIB.T6G(SCH_1):PAGE257_I8@PURE_QUANTA.SN74LVC1G17DCKR(CHIPS)':
 C_PATH='@t6g_mb_lib.t6g(sch_1):page257_i8@pure_quanta.sn74lvc1g17dckr(chips)';

PART_NAME
 SW8 'SW6S_TBEGNQTR-SW6S_TBEG-N-Q-T/R,SMLF,MECH,DHP00TBEG00':;

SECTION_NUMBER 1
 '@T6G_MB_LIB.T6G(SCH_1):PAGE257_I37@PURE_QUANTA.SW6S_TBEGNQTR(CHIPS)':
 C_PATH='@t6g_mb_lib.t6g(sch_1):page257_i37@pure_quanta.sw6s_tbegnqtr(chips)';

PART_NAME
 SW7 'SW6S_TBEGNQTR-SW6S_TBEG-N-Q-T/R,SMLF,MECH,DHP00TBEG00':;

SECTION_NUMBER 1
 '@T6G_MB_LIB.T6G(SCH_1):PAGE257_I20@PURE_QUANTA.SW6S_TBEGNQTR(CHIPS)':
 C_PATH='@t6g_mb_lib.t6g(sch_1):page257_i20@pure_quanta.sw6s_tbegnqtr(chips)';

PART_NAME
 R3766 'Q_RES_0402LF-4.7K,5%,1/16W,CHIP,TMP_QCS24702JB38':;

SECTION_NUMBER 1
 '@T6G_MB_LIB.T6G(SCH_1):PAGE257_I53@PURE_QUANTA.Q_RES(CHIPS)':
 C_PATH='@t6g_mb_lib.t6g(sch_1):page257_i53@pure_quanta.q_res(chips)';

PART_NAME
 R3526 'Q_RES_0402LF-33,5%,1/16W,CHIP,CS03302JB29':;

SECTION_NUMBER 1
 '@T6G_MB_LIB.T6G(SCH_1):PAGE257_I7@PURE_QUANTA.Q_RES(CHIPS)':
 C_PATH='@t6g_mb_lib.t6g(sch_1):page257_i7@pure_quanta.q_res(chips)';

PART_NAME
 R3525 'Q_RES_0402LF-33,5%,1/16W,CHIP,CS03302JB29':;

SECTION_NUMBER 1
 '@T6G_MB_LIB.T6G(SCH_1):PAGE257_I27@PURE_QUANTA.Q_RES(CHIPS)':
 C_PATH='@t6g_mb_lib.t6g(sch_1):page257_i27@pure_quanta.q_res(chips)';

PART_NAME
 R3524 'Q_RES_0402LF-0,5%,1/16W,EMPTY,CS00002JB38':;

SECTION_NUMBER 1
 '@T6G_MB_LIB.T6G(SCH_1):PAGE257_I15@PURE_QUANTA.Q_RES(CHIPS)':
 C_PATH='@t6g_mb_lib.t6g(sch_1):page257_i15@pure_quanta.q_res(chips)';

PART_NAME
 R3523 'Q_RES_0402LF-1K,5%,1/16W,CHIP,TMP_QCS21002JB34':;

SECTION_NUMBER 1
 '@T6G_MB_LIB.T6G(SCH_1):PAGE257_I35@PURE_QUANTA.Q_RES(CHIPS)':
 C_PATH='@t6g_mb_lib.t6g(sch_1):page257_i35@pure_quanta.q_res(chips)';

PART_NAME
 R3522 'Q_RES_0402LF-1K,5%,1/16W,CHIP,TMP_QCS21002JB34':;

SECTION_NUMBER 1
 '@T6G_MB_LIB.T6G(SCH_1):PAGE257_I16@PURE_QUANTA.Q_RES(CHIPS)':
 C_PATH='@t6g_mb_lib.t6g(sch_1):page257_i16@pure_quanta.q_res(chips)';

PART_NAME
 R3521 'Q_RES_0402LF-4.7K,5%,1/16W,CHIP,TMP_QCS24702JB38':;

SECTION_NUMBER 1
 '@T6G_MB_LIB.T6G(SCH_1):PAGE257_I36@PURE_QUANTA.Q_RES(CHIPS)':
 C_PATH='@t6g_mb_lib.t6g(sch_1):page257_i36@pure_quanta.q_res(chips)';

PART_NAME
 R3520 'Q_RES_0402LF-4.7K,5%,1/16W,CHIP,TMP_QCS24702JB38':;

SECTION_NUMBER 1
 '@T6G_MB_LIB.T6G(SCH_1):PAGE257_I18@PURE_QUANTA.Q_RES(CHIPS)':
 C_PATH='@t6g_mb_lib.t6g(sch_1):page257_i18@pure_quanta.q_res(chips)';

PART_NAME
 C2924 'Q_CAP_0402-0.1UF,25V,10%,X7R,CH4104K1B00':;

SECTION_NUMBER 1
 '@T6G_MB_LIB.T6G(SCH_1):PAGE257_I55@PURE_QUANTA.Q_CAP(CHIPS)':
 C_PATH='@t6g_mb_lib.t6g(sch_1):page257_i55@pure_quanta.q_cap(chips)';

PART_NAME
 C2823 'Q_CAP_0402-0.1UF,25V,10%,X7R,CH4104K1B00':;

SECTION_NUMBER 1
 '@T6G_MB_LIB.T6G(SCH_1):PAGE257_I29@PURE_QUANTA.Q_CAP(CHIPS)':
 C_PATH='@t6g_mb_lib.t6g(sch_1):page257_i29@pure_quanta.q_cap(chips)';

PART_NAME
 C2822 'Q_CAP_0402-0.1UF,25V,10%,X7R,CH4104K1B00':;

SECTION_NUMBER 1
 '@T6G_MB_LIB.T6G(SCH_1):PAGE257_I10@PURE_QUANTA.Q_CAP(CHIPS)':
 C_PATH='@t6g_mb_lib.t6g(sch_1):page257_i10@pure_quanta.q_cap(chips)';

PART_NAME
 C2821 'Q_CAP_0402-0.1UF,25V,10%,X7R,CH4104K1B00':;

SECTION_NUMBER 1
 '@T6G_MB_LIB.T6G(SCH_1):PAGE257_I32@PURE_QUANTA.Q_CAP(CHIPS)':
 C_PATH='@t6g_mb_lib.t6g(sch_1):page257_i32@pure_quanta.q_cap(chips)';

PART_NAME
 C2820 'Q_CAP_0402-0.1UF,25V,10%,X7R,CH4104K1B00':;

SECTION_NUMBER 1
 '@T6G_MB_LIB.T6G(SCH_1):PAGE257_I13@PURE_QUANTA.Q_CAP(CHIPS)':
 C_PATH='@t6g_mb_lib.t6g(sch_1):page257_i13@pure_quanta.q_cap(chips)';

PART_NAME
 C1686 'Q_CAP_0402-0.1UF,25V,10%,X7R,CH4104K1B00':;

SECTION_NUMBER 1
 '@T6G_MB_LIB.T6G(SCH_1):PAGE257_I42@PURE_QUANTA.Q_CAP(CHIPS)':
 C_PATH='@t6g_mb_lib.t6g(sch_1):page257_i42@pure_quanta.q_cap(chips)';

PART_NAME
 R2490 'Q_RES_0402LF-0,5%,1/16W,EMPTY,CS00002JB13':
;

SECTION_NUMBER 1
 '@T6G_MB_LIB.T6G(SCH_1):PAGE87_I72@PURE_QUANTA.Q_RES(CHIPS)':
 C_PATH='@t6g_mb_lib.t6g(sch_1):page87_i72@pure_quanta.q_res(chips)';

PART_NAME
 R2489 'Q_RES_0402LF-0,5%,1/16W,EMPTY,CS00002JB13':
;

SECTION_NUMBER 1
 '@T6G_MB_LIB.T6G(SCH_1):PAGE87_I64@PURE_QUANTA.Q_RES(CHIPS)':
 C_PATH='@t6g_mb_lib.t6g(sch_1):page87_i64@pure_quanta.q_res(chips)';

PART_NAME
 R2472 'Q_RES_0402LF-10K,1%,1/16W,CHIP,CS31002FB08':
;

SECTION_NUMBER 1
 '@T6G_MB_LIB.T6G(SCH_1):PAGE87_I38@PURE_QUANTA.Q_RES(CHIPS)':
 C_PATH='@t6g_mb_lib.t6g(sch_1):page87_i38@pure_quanta.q_res(chips)';

PART_NAME
 R2469 'Q_RES_0402LF-1K,0.1%,1/16W,CHIP,CS21002BB05':
;

SECTION_NUMBER 1
 '@T6G_MB_LIB.T6G(SCH_1):PAGE87_I58@PURE_QUANTA.Q_RES(CHIPS)':
 C_PATH='@t6g_mb_lib.t6g(sch_1):page87_i58@pure_quanta.q_res(chips)';

PART_NAME
 R2430 'Q_RES_0402LF-0,5%,1/16W,EMPTY,CS00002JB13':
;

SECTION_NUMBER 1
 '@T6G_MB_LIB.T6G(SCH_1):PAGE87_I74@PURE_QUANTA.Q_RES(CHIPS)':
 C_PATH='@t6g_mb_lib.t6g(sch_1):page87_i74@pure_quanta.q_res(chips)';

PART_NAME
 R2426 'Q_RES_0402LF-0,5%,1/16W,CHIP,CS00002JB13':
;

SECTION_NUMBER 1
 '@T6G_MB_LIB.T6G(SCH_1):PAGE87_I41@PURE_QUANTA.Q_RES(CHIPS)':
 C_PATH='@t6g_mb_lib.t6g(sch_1):page87_i41@pure_quanta.q_res(chips)';

PART_NAME
 R2425 'Q_RES_0402LF-0,5%,1/16W,EMPTY,CS00002JB13':
;

SECTION_NUMBER 1
 '@T6G_MB_LIB.T6G(SCH_1):PAGE87_I44@PURE_QUANTA.Q_RES(CHIPS)':
 C_PATH='@t6g_mb_lib.t6g(sch_1):page87_i44@pure_quanta.q_res(chips)';

PART_NAME
 R2424 'Q_RES_0402LF-0,5%,1/16W,EMPTY,CS00002JB13':
;

SECTION_NUMBER 1
 '@T6G_MB_LIB.T6G(SCH_1):PAGE87_I25@PURE_QUANTA.Q_RES(CHIPS)':
 C_PATH='@t6g_mb_lib.t6g(sch_1):page87_i25@pure_quanta.q_res(chips)';

PART_NAME
 R2422 'Q_RES_0402LF-0,5%,1/16W,EMPTY,CS00002JB13':
;

SECTION_NUMBER 1
 '@T6G_MB_LIB.T6G(SCH_1):PAGE87_I40@PURE_QUANTA.Q_RES(CHIPS)':
 C_PATH='@t6g_mb_lib.t6g(sch_1):page87_i40@pure_quanta.q_res(chips)';

PART_NAME
 R2421 'Q_RES_0402LF-0,5%,1/16W,EMPTY,CS00002JB13':
;

SECTION_NUMBER 1
 '@T6G_MB_LIB.T6G(SCH_1):PAGE87_I7@PURE_QUANTA.Q_RES(CHIPS)':
 C_PATH='@t6g_mb_lib.t6g(sch_1):page87_i7@pure_quanta.q_res(chips)';

PART_NAME
 R2420 'Q_RES_0402LF-1K,0.1%,1/16W,CHIP,CS21002BB05':
;

SECTION_NUMBER 1
 '@T6G_MB_LIB.T6G(SCH_1):PAGE87_I52@PURE_QUANTA.Q_RES(CHIPS)':
 C_PATH='@t6g_mb_lib.t6g(sch_1):page87_i52@pure_quanta.q_res(chips)';

PART_NAME
 R2417 'Q_RES_0402LF-1K,0.1%,1/16W,CHIP,CS21002BB05':
;

SECTION_NUMBER 1
 '@T6G_MB_LIB.T6G(SCH_1):PAGE87_I18@PURE_QUANTA.Q_RES(CHIPS)':
 C_PATH='@t6g_mb_lib.t6g(sch_1):page87_i18@pure_quanta.q_res(chips)';

PART_NAME
 R2413 'Q_RES_0402LF-0,5%,1/16W,EMPTY,CS00002JB13':
;

SECTION_NUMBER 1
 '@T6G_MB_LIB.T6G(SCH_1):PAGE87_I14@PURE_QUANTA.Q_RES(CHIPS)':
 C_PATH='@t6g_mb_lib.t6g(sch_1):page87_i14@pure_quanta.q_res(chips)';

PART_NAME
 R2371 'Q_RES_0402LF-0,5%,1/16W,CHIP,CS00002JB13':
;

SECTION_NUMBER 1
 '@T6G_MB_LIB.T6G(SCH_1):PAGE87_I24@PURE_QUANTA.Q_RES(CHIPS)':
 C_PATH='@t6g_mb_lib.t6g(sch_1):page87_i24@pure_quanta.q_res(chips)';

PART_NAME
 R2370 'Q_RES_0402LF-0,5%,1/16W,CHIP,CS00002JB13':
;

SECTION_NUMBER 1
 '@T6G_MB_LIB.T6G(SCH_1):PAGE87_I6@PURE_QUANTA.Q_RES(CHIPS)':
 C_PATH='@t6g_mb_lib.t6g(sch_1):page87_i6@pure_quanta.q_res(chips)';

PART_NAME
 R2369 'Q_RES_0402LF-0,5%,1/16W,CHIP,CS00002JB13':
;

SECTION_NUMBER 1
 '@T6G_MB_LIB.T6G(SCH_1):PAGE87_I13@PURE_QUANTA.Q_RES(CHIPS)':
 C_PATH='@t6g_mb_lib.t6g(sch_1):page87_i13@pure_quanta.q_res(chips)';

PART_NAME
 R2297 'Q_RES_0402LF-1K,0.1%,1/16W,CHIP,CS21002BB05':
;

SECTION_NUMBER 1
 '@T6G_MB_LIB.T6G(SCH_1):PAGE87_I70@PURE_QUANTA.Q_RES(CHIPS)':
 C_PATH='@t6g_mb_lib.t6g(sch_1):page87_i70@pure_quanta.q_res(chips)';

PART_NAME
 R2296 'Q_RES_0402LF-1K,0.1%,1/16W,CHIP,CS21002BB05':
;

SECTION_NUMBER 1
 '@T6G_MB_LIB.T6G(SCH_1):PAGE87_I62@PURE_QUANTA.Q_RES(CHIPS)':
 C_PATH='@t6g_mb_lib.t6g(sch_1):page87_i62@pure_quanta.q_res(chips)';

PART_NAME
 R2295 'Q_RES_0402LF-10K,1%,1/16W,CHIP,CS31002FB08':
;

SECTION_NUMBER 1
 '@T6G_MB_LIB.T6G(SCH_1):PAGE87_I23@PURE_QUANTA.Q_RES(CHIPS)':
 C_PATH='@t6g_mb_lib.t6g(sch_1):page87_i23@pure_quanta.q_res(chips)';

PART_NAME
 R2292 'Q_RES_0402LF-1K,0.1%,1/16W,CHIP,CS21002BB05':
;

SECTION_NUMBER 1
 '@T6G_MB_LIB.T6G(SCH_1):PAGE87_I48@PURE_QUANTA.Q_RES(CHIPS)':
 C_PATH='@t6g_mb_lib.t6g(sch_1):page87_i48@pure_quanta.q_res(chips)';

PART_NAME
 R2291 'Q_RES_0402LF-1K,0.1%,1/16W,CHIP,CS21002BB05':
;

SECTION_NUMBER 1
 '@T6G_MB_LIB.T6G(SCH_1):PAGE87_I33@PURE_QUANTA.Q_RES(CHIPS)':
 C_PATH='@t6g_mb_lib.t6g(sch_1):page87_i33@pure_quanta.q_res(chips)';

PART_NAME
 R2290 'Q_RES_0402LF-1K,0.1%,1/16W,CHIP,CS21002BB05':
;

SECTION_NUMBER 1
 '@T6G_MB_LIB.T6G(SCH_1):PAGE87_I32@PURE_QUANTA.Q_RES(CHIPS)':
 C_PATH='@t6g_mb_lib.t6g(sch_1):page87_i32@pure_quanta.q_res(chips)';

PART_NAME
 R2289 'Q_RES_0402LF-10K,1%,1/16W,CHIP,CS31002FB08':
;

SECTION_NUMBER 1
 '@T6G_MB_LIB.T6G(SCH_1):PAGE87_I5@PURE_QUANTA.Q_RES(CHIPS)':
 C_PATH='@t6g_mb_lib.t6g(sch_1):page87_i5@pure_quanta.q_res(chips)';

PART_NAME
 R2287 'Q_RES_0402LF-10K,1%,1/16W,CHIP,CS31002FB08':
;

SECTION_NUMBER 1
 '@T6G_MB_LIB.T6G(SCH_1):PAGE87_I11@PURE_QUANTA.Q_RES(CHIPS)':
 C_PATH='@t6g_mb_lib.t6g(sch_1):page87_i11@pure_quanta.q_res(chips)';

PART_NAME
 Q38 'MOSFET_NCH_DUAL-NTJD4001NT1G,SMLF,IC,BAM40010011':;

SECTION_NUMBER 1
 '@T6G_MB_LIB.T6G(SCH_1):PAGE87_I81@PURE_QUANTA.MOSFET_NCH_DUAL(CHIPS)':
 C_PATH='@t6g_mb_lib.t6g(sch_1):page87_i81@pure_quanta.mosfet_nch_dual(chips)';

SECTION_NUMBER 2
 '@T6G_MB_LIB.T6G(SCH_1):PAGE87_I82@PURE_QUANTA.MOSFET_NCH_DUAL(CHIPS)':
 C_PATH='@t6g_mb_lib.t6g(sch_1):page87_i82@pure_quanta.mosfet_nch_dual(chips)';

PART_NAME
 Q37 'MOSFET_NCH_DUAL-NTJD4001NT1G,SMLF,IC,BAM40010011':;

SECTION_NUMBER 1
 '@T6G_MB_LIB.T6G(SCH_1):PAGE87_I77@PURE_QUANTA.MOSFET_NCH_DUAL(CHIPS)':
 C_PATH='@t6g_mb_lib.t6g(sch_1):page87_i77@pure_quanta.mosfet_nch_dual(chips)';

SECTION_NUMBER 2
 '@T6G_MB_LIB.T6G(SCH_1):PAGE87_I78@PURE_QUANTA.MOSFET_NCH_DUAL(CHIPS)':
 C_PATH='@t6g_mb_lib.t6g(sch_1):page87_i78@pure_quanta.mosfet_nch_dual(chips)';

PART_NAME
 Q36 'MOSFET_NCH_DUAL-NTJD4001NT1G,SMLF,IC,BAM40010011':;

SECTION_NUMBER 1
 '@T6G_MB_LIB.T6G(SCH_1):PAGE87_I79@PURE_QUANTA.MOSFET_NCH_DUAL(CHIPS)':
 C_PATH='@t6g_mb_lib.t6g(sch_1):page87_i79@pure_quanta.mosfet_nch_dual(chips)';

SECTION_NUMBER 2
 '@T6G_MB_LIB.T6G(SCH_1):PAGE87_I80@PURE_QUANTA.MOSFET_NCH_DUAL(CHIPS)':
 C_PATH='@t6g_mb_lib.t6g(sch_1):page87_i80@pure_quanta.mosfet_nch_dual(chips)';

PART_NAME
 Q35 'MOSFET_NCH_DUAL-NTJD4001NT1G,SMLF,IC,BAM40010011':;

SECTION_NUMBER 1
 '@T6G_MB_LIB.T6G(SCH_1):PAGE87_I83@PURE_QUANTA.MOSFET_NCH_DUAL(CHIPS)':
 C_PATH='@t6g_mb_lib.t6g(sch_1):page87_i83@pure_quanta.mosfet_nch_dual(chips)';

SECTION_NUMBER 2
 '@T6G_MB_LIB.T6G(SCH_1):PAGE87_I84@PURE_QUANTA.MOSFET_NCH_DUAL(CHIPS)':
 C_PATH='@t6g_mb_lib.t6g(sch_1):page87_i84@pure_quanta.mosfet_nch_dual(chips)';

PART_NAME
 C1980 'Q_CAP_C0402-1UF,6.3V,10%,EMPTY,CH5101KEB00':
;

SECTION_NUMBER 1
 '@T6G_MB_LIB.T6G(SCH_1):PAGE87_I71@PURE_QUANTA.Q_CAP(CHIPS)':
 C_PATH='@t6g_mb_lib.t6g(sch_1):page87_i71@pure_quanta.q_cap(chips)';

PART_NAME
 C1979 'Q_CAP_C0402-1UF,6.3V,10%,EMPTY,CH5101KEB00':
;

SECTION_NUMBER 1
 '@T6G_MB_LIB.T6G(SCH_1):PAGE87_I37@PURE_QUANTA.Q_CAP(CHIPS)':
 C_PATH='@t6g_mb_lib.t6g(sch_1):page87_i37@pure_quanta.q_cap(chips)';

PART_NAME
 C1978 'Q_CAP_C0402-1UF,6.3V,10%,EMPTY,CH5101KEB00':
;

SECTION_NUMBER 1
 '@T6G_MB_LIB.T6G(SCH_1):PAGE87_I21@PURE_QUANTA.Q_CAP(CHIPS)':
 C_PATH='@t6g_mb_lib.t6g(sch_1):page87_i21@pure_quanta.q_cap(chips)';

PART_NAME
 C1977 'Q_CAP_C0402-1UF,6.3V,10%,EMPTY,CH5101KEB00':
;

SECTION_NUMBER 1
 '@T6G_MB_LIB.T6G(SCH_1):PAGE87_I46@PURE_QUANTA.Q_CAP(CHIPS)':
 C_PATH='@t6g_mb_lib.t6g(sch_1):page87_i46@pure_quanta.q_cap(chips)';

PART_NAME
 C1976 'Q_CAP_C0402-1UF,6.3V,10%,EMPTY,CH5101KEB00':
;

SECTION_NUMBER 1
 '@T6G_MB_LIB.T6G(SCH_1):PAGE87_I28@PURE_QUANTA.Q_CAP(CHIPS)':
 C_PATH='@t6g_mb_lib.t6g(sch_1):page87_i28@pure_quanta.q_cap(chips)';

PART_NAME
 C1975 'Q_CAP_C0402-1UF,6.3V,10%,EMPTY,CH5101KEB00':
;

SECTION_NUMBER 1
 '@T6G_MB_LIB.T6G(SCH_1):PAGE87_I4@PURE_QUANTA.Q_CAP(CHIPS)':
 C_PATH='@t6g_mb_lib.t6g(sch_1):page87_i4@pure_quanta.q_cap(chips)';

PART_NAME
 C1974 'Q_CAP_C0402-1UF,6.3V,10%,EMPTY,CH5101KEB00':
;

SECTION_NUMBER 1
 '@T6G_MB_LIB.T6G(SCH_1):PAGE87_I9@PURE_QUANTA.Q_CAP(CHIPS)':
 C_PATH='@t6g_mb_lib.t6g(sch_1):page87_i9@pure_quanta.q_cap(chips)';

PART_NAME
 C1584 'Q_CAP_C0402-1UF,6.3V,10%,EMPTY,CH5101KEB00':
;

SECTION_NUMBER 1
 '@T6G_MB_LIB.T6G(SCH_1):PAGE87_I63@PURE_QUANTA.Q_CAP(CHIPS)':
 C_PATH='@t6g_mb_lib.t6g(sch_1):page87_i63@pure_quanta.q_cap(chips)';

PART_NAME
 R2858 'Q_RES_0402LF-1K,0.1%,1/16W,CHIP,CS21002BB05':
;

SECTION_NUMBER 1
 '@T6G_MB_LIB.T6G(SCH_1):PAGE86_I70@PURE_QUANTA.Q_RES(CHIPS)':
 C_PATH='@t6g_mb_lib.t6g(sch_1):page86_i70@pure_quanta.q_res(chips)';

PART_NAME
 R2857 'Q_RES_0402LF-1K,0.1%,1/16W,CHIP,CS21002BB05':
;

SECTION_NUMBER 1
 '@T6G_MB_LIB.T6G(SCH_1):PAGE86_I56@PURE_QUANTA.Q_RES(CHIPS)':
 C_PATH='@t6g_mb_lib.t6g(sch_1):page86_i56@pure_quanta.q_res(chips)';

PART_NAME
 R2856 'Q_RES_0402LF-1K,0.1%,1/16W,CHIP,CS21002BB05':
;

SECTION_NUMBER 1
 '@T6G_MB_LIB.T6G(SCH_1):PAGE86_I52@PURE_QUANTA.Q_RES(CHIPS)':
 C_PATH='@t6g_mb_lib.t6g(sch_1):page86_i52@pure_quanta.q_res(chips)';

PART_NAME
 R2855 'Q_RES_0402LF-1K,0.1%,1/16W,CHIP,CS21002BB05':
;

SECTION_NUMBER 1
 '@T6G_MB_LIB.T6G(SCH_1):PAGE86_I61@PURE_QUANTA.Q_RES(CHIPS)':
 C_PATH='@t6g_mb_lib.t6g(sch_1):page86_i61@pure_quanta.q_res(chips)';

PART_NAME
 R2852 'Q_RES_0402LF-10K,1%,1/16W,CHIP,CS31002FB08':
;

SECTION_NUMBER 1
 '@T6G_MB_LIB.T6G(SCH_1):PAGE86_I24@PURE_QUANTA.Q_RES(CHIPS)':
 C_PATH='@t6g_mb_lib.t6g(sch_1):page86_i24@pure_quanta.q_res(chips)';

PART_NAME
 R2851 'Q_RES_0402LF-10K,1%,1/16W,CHIP,CS31002FB08':
;

SECTION_NUMBER 1
 '@T6G_MB_LIB.T6G(SCH_1):PAGE86_I39@PURE_QUANTA.Q_RES(CHIPS)':
 C_PATH='@t6g_mb_lib.t6g(sch_1):page86_i39@pure_quanta.q_res(chips)';

PART_NAME
 R2464 'Q_RES_0402LF-1K,0.1%,1/16W,CHIP,CS21002BB05':
;

SECTION_NUMBER 1
 '@T6G_MB_LIB.T6G(SCH_1):PAGE86_I48@PURE_QUANTA.Q_RES(CHIPS)':
 C_PATH='@t6g_mb_lib.t6g(sch_1):page86_i48@pure_quanta.q_res(chips)';

PART_NAME
 R2463 'Q_RES_0402LF-1K,0.1%,1/16W,CHIP,CS21002BB05':
;

SECTION_NUMBER 1
 '@T6G_MB_LIB.T6G(SCH_1):PAGE86_I30@PURE_QUANTA.Q_RES(CHIPS)':
 C_PATH='@t6g_mb_lib.t6g(sch_1):page86_i30@pure_quanta.q_res(chips)';

PART_NAME
 R2462 'Q_RES_0402LF-1K,0.1%,1/16W,CHIP,CS21002BB05':
;

SECTION_NUMBER 1
 '@T6G_MB_LIB.T6G(SCH_1):PAGE86_I18@PURE_QUANTA.Q_RES(CHIPS)':
 C_PATH='@t6g_mb_lib.t6g(sch_1):page86_i18@pure_quanta.q_res(chips)';

PART_NAME
 R2461 'Q_RES_0402LF-1K,0.1%,1/16W,CHIP,CS21002BB05':
;

SECTION_NUMBER 1
 '@T6G_MB_LIB.T6G(SCH_1):PAGE86_I37@PURE_QUANTA.Q_RES(CHIPS)':
 C_PATH='@t6g_mb_lib.t6g(sch_1):page86_i37@pure_quanta.q_res(chips)';

PART_NAME
 R2415 'Q_RES_0402LF-10K,1%,1/16W,CHIP,CS31002FB08':
;

SECTION_NUMBER 1
 '@T6G_MB_LIB.T6G(SCH_1):PAGE86_I5@PURE_QUANTA.Q_RES(CHIPS)':
 C_PATH='@t6g_mb_lib.t6g(sch_1):page86_i5@pure_quanta.q_res(chips)';

PART_NAME
 R2414 'Q_RES_0402LF-10K,1%,1/16W,CHIP,CS31002FB08':
;

SECTION_NUMBER 1
 '@T6G_MB_LIB.T6G(SCH_1):PAGE86_I12@PURE_QUANTA.Q_RES(CHIPS)':
 C_PATH='@t6g_mb_lib.t6g(sch_1):page86_i12@pure_quanta.q_res(chips)';

PART_NAME
 R2368 'Q_RES_0402LF-0,5%,1/16W,EMPTY,CS00002JB13':
;

SECTION_NUMBER 1
 '@T6G_MB_LIB.T6G(SCH_1):PAGE86_I72@PURE_QUANTA.Q_RES(CHIPS)':
 C_PATH='@t6g_mb_lib.t6g(sch_1):page86_i72@pure_quanta.q_res(chips)';

PART_NAME
 R2362 'Q_RES_0402LF-0,5%,1/16W,EMPTY,CS00002JB13':
;

SECTION_NUMBER 1
 '@T6G_MB_LIB.T6G(SCH_1):PAGE86_I66@PURE_QUANTA.Q_RES(CHIPS)':
 C_PATH='@t6g_mb_lib.t6g(sch_1):page86_i66@pure_quanta.q_res(chips)';

PART_NAME
 R2361 'Q_RES_0402LF-0,5%,1/16W,EMPTY,CS00002JB13':
;

SECTION_NUMBER 1
 '@T6G_MB_LIB.T6G(SCH_1):PAGE86_I74@PURE_QUANTA.Q_RES(CHIPS)':
 C_PATH='@t6g_mb_lib.t6g(sch_1):page86_i74@pure_quanta.q_res(chips)';

PART_NAME
 R2360 'Q_RES_0402LF-0,5%,1/16W,CHIP,CS00002JB13':
;

SECTION_NUMBER 1
 '@T6G_MB_LIB.T6G(SCH_1):PAGE86_I42@PURE_QUANTA.Q_RES(CHIPS)':
 C_PATH='@t6g_mb_lib.t6g(sch_1):page86_i42@pure_quanta.q_res(chips)';

PART_NAME
 R2359 'Q_RES_0402LF-0,5%,1/16W,EMPTY,CS00002JB13':
;

SECTION_NUMBER 1
 '@T6G_MB_LIB.T6G(SCH_1):PAGE86_I46@PURE_QUANTA.Q_RES(CHIPS)':
 C_PATH='@t6g_mb_lib.t6g(sch_1):page86_i46@pure_quanta.q_res(chips)';

PART_NAME
 R2358 'Q_RES_0402LF-0,5%,1/16W,CHIP,CS00002JB13':
;

SECTION_NUMBER 1
 '@T6G_MB_LIB.T6G(SCH_1):PAGE86_I25@PURE_QUANTA.Q_RES(CHIPS)':
 C_PATH='@t6g_mb_lib.t6g(sch_1):page86_i25@pure_quanta.q_res(chips)';

PART_NAME
 R2357 'Q_RES_0402LF-0,5%,1/16W,EMPTY,CS00002JB13':
;

SECTION_NUMBER 1
 '@T6G_MB_LIB.T6G(SCH_1):PAGE86_I26@PURE_QUANTA.Q_RES(CHIPS)':
 C_PATH='@t6g_mb_lib.t6g(sch_1):page86_i26@pure_quanta.q_res(chips)';

PART_NAME
 R2356 'Q_RES_0402LF-0,5%,1/16W,EMPTY,CS00002JB13':
;

SECTION_NUMBER 1
 '@T6G_MB_LIB.T6G(SCH_1):PAGE86_I41@PURE_QUANTA.Q_RES(CHIPS)':
 C_PATH='@t6g_mb_lib.t6g(sch_1):page86_i41@pure_quanta.q_res(chips)';

PART_NAME
 R2355 'Q_RES_0402LF-0,5%,1/16W,EMPTY,CS00002JB13':
;

SECTION_NUMBER 1
 '@T6G_MB_LIB.T6G(SCH_1):PAGE86_I7@PURE_QUANTA.Q_RES(CHIPS)':
 C_PATH='@t6g_mb_lib.t6g(sch_1):page86_i7@pure_quanta.q_res(chips)';

PART_NAME
 R2307 'Q_RES_0402LF-0,5%,1/16W,EMPTY,CS00002JB13':
;

SECTION_NUMBER 1
 '@T6G_MB_LIB.T6G(SCH_1):PAGE86_I14@PURE_QUANTA.Q_RES(CHIPS)':
 C_PATH='@t6g_mb_lib.t6g(sch_1):page86_i14@pure_quanta.q_res(chips)';

PART_NAME
 R2301 'Q_RES_0402LF-0,5%,1/16W,CHIP,CS00002JB13':
;

SECTION_NUMBER 1
 '@T6G_MB_LIB.T6G(SCH_1):PAGE86_I15@PURE_QUANTA.Q_RES(CHIPS)':
 C_PATH='@t6g_mb_lib.t6g(sch_1):page86_i15@pure_quanta.q_res(chips)';

PART_NAME
 R2300 'Q_RES_0402LF-0,5%,1/16W,CHIP,CS00002JB13':
;

SECTION_NUMBER 1
 '@T6G_MB_LIB.T6G(SCH_1):PAGE86_I6@PURE_QUANTA.Q_RES(CHIPS)':
 C_PATH='@t6g_mb_lib.t6g(sch_1):page86_i6@pure_quanta.q_res(chips)';

PART_NAME
 Q50 'MOSFET_NCH_DUAL-NTJD4001NT1G,SMLF,IC,BAM40010011':;

SECTION_NUMBER 1
 '@T6G_MB_LIB.T6G(SCH_1):PAGE86_I84@PURE_QUANTA.MOSFET_NCH_DUAL(CHIPS)':
 C_PATH='@t6g_mb_lib.t6g(sch_1):page86_i84@pure_quanta.mosfet_nch_dual(chips)';

SECTION_NUMBER 2
 '@T6G_MB_LIB.T6G(SCH_1):PAGE86_I83@PURE_QUANTA.MOSFET_NCH_DUAL(CHIPS)':
 C_PATH='@t6g_mb_lib.t6g(sch_1):page86_i83@pure_quanta.mosfet_nch_dual(chips)';

PART_NAME
 Q49 'MOSFET_NCH_DUAL-NTJD4001NT1G,SMLF,IC,BAM40010011':;

SECTION_NUMBER 1
 '@T6G_MB_LIB.T6G(SCH_1):PAGE86_I77@PURE_QUANTA.MOSFET_NCH_DUAL(CHIPS)':
 C_PATH='@t6g_mb_lib.t6g(sch_1):page86_i77@pure_quanta.mosfet_nch_dual(chips)';

SECTION_NUMBER 2
 '@T6G_MB_LIB.T6G(SCH_1):PAGE86_I78@PURE_QUANTA.MOSFET_NCH_DUAL(CHIPS)':
 C_PATH='@t6g_mb_lib.t6g(sch_1):page86_i78@pure_quanta.mosfet_nch_dual(chips)';

PART_NAME
 Q39 'MOSFET_NCH_DUAL-NTJD4001NT1G,SMLF,IC,BAM40010011':;

SECTION_NUMBER 1
 '@T6G_MB_LIB.T6G(SCH_1):PAGE86_I81@PURE_QUANTA.MOSFET_NCH_DUAL(CHIPS)':
 C_PATH='@t6g_mb_lib.t6g(sch_1):page86_i81@pure_quanta.mosfet_nch_dual(chips)';

SECTION_NUMBER 2
 '@T6G_MB_LIB.T6G(SCH_1):PAGE86_I82@PURE_QUANTA.MOSFET_NCH_DUAL(CHIPS)':
 C_PATH='@t6g_mb_lib.t6g(sch_1):page86_i82@pure_quanta.mosfet_nch_dual(chips)';

PART_NAME
 Q8 'MOSFET_NCH_DUAL-NTJD4001NT1G,SMLF,IC,BAM40010011':;

SECTION_NUMBER 1
 '@T6G_MB_LIB.T6G(SCH_1):PAGE86_I80@PURE_QUANTA.MOSFET_NCH_DUAL(CHIPS)':
 C_PATH='@t6g_mb_lib.t6g(sch_1):page86_i80@pure_quanta.mosfet_nch_dual(chips)';

SECTION_NUMBER 2
 '@T6G_MB_LIB.T6G(SCH_1):PAGE86_I79@PURE_QUANTA.MOSFET_NCH_DUAL(CHIPS)':
 C_PATH='@t6g_mb_lib.t6g(sch_1):page86_i79@pure_quanta.mosfet_nch_dual(chips)';

PART_NAME
 C1800 'Q_CAP_C0402-1UF,6.3V,10%,EMPTY,CH5101KEB00':
;

SECTION_NUMBER 1
 '@T6G_MB_LIB.T6G(SCH_1):PAGE86_I65@PURE_QUANTA.Q_CAP(CHIPS)':
 C_PATH='@t6g_mb_lib.t6g(sch_1):page86_i65@pure_quanta.q_cap(chips)';

PART_NAME
 C1799 'Q_CAP_C0402-1UF,6.3V,10%,EMPTY,CH5101KEB00':
;

SECTION_NUMBER 1
 '@T6G_MB_LIB.T6G(SCH_1):PAGE86_I71@PURE_QUANTA.Q_CAP(CHIPS)':
 C_PATH='@t6g_mb_lib.t6g(sch_1):page86_i71@pure_quanta.q_cap(chips)';

PART_NAME
 C1798 'Q_CAP_C0402-1UF,6.3V,10%,EMPTY,CH5101KEB00':
;

SECTION_NUMBER 1
 '@T6G_MB_LIB.T6G(SCH_1):PAGE86_I22@PURE_QUANTA.Q_CAP(CHIPS)':
 C_PATH='@t6g_mb_lib.t6g(sch_1):page86_i22@pure_quanta.q_cap(chips)';

PART_NAME
 C1797 'Q_CAP_C0402-1UF,6.3V,10%,EMPTY,CH5101KEB00':
;

SECTION_NUMBER 1
 '@T6G_MB_LIB.T6G(SCH_1):PAGE86_I34@PURE_QUANTA.Q_CAP(CHIPS)':
 C_PATH='@t6g_mb_lib.t6g(sch_1):page86_i34@pure_quanta.q_cap(chips)';

PART_NAME
 C1576 'Q_CAP_C0402-1UF,6.3V,10%,EMPTY,CH5101KEB00':
;

SECTION_NUMBER 1
 '@T6G_MB_LIB.T6G(SCH_1):PAGE86_I28@PURE_QUANTA.Q_CAP(CHIPS)':
 C_PATH='@t6g_mb_lib.t6g(sch_1):page86_i28@pure_quanta.q_cap(chips)';

PART_NAME
 C1575 'Q_CAP_C0402-1UF,6.3V,10%,EMPTY,CH5101KEB00':
;

SECTION_NUMBER 1
 '@T6G_MB_LIB.T6G(SCH_1):PAGE86_I45@PURE_QUANTA.Q_CAP(CHIPS)':
 C_PATH='@t6g_mb_lib.t6g(sch_1):page86_i45@pure_quanta.q_cap(chips)';

PART_NAME
 C1574 'Q_CAP_C0402-1UF,6.3V,10%,EMPTY,CH5101KEB00':
;

SECTION_NUMBER 1
 '@T6G_MB_LIB.T6G(SCH_1):PAGE86_I4@PURE_QUANTA.Q_CAP(CHIPS)':
 C_PATH='@t6g_mb_lib.t6g(sch_1):page86_i4@pure_quanta.q_cap(chips)';

PART_NAME
 C1511 'Q_CAP_C0402-1UF,6.3V,10%,EMPTY,CH5101KEB00':
;

SECTION_NUMBER 1
 '@T6G_MB_LIB.T6G(SCH_1):PAGE86_I10@PURE_QUANTA.Q_CAP(CHIPS)':
 C_PATH='@t6g_mb_lib.t6g(sch_1):page86_i10@pure_quanta.q_cap(chips)';

PART_NAME
 R1217 'Q_RES_0402LF-10K,1%,1/16W,CHIP,TMP_QCS31002FB26':;

SECTION_NUMBER 1
 '@T6G_MB_LIB.T6G(SCH_1):PAGE83_I19@PURE_QUANTA.Q_RES(CHIPS)':
 C_PATH='@t6g_mb_lib.t6g(sch_1):page83_i19@pure_quanta.q_res(chips)';

PART_NAME
 R1216 'Q_RES_0402LF-10K,1%,1/16W,CHIP,TMP_QCS31002FB26':;

SECTION_NUMBER 1
 '@T6G_MB_LIB.T6G(SCH_1):PAGE83_I1@PURE_QUANTA.Q_RES(CHIPS)':
 C_PATH='@t6g_mb_lib.t6g(sch_1):page83_i1@pure_quanta.q_res(chips)';

PART_NAME
 R383 'Q_RES_0402LF-10K,1%,1/16W,EMPTY,TMP_QCS31002FB26':;

SECTION_NUMBER 1
 '@T6G_MB_LIB.T6G(SCH_1):PAGE83_I18@PURE_QUANTA.Q_RES(CHIPS)':
 C_PATH='@t6g_mb_lib.t6g(sch_1):page83_i18@pure_quanta.q_res(chips)';

PART_NAME
 R330 'Q_RES_1206LF-0,,1/2W,CHIP,CS00007T200':;

SECTION_NUMBER 1
 '@T6G_MB_LIB.T6G(SCH_1):PAGE83_I36@PURE_QUANTA.Q_RES(CHIPS)':
 C_PATH='@t6g_mb_lib.t6g(sch_1):page83_i36@pure_quanta.q_res(chips)';

PART_NAME
 R329 'Q_RES_1206LF-0,,1/2W,EMPTY,CS00007T200':;

SECTION_NUMBER 1
 '@T6G_MB_LIB.T6G(SCH_1):PAGE83_I37@PURE_QUANTA.Q_RES(CHIPS)':
 C_PATH='@t6g_mb_lib.t6g(sch_1):page83_i37@pure_quanta.q_res(chips)';

PART_NAME
 R327 'Q_RES_0402LF-10K,1%,1/16W,CHIP,TMP_QCS31002FB26':;

SECTION_NUMBER 1
 '@T6G_MB_LIB.T6G(SCH_1):PAGE83_I20@PURE_QUANTA.Q_RES(CHIPS)':
 C_PATH='@t6g_mb_lib.t6g(sch_1):page83_i20@pure_quanta.q_res(chips)';

PART_NAME
 R326 'Q_RES_0402LF-10K,1%,1/16W,CHIP,TMP_QCS31002FB26':;

SECTION_NUMBER 1
 '@T6G_MB_LIB.T6G(SCH_1):PAGE83_I24@PURE_QUANTA.Q_RES(CHIPS)':
 C_PATH='@t6g_mb_lib.t6g(sch_1):page83_i24@pure_quanta.q_res(chips)';

PART_NAME
 R325 'Q_RES_0402LF-10K,1%,1/16W,CHIP,TMP_QCS31002FB26':;

SECTION_NUMBER 1
 '@T6G_MB_LIB.T6G(SCH_1):PAGE83_I25@PURE_QUANTA.Q_RES(CHIPS)':
 C_PATH='@t6g_mb_lib.t6g(sch_1):page83_i25@pure_quanta.q_res(chips)';

PART_NAME
 R324 'Q_RES_1206LF-0,,1/2W,CHIP,CS00007T200':;

SECTION_NUMBER 1
 '@T6G_MB_LIB.T6G(SCH_1):PAGE83_I11@PURE_QUANTA.Q_RES(CHIPS)':
 C_PATH='@t6g_mb_lib.t6g(sch_1):page83_i11@pure_quanta.q_res(chips)';

PART_NAME
 R323 'Q_RES_1206LF-0,,1/2W,EMPTY,CS00007T200':;

SECTION_NUMBER 1
 '@T6G_MB_LIB.T6G(SCH_1):PAGE83_I13@PURE_QUANTA.Q_RES(CHIPS)':
 C_PATH='@t6g_mb_lib.t6g(sch_1):page83_i13@pure_quanta.q_res(chips)';

PART_NAME
 R321 'Q_RES_0402LF-10K,1%,1/16W,CHIP,TMP_QCS31002FB26':;

SECTION_NUMBER 1
 '@T6G_MB_LIB.T6G(SCH_1):PAGE83_I2@PURE_QUANTA.Q_RES(CHIPS)':
 C_PATH='@t6g_mb_lib.t6g(sch_1):page83_i2@pure_quanta.q_res(chips)';

PART_NAME
 R320 'Q_RES_0402LF-10K,1%,1/16W,CHIP,TMP_QCS31002FB26':;

SECTION_NUMBER 1
 '@T6G_MB_LIB.T6G(SCH_1):PAGE83_I4@PURE_QUANTA.Q_RES(CHIPS)':
 C_PATH='@t6g_mb_lib.t6g(sch_1):page83_i4@pure_quanta.q_res(chips)';

PART_NAME
 R319 'Q_RES_0402LF-10K,1%,1/16W,CHIP,TMP_QCS31002FB26':;

SECTION_NUMBER 1
 '@T6G_MB_LIB.T6G(SCH_1):PAGE83_I5@PURE_QUANTA.Q_RES(CHIPS)':
 C_PATH='@t6g_mb_lib.t6g(sch_1):page83_i5@pure_quanta.q_res(chips)';

PART_NAME
 C1366 'Q_CAP_C0402-22UF,4V,20%,X6S,CH622KMEB02':;

SECTION_NUMBER 1
 '@T6G_MB_LIB.T6G(SCH_1):PAGE83_I46@PURE_QUANTA.Q_CAP(CHIPS)':
 C_PATH='@t6g_mb_lib.t6g(sch_1):page83_i46@pure_quanta.q_cap(chips)';

PART_NAME
 C1365 'Q_CAP_C0402-22UF,4V,20%,X6S,CH622KMEB02':;

SECTION_NUMBER 1
 '@T6G_MB_LIB.T6G(SCH_1):PAGE83_I44@PURE_QUANTA.Q_CAP(CHIPS)':
 C_PATH='@t6g_mb_lib.t6g(sch_1):page83_i44@pure_quanta.q_cap(chips)';

PART_NAME
 C1364 'Q_CAP_C0402-22UF,4V,20%,X6S,CH622KMEB02':;

SECTION_NUMBER 1
 '@T6G_MB_LIB.T6G(SCH_1):PAGE83_I42@PURE_QUANTA.Q_CAP(CHIPS)':
 C_PATH='@t6g_mb_lib.t6g(sch_1):page83_i42@pure_quanta.q_cap(chips)';

PART_NAME
 C1363 'Q_CAP_C0402-22UF,4V,20%,X6S,CH622KMEB02':;

SECTION_NUMBER 1
 '@T6G_MB_LIB.T6G(SCH_1):PAGE83_I41@PURE_QUANTA.Q_CAP(CHIPS)':
 C_PATH='@t6g_mb_lib.t6g(sch_1):page83_i41@pure_quanta.q_cap(chips)';

PART_NAME
 U182 'RT9059GQW-RT9059GQW,SMLF,IC,AL009059000':;

SECTION_NUMBER 1
 '@T6G_MB_LIB.T6G(SCH_1):PAGE284_I24@PURE_QUANTA.RT9059GQW(CHIPS)':
 C_PATH='@t6g_mb_lib.t6g(sch_1):page284_i24@pure_quanta.rt9059gqw(chips)';

PART_NAME
 R2343 'Q_RES_0402LF-12K,1%,1/16W,CHIP,TMP_QCS31202FB15':;

SECTION_NUMBER 1
 '@T6G_MB_LIB.T6G(SCH_1):PAGE284_I14@PURE_QUANTA.Q_RES(CHIPS)':
 C_PATH='@t6g_mb_lib.t6g(sch_1):page284_i14@pure_quanta.q_res(chips)';

PART_NAME
 R2340 'Q_RES_0402LF-25.5K,1%,1/16W,CHIP,CS32552FB11':;

SECTION_NUMBER 1
 '@T6G_MB_LIB.T6G(SCH_1):PAGE284_I15@PURE_QUANTA.Q_RES(CHIPS)':
 C_PATH='@t6g_mb_lib.t6g(sch_1):page284_i15@pure_quanta.q_res(chips)';

PART_NAME
 R1819 'Q_RES_0402LF-0,5%,1/16W,EMPTY,CS00002JB38':;

SECTION_NUMBER 1
 '@T6G_MB_LIB.T6G(SCH_1):PAGE284_I8@PURE_QUANTA.Q_RES(CHIPS)':
 C_PATH='@t6g_mb_lib.t6g(sch_1):page284_i8@pure_quanta.q_res(chips)';

PART_NAME
 R1818 'Q_RES_0402LF-0,5%,1/16W,CHIP,CS00002JB38':;

SECTION_NUMBER 1
 '@T6G_MB_LIB.T6G(SCH_1):PAGE284_I9@PURE_QUANTA.Q_RES(CHIPS)':
 C_PATH='@t6g_mb_lib.t6g(sch_1):page284_i9@pure_quanta.q_res(chips)';

PART_NAME
 R1729 'Q_RES_0402LF-10K,1%,1/16W,CHIP,TMP_QCS31002FB26':;

SECTION_NUMBER 1
 '@T6G_MB_LIB.T6G(SCH_1):PAGE284_I1@PURE_QUANTA.Q_RES(CHIPS)':
 C_PATH='@t6g_mb_lib.t6g(sch_1):page284_i1@pure_quanta.q_res(chips)';

PART_NAME
 R1716 'Q_RES_0402LF-0,5%,1/16W,CHIP,CS00002JB38':;

SECTION_NUMBER 1
 '@T6G_MB_LIB.T6G(SCH_1):PAGE284_I7@PURE_QUANTA.Q_RES(CHIPS)':
 C_PATH='@t6g_mb_lib.t6g(sch_1):page284_i7@pure_quanta.q_res(chips)';

PART_NAME
 C1330 'Q_CAP_0402-0.1UF,25V,10%,X7R,CH4104K1B00':;

SECTION_NUMBER 1
 '@T6G_MB_LIB.T6G(SCH_1):PAGE284_I20@PURE_QUANTA.Q_CAP(CHIPS)':
 C_PATH='@t6g_mb_lib.t6g(sch_1):page284_i20@pure_quanta.q_cap(chips)';

PART_NAME
 C1329 'Q_CAP_C0805-10UF,16V,10%,X6S,CH6103KEA00':
;

SECTION_NUMBER 1
 '@T6G_MB_LIB.T6G(SCH_1):PAGE284_I18@PURE_QUANTA.Q_CAP(CHIPS)':
 C_PATH='@t6g_mb_lib.t6g(sch_1):page284_i18@pure_quanta.q_cap(chips)';

PART_NAME
 C1328 'Q_CAP_C0805-10UF,16V,10%,X6S,CH6103KEA00':
;

SECTION_NUMBER 1
 '@T6G_MB_LIB.T6G(SCH_1):PAGE284_I17@PURE_QUANTA.Q_CAP(CHIPS)':
 C_PATH='@t6g_mb_lib.t6g(sch_1):page284_i17@pure_quanta.q_cap(chips)';

PART_NAME
 C1327 'Q_CAP_C0805-10UF,16V,10%,X6S,CH6103KEA00':
;

SECTION_NUMBER 1
 '@T6G_MB_LIB.T6G(SCH_1):PAGE284_I11@PURE_QUANTA.Q_CAP(CHIPS)':
 C_PATH='@t6g_mb_lib.t6g(sch_1):page284_i11@pure_quanta.q_cap(chips)';

PART_NAME
 U89 'MOSFET_N_SMLF-BSS138K,BSS138K,IC,BAM138K0000':;

SECTION_NUMBER 1
 '@T6G_MB_LIB.T6G(SCH_1):PAGE242_I259@PURE_QUANTA.MOSFET_N(CHIPS)':
 C_PATH='@t6g_mb_lib.t6g(sch_1):page242_i259@pure_quanta.mosfet_n(chips)';

PART_NAME
 R3722 'Q_RES_0402LF-0,5%,1/16W,EMPTY,CS00002JB38':;

SECTION_NUMBER 1
 '@T6G_MB_LIB.T6G(SCH_1):PAGE242_I284@PURE_QUANTA.Q_RES(CHIPS)':
 C_PATH='@t6g_mb_lib.t6g(sch_1):page242_i284@pure_quanta.q_res(chips)';

PART_NAME
 R3676 'Q_RES_0402LF-0,5%,1/16W,CHIP,CS00002JB38':;

SECTION_NUMBER 1
 '@T6G_MB_LIB.T6G(SCH_1):PAGE242_I289@PURE_QUANTA.Q_RES(CHIPS)':
 C_PATH='@t6g_mb_lib.t6g(sch_1):page242_i289@pure_quanta.q_res(chips)';

PART_NAME
 R1917 'Q_RES_0402LF-0,5%,1/16W,CHIP,CS00002JB38':;

SECTION_NUMBER 1
 '@T6G_MB_LIB.T6G(SCH_1):PAGE242_I226@PURE_QUANTA.Q_RES(CHIPS)':
 C_PATH='@t6g_mb_lib.t6g(sch_1):page242_i226@pure_quanta.q_res(chips)';

PART_NAME
 R1740 'Q_RES_0402LF-100,1%,1/16W,CHIP,TMP_QCS11002FB22':;

SECTION_NUMBER 1
 '@T6G_MB_LIB.T6G(SCH_1):PAGE242_I256@PURE_QUANTA.Q_RES(CHIPS)':
 C_PATH='@t6g_mb_lib.t6g(sch_1):page242_i256@pure_quanta.q_res(chips)';

PART_NAME
 R1739 'Q_RES_0402LF-100,1%,1/16W,CHIP,TMP_QCS11002FB22':;

SECTION_NUMBER 1
 '@T6G_MB_LIB.T6G(SCH_1):PAGE242_I255@PURE_QUANTA.Q_RES(CHIPS)':
 C_PATH='@t6g_mb_lib.t6g(sch_1):page242_i255@pure_quanta.q_res(chips)';

PART_NAME
 R1738 'Q_RES_0402LF-100,1%,1/16W,CHIP,TMP_QCS11002FB22':;

SECTION_NUMBER 1
 '@T6G_MB_LIB.T6G(SCH_1):PAGE242_I254@PURE_QUANTA.Q_RES(CHIPS)':
 C_PATH='@t6g_mb_lib.t6g(sch_1):page242_i254@pure_quanta.q_res(chips)';

PART_NAME
 R1710 'Q_RES_0402LF-49.9     ,1%  ,1/16W,CHIP,CS04992FB31':;

SECTION_NUMBER 1
 '@T6G_MB_LIB.T6G(SCH_1):PAGE242_I204@PURE_QUANTA.Q_RES(CHIPS)':
 C_PATH='@t6g_mb_lib.t6g(sch_1):page242_i204@pure_quanta.q_res(chips)';

PART_NAME
 R1195 'Q_RES_0402LF-750,1%,1/16W,CHIP,CS17502FB19':;

SECTION_NUMBER 1
 '@T6G_MB_LIB.T6G(SCH_1):PAGE242_I264@PURE_QUANTA.Q_RES(CHIPS)':
 C_PATH='@t6g_mb_lib.t6g(sch_1):page242_i264@pure_quanta.q_res(chips)';

PART_NAME
 R1106 'Q_RES_0402LF-10K,1%,1/16W,CHIP,TMP_QCS31002FB26':;

SECTION_NUMBER 1
 '@T6G_MB_LIB.T6G(SCH_1):PAGE242_I203@PURE_QUANTA.Q_RES(CHIPS)':
 C_PATH='@t6g_mb_lib.t6g(sch_1):page242_i203@pure_quanta.q_res(chips)';

PART_NAME
 R707 'Q_RES_0402LF-33,5%,1/16W,CHIP,CS03302JB29':;

SECTION_NUMBER 1
 '@T6G_MB_LIB.T6G(SCH_1):PAGE242_I272@PURE_QUANTA.Q_RES(CHIPS)':
 C_PATH='@t6g_mb_lib.t6g(sch_1):page242_i272@pure_quanta.q_res(chips)';

PART_NAME
 R706 'Q_RES_0402LF-33,5%,1/16W,CHIP,CS03302JB29':;

SECTION_NUMBER 1
 '@T6G_MB_LIB.T6G(SCH_1):PAGE242_I270@PURE_QUANTA.Q_RES(CHIPS)':
 C_PATH='@t6g_mb_lib.t6g(sch_1):page242_i270@pure_quanta.q_res(chips)';

PART_NAME
 R699 'Q_RES_0402LF-33,5%,1/16W,CHIP,CS03302JB29':;

SECTION_NUMBER 1
 '@T6G_MB_LIB.T6G(SCH_1):PAGE242_I273@PURE_QUANTA.Q_RES(CHIPS)':
 C_PATH='@t6g_mb_lib.t6g(sch_1):page242_i273@pure_quanta.q_res(chips)';

PART_NAME
 R668 'Q_RES_0402LF-33,5%,1/16W,CHIP,CS03302JB29':;

SECTION_NUMBER 1
 '@T6G_MB_LIB.T6G(SCH_1):PAGE242_I265@PURE_QUANTA.Q_RES(CHIPS)':
 C_PATH='@t6g_mb_lib.t6g(sch_1):page242_i265@pure_quanta.q_res(chips)';

PART_NAME
 D0 'Q_LED_SMLF-LED_GREEN,19-213/GVC-AMNB/3T,IC,BEGR0278Z00':;

SECTION_NUMBER 1
 '@T6G_MB_LIB.T6G(SCH_1):PAGE242_I262@PURE_QUANTA.Q_LED(CHIPS)':
 C_PATH='@t6g_mb_lib.t6g(sch_1):page242_i262@pure_quanta.q_led(chips)';

PART_NAME
 C1325 'Q_CAP_0402-0.1UF,25V,10%,X7R,CH4104K1B00':;

SECTION_NUMBER 1
 '@T6G_MB_LIB.T6G(SCH_1):PAGE242_I205@PURE_QUANTA.Q_CAP(CHIPS)':
 C_PATH='@t6g_mb_lib.t6g(sch_1):page242_i205@pure_quanta.q_cap(chips)';

PART_NAME
 R3846 'Q_RES_0402LF-1K,5%,1/16W,CHIP,TMP_QCS21002JB34':;

SECTION_NUMBER 1
 '@T6G_MB_LIB.T6G(SCH_1):PAGE239_I378@PURE_QUANTA.Q_RES(CHIPS)':
 C_PATH='@t6g_mb_lib.t6g(sch_1):page239_i378@pure_quanta.q_res(chips)';

PART_NAME
 R3845 'Q_RES_0402LF-1K,5%,1/16W,EMPTY,TMP_QCS21002JB34':;

SECTION_NUMBER 1
 '@T6G_MB_LIB.T6G(SCH_1):PAGE239_I382@PURE_QUANTA.Q_RES(CHIPS)':
 C_PATH='@t6g_mb_lib.t6g(sch_1):page239_i382@pure_quanta.q_res(chips)';

PART_NAME
 R3844 'Q_RES_0402LF-1K,5%,1/16W,CHIP,TMP_QCS21002JB34':;

SECTION_NUMBER 1
 '@T6G_MB_LIB.T6G(SCH_1):PAGE239_I376@PURE_QUANTA.Q_RES(CHIPS)':
 C_PATH='@t6g_mb_lib.t6g(sch_1):page239_i376@pure_quanta.q_res(chips)';

PART_NAME
 R3843 'Q_RES_0402LF-1K,5%,1/16W,EMPTY,TMP_QCS21002JB34':;

SECTION_NUMBER 1
 '@T6G_MB_LIB.T6G(SCH_1):PAGE239_I381@PURE_QUANTA.Q_RES(CHIPS)':
 C_PATH='@t6g_mb_lib.t6g(sch_1):page239_i381@pure_quanta.q_res(chips)';

PART_NAME
 R1823 'Q_RES_0402LF-1K,1%,1/16W,CHIP,TMP_QCS21002FB24':;

SECTION_NUMBER 1
 '@T6G_MB_LIB.T6G(SCH_1):PAGE239_I309@PURE_QUANTA.Q_RES(CHIPS)':
 C_PATH='@t6g_mb_lib.t6g(sch_1):page239_i309@pure_quanta.q_res(chips)';

PART_NAME
 R1644 'Q_RES_0402LF-1K,1%,1/16W,CHIP,TMP_QCS21002FB24':;

SECTION_NUMBER 1
 '@T6G_MB_LIB.T6G(SCH_1):PAGE239_I307@PURE_QUANTA.Q_RES(CHIPS)':
 C_PATH='@t6g_mb_lib.t6g(sch_1):page239_i307@pure_quanta.q_res(chips)';

PART_NAME
 R1100 'Q_RES_0402LF-33,5%,1/16W,CHIP,CS03302JB29':;

SECTION_NUMBER 1
 '@T6G_MB_LIB.T6G(SCH_1):PAGE239_I345@PURE_QUANTA.Q_RES(CHIPS)':
 C_PATH='@t6g_mb_lib.t6g(sch_1):page239_i345@pure_quanta.q_res(chips)';

PART_NAME
 R1099 'Q_RES_0402LF-10K,1%,1/16W,CHIP,TMP_QCS31002FB26':;

SECTION_NUMBER 1
 '@T6G_MB_LIB.T6G(SCH_1):PAGE239_I371@PURE_QUANTA.Q_RES(CHIPS)':
 C_PATH='@t6g_mb_lib.t6g(sch_1):page239_i371@pure_quanta.q_res(chips)';

PART_NAME
 OSC2 'Q_OSC4P_SMLF-25MHZ,OSC,BF625000014':;

SECTION_NUMBER 1
 '@T6G_MB_LIB.T6G(SCH_1):PAGE239_I369@PURE_QUANTA.Q_OSC4P(CHIPS)':
 C_PATH='@t6g_mb_lib.t6g(sch_1):page239_i369@pure_quanta.q_osc4p(chips)';

PART_NAME
 C1320 'Q_CAP_0402-0.1UF,25V,10%,X7R,CH4104K1B00':;

SECTION_NUMBER 1
 '@T6G_MB_LIB.T6G(SCH_1):PAGE239_I366@PURE_QUANTA.Q_CAP(CHIPS)':
 C_PATH='@t6g_mb_lib.t6g(sch_1):page239_i366@pure_quanta.q_cap(chips)';

PART_NAME
 U172 'TPS3897PDRYR-TPS3897PDRYR,SMLF,EMPTY,AL003897006':;

SECTION_NUMBER 1
 '@T6G_MB_LIB.T6G(SCH_1):PAGE249_I25@PURE_QUANTA.TPS3897PDRYR(CHIPS)':
 C_PATH='@t6g_mb_lib.t6g(sch_1):page249_i25@pure_quanta.tps3897pdryr(chips)';

PART_NAME
 U171 'SN74LVC1G07DCKR-SN74LVC1G07DCKR,SMLF,IC,AL1G0007016':;

SECTION_NUMBER 1
 '@T6G_MB_LIB.T6G(SCH_1):PAGE249_I14@PURE_QUANTA.SN74LVC1G07DCKR(CHIPS)':
 C_PATH='@t6g_mb_lib.t6g(sch_1):page249_i14@pure_quanta.sn74lvc1g07dckr(chips)';

PART_NAME
 U170 'ADM1086AKSZREEL7-ADM1086AKSZ-REEL7,SMLF,IC,AL001086001':;

SECTION_NUMBER 1
 '@T6G_MB_LIB.T6G(SCH_1):PAGE249_I26@PURE_QUANTA.ADM1086AKSZREEL7(CHIPS)':
 C_PATH='@t6g_mb_lib.t6g(sch_1):page249_i26@pure_quanta.adm1086akszreel7(chips)';

PART_NAME
 R3842 'Q_RES_0402LF-0,5%,1/16W,EMPTY,CS00002JB38':;

SECTION_NUMBER 1
 '@T6G_MB_LIB.T6G(SCH_1):PAGE249_I49@PURE_QUANTA.Q_RES(CHIPS)':
 C_PATH='@t6g_mb_lib.t6g(sch_1):page249_i49@pure_quanta.q_res(chips)';

PART_NAME
 R3707 'Q_RES_0402LF-10K,1%,1/16W,CHIP,TMP_QCS31002FB26':;

SECTION_NUMBER 1
 '@T6G_MB_LIB.T6G(SCH_1):PAGE249_I45@PURE_QUANTA.Q_RES(CHIPS)':
 C_PATH='@t6g_mb_lib.t6g(sch_1):page249_i45@pure_quanta.q_res(chips)';

PART_NAME
 R3700 'Q_RES_0402LF-0,5%,1/16W,CHIP,CS00002JB38':;

SECTION_NUMBER 1
 '@T6G_MB_LIB.T6G(SCH_1):PAGE249_I41@PURE_QUANTA.Q_RES(CHIPS)':
 C_PATH='@t6g_mb_lib.t6g(sch_1):page249_i41@pure_quanta.q_res(chips)';

PART_NAME
 R1788 'Q_RES_0402LF-0,5%,1/16W,EMPTY,CS00002JB38':;

SECTION_NUMBER 1
 '@T6G_MB_LIB.T6G(SCH_1):PAGE249_I30@PURE_QUANTA.Q_RES(CHIPS)':
 C_PATH='@t6g_mb_lib.t6g(sch_1):page249_i30@pure_quanta.q_res(chips)';

PART_NAME
 R1787 'Q_RES_0402LF-10K,1%,1/16W,CHIP,TMP_QCS31002FB26':;

SECTION_NUMBER 1
 '@T6G_MB_LIB.T6G(SCH_1):PAGE249_I33@PURE_QUANTA.Q_RES(CHIPS)':
 C_PATH='@t6g_mb_lib.t6g(sch_1):page249_i33@pure_quanta.q_res(chips)';

PART_NAME
 R1786 'Q_RES_0402LF-33,5%,1/16W,CHIP,CS03302JB29':;

SECTION_NUMBER 1
 '@T6G_MB_LIB.T6G(SCH_1):PAGE249_I48@PURE_QUANTA.Q_RES(CHIPS)':
 C_PATH='@t6g_mb_lib.t6g(sch_1):page249_i48@pure_quanta.q_res(chips)';

PART_NAME
 R1785 'Q_RES_0402LF-100K,1%,1/16W,EMPTY,TMP_QCS41002FB28':;

SECTION_NUMBER 1
 '@T6G_MB_LIB.T6G(SCH_1):PAGE249_I2@PURE_QUANTA.Q_RES(CHIPS)':
 C_PATH='@t6g_mb_lib.t6g(sch_1):page249_i2@pure_quanta.q_res(chips)';

PART_NAME
 R1784 'Q_RES_0402LF-10K,1%,1/16W,CHIP,TMP_QCS31002FB26':;

SECTION_NUMBER 1
 '@T6G_MB_LIB.T6G(SCH_1):PAGE249_I4@PURE_QUANTA.Q_RES(CHIPS)':
 C_PATH='@t6g_mb_lib.t6g(sch_1):page249_i4@pure_quanta.q_res(chips)';

PART_NAME
 R1783 'Q_RES_0402LF-10K,1%,1/16W,CHIP,TMP_QCS31002FB26':;

SECTION_NUMBER 1
 '@T6G_MB_LIB.T6G(SCH_1):PAGE249_I21@PURE_QUANTA.Q_RES(CHIPS)':
 C_PATH='@t6g_mb_lib.t6g(sch_1):page249_i21@pure_quanta.q_res(chips)';

PART_NAME
 R1782 'Q_RES_0402LF-6.19K,1%,1/16W,CHIP,TMP_QCS26192FB14':;

SECTION_NUMBER 1
 '@T6G_MB_LIB.T6G(SCH_1):PAGE249_I18@PURE_QUANTA.Q_RES(CHIPS)':
 C_PATH='@t6g_mb_lib.t6g(sch_1):page249_i18@pure_quanta.q_res(chips)';

PART_NAME
 R1781 'Q_RES_0402LF-100K,1%,1/16W,CHIP,TMP_QCS41002FB28':;

SECTION_NUMBER 1
 '@T6G_MB_LIB.T6G(SCH_1):PAGE249_I19@PURE_QUANTA.Q_RES(CHIPS)':
 C_PATH='@t6g_mb_lib.t6g(sch_1):page249_i19@pure_quanta.q_res(chips)';

PART_NAME
 R1745 'Q_RES_0402LF-0,5%,1/16W,EMPTY,CS00002JB38':;

SECTION_NUMBER 1
 '@T6G_MB_LIB.T6G(SCH_1):PAGE249_I13@PURE_QUANTA.Q_RES(CHIPS)':
 C_PATH='@t6g_mb_lib.t6g(sch_1):page249_i13@pure_quanta.q_res(chips)';

PART_NAME
 Q18 'MOSFET_NCH_DUAL-2N7002KDW,SMLF,IC,BAM70020047':;

SECTION_NUMBER 1
 '@T6G_MB_LIB.T6G(SCH_1):PAGE249_I47@PURE_QUANTA.MOSFET_NCH_DUAL(CHIPS)':
 C_PATH='@t6g_mb_lib.t6g(sch_1):page249_i47@pure_quanta.mosfet_nch_dual(chips)';

SECTION_NUMBER 2
 '@T6G_MB_LIB.T6G(SCH_1):PAGE249_I42@PURE_QUANTA.MOSFET_NCH_DUAL(CHIPS)':
 C_PATH='@t6g_mb_lib.t6g(sch_1):page249_i42@pure_quanta.mosfet_nch_dual(chips)';

PART_NAME
 C1319 'Q_CAP_C0402-1UF,25V,10%,X6S,CH5104KEB02':;

SECTION_NUMBER 1
 '@T6G_MB_LIB.T6G(SCH_1):PAGE249_I28@PURE_QUANTA.Q_CAP(CHIPS)':
 C_PATH='@t6g_mb_lib.t6g(sch_1):page249_i28@pure_quanta.q_cap(chips)';

PART_NAME
 C1318 'Q_CAP_C0402-1UF,25V,10%,X6S,CH5104KEB02':;

SECTION_NUMBER 1
 '@T6G_MB_LIB.T6G(SCH_1):PAGE249_I6@PURE_QUANTA.Q_CAP(CHIPS)':
 C_PATH='@t6g_mb_lib.t6g(sch_1):page249_i6@pure_quanta.q_cap(chips)';

PART_NAME
 C1317 'Q_CAP_0402-0.1UF,25V,10%,X7R,CH4104K1B00':;

SECTION_NUMBER 1
 '@T6G_MB_LIB.T6G(SCH_1):PAGE249_I9@PURE_QUANTA.Q_CAP(CHIPS)':
 C_PATH='@t6g_mb_lib.t6g(sch_1):page249_i9@pure_quanta.q_cap(chips)';

PART_NAME
 C1316 'Q_CAP_C0402-0.047UF,25V,10%,X7R,CH3474K1B04':;

SECTION_NUMBER 1
 '@T6G_MB_LIB.T6G(SCH_1):PAGE249_I38@PURE_QUANTA.Q_CAP(CHIPS)':
 C_PATH='@t6g_mb_lib.t6g(sch_1):page249_i38@pure_quanta.q_cap(chips)';

PART_NAME
 C1315 'Q_CAP_C0402-1UF,25V,10%,X6S,CH5104KEB02':;

SECTION_NUMBER 1
 '@T6G_MB_LIB.T6G(SCH_1):PAGE249_I23@PURE_QUANTA.Q_CAP(CHIPS)':
 C_PATH='@t6g_mb_lib.t6g(sch_1):page249_i23@pure_quanta.q_cap(chips)';

PART_NAME
 U199 'TPD2EUSB30DRTR_SMLF-TPD2EUSB30DRTR,IC,AL2EUSB3000':;

SECTION_NUMBER 1
 '@T6G_MB_LIB.T6G(SCH_1):PAGE271_I701@PURE_QUANTA.TPD2EUSB30DRTR(CHIPS)':
 C_PATH='@t6g_mb_lib.t6g(sch_1):page271_i701@pure_quanta.tpd2eusb30drtr(chips)';

PART_NAME
 U198 'TPD2EUSB30DRTR_SMLF-TPD2EUSB30DRTR,IC,AL2EUSB3000':;

SECTION_NUMBER 1
 '@T6G_MB_LIB.T6G(SCH_1):PAGE271_I705@PURE_QUANTA.TPD2EUSB30DRTR(CHIPS)':
 C_PATH='@t6g_mb_lib.t6g(sch_1):page271_i705@pure_quanta.tpd2eusb30drtr(chips)';

PART_NAME
 R3834 'Q_RES_0402LF-33,5%,1/16W,CHIP,CS03302JB29':;

SECTION_NUMBER 1
 '@T6G_MB_LIB.T6G(SCH_1):PAGE271_I696@PURE_QUANTA.Q_RES(CHIPS)':
 C_PATH='@t6g_mb_lib.t6g(sch_1):page271_i696@pure_quanta.q_res(chips)';

PART_NAME
 R3833 'Q_RES_0402LF-33,5%,1/16W,CHIP,CS03302JB29':;

SECTION_NUMBER 1
 '@T6G_MB_LIB.T6G(SCH_1):PAGE271_I695@PURE_QUANTA.Q_RES(CHIPS)':
 C_PATH='@t6g_mb_lib.t6g(sch_1):page271_i695@pure_quanta.q_res(chips)';

PART_NAME
 R3832 'Q_RES_0402LF-33,5%,1/16W,CHIP,CS03302JB29':;

SECTION_NUMBER 1
 '@T6G_MB_LIB.T6G(SCH_1):PAGE271_I693@PURE_QUANTA.Q_RES(CHIPS)':
 C_PATH='@t6g_mb_lib.t6g(sch_1):page271_i693@pure_quanta.q_res(chips)';

PART_NAME
 R3830 'Q_RES_0402LF-33,5%,1/16W,CHIP,CS03302JB29':;

SECTION_NUMBER 1
 '@T6G_MB_LIB.T6G(SCH_1):PAGE271_I694@PURE_QUANTA.Q_RES(CHIPS)':
 C_PATH='@t6g_mb_lib.t6g(sch_1):page271_i694@pure_quanta.q_res(chips)';

PART_NAME
 R3829 'Q_RES_0402LF-33,5%,1/16W,CHIP,CS03302JB29':;

SECTION_NUMBER 1
 '@T6G_MB_LIB.T6G(SCH_1):PAGE271_I688@PURE_QUANTA.Q_RES(CHIPS)':
 C_PATH='@t6g_mb_lib.t6g(sch_1):page271_i688@pure_quanta.q_res(chips)';

PART_NAME
 R3828 'Q_RES_0402LF-33,5%,1/16W,CHIP,CS03302JB29':;

SECTION_NUMBER 1
 '@T6G_MB_LIB.T6G(SCH_1):PAGE271_I687@PURE_QUANTA.Q_RES(CHIPS)':
 C_PATH='@t6g_mb_lib.t6g(sch_1):page271_i687@pure_quanta.q_res(chips)';

PART_NAME
 R3797 'Q_RES_0402LF-0,5%,1/16W,CHIP,CS00002JB38':;

SECTION_NUMBER 1
 '@T6G_MB_LIB.T6G(SCH_1):PAGE271_I677@PURE_QUANTA.Q_RES(CHIPS)':
 C_PATH='@t6g_mb_lib.t6g(sch_1):page271_i677@pure_quanta.q_res(chips)';

PART_NAME
 R3796 'Q_RES_0402LF-10K,1%,1/16W,CHIP,TMP_QCS31002FB26':;

SECTION_NUMBER 1
 '@T6G_MB_LIB.T6G(SCH_1):PAGE271_I674@PURE_QUANTA.Q_RES(CHIPS)':
 C_PATH='@t6g_mb_lib.t6g(sch_1):page271_i674@pure_quanta.q_res(chips)';

PART_NAME
 R3793 'Q_RES_0402LF-0,5%,1/16W,CHIP,CS00002JB38':;

SECTION_NUMBER 1
 '@T6G_MB_LIB.T6G(SCH_1):PAGE271_I679@PURE_QUANTA.Q_RES(CHIPS)':
 C_PATH='@t6g_mb_lib.t6g(sch_1):page271_i679@pure_quanta.q_res(chips)';

PART_NAME
 R3788 'Q_RES_0402LF-0,5%,1/16W,CHIP,CS00002JB38':;

SECTION_NUMBER 1
 '@T6G_MB_LIB.T6G(SCH_1):PAGE271_I678@PURE_QUANTA.Q_RES(CHIPS)':
 C_PATH='@t6g_mb_lib.t6g(sch_1):page271_i678@pure_quanta.q_res(chips)';

PART_NAME
 R3787 'Q_RES_0402LF-0,5%,1/16W,EMPTY,CS00002JB38':;

SECTION_NUMBER 1
 '@T6G_MB_LIB.T6G(SCH_1):PAGE271_I635@PURE_QUANTA.Q_RES(CHIPS)':
 C_PATH='@t6g_mb_lib.t6g(sch_1):page271_i635@pure_quanta.q_res(chips)';

PART_NAME
 R3786 'Q_RES_0402LF-0,5%,1/16W,CHIP,CS00002JB38':;

SECTION_NUMBER 1
 '@T6G_MB_LIB.T6G(SCH_1):PAGE271_I636@PURE_QUANTA.Q_RES(CHIPS)':
 C_PATH='@t6g_mb_lib.t6g(sch_1):page271_i636@pure_quanta.q_res(chips)';

PART_NAME
 R3784 'Q_RES_0402LF-33,5%,1/16W,CHIP,CS03302JB29':;

SECTION_NUMBER 1
 '@T6G_MB_LIB.T6G(SCH_1):PAGE271_I621@PURE_QUANTA.Q_RES(CHIPS)':
 C_PATH='@t6g_mb_lib.t6g(sch_1):page271_i621@pure_quanta.q_res(chips)';

PART_NAME
 R3783 'Q_RES_0402LF-33,5%,1/16W,CHIP,CS03302JB29':;

SECTION_NUMBER 1
 '@T6G_MB_LIB.T6G(SCH_1):PAGE271_I631@PURE_QUANTA.Q_RES(CHIPS)':
 C_PATH='@t6g_mb_lib.t6g(sch_1):page271_i631@pure_quanta.q_res(chips)';

PART_NAME
 R3782 'Q_RES_0402LF-33,5%,1/16W,CHIP,CS03302JB29':;

SECTION_NUMBER 1
 '@T6G_MB_LIB.T6G(SCH_1):PAGE271_I632@PURE_QUANTA.Q_RES(CHIPS)':
 C_PATH='@t6g_mb_lib.t6g(sch_1):page271_i632@pure_quanta.q_res(chips)';

PART_NAME
 R3779 'Q_RES_0402LF-33,5%,1/16W,CHIP,CS03302JB29':;

SECTION_NUMBER 1
 '@T6G_MB_LIB.T6G(SCH_1):PAGE271_I620@PURE_QUANTA.Q_RES(CHIPS)':
 C_PATH='@t6g_mb_lib.t6g(sch_1):page271_i620@pure_quanta.q_res(chips)';

PART_NAME
 R3778 'Q_RES_0402LF-33,5%,1/16W,CHIP,CS03302JB29':;

SECTION_NUMBER 1
 '@T6G_MB_LIB.T6G(SCH_1):PAGE271_I619@PURE_QUANTA.Q_RES(CHIPS)':
 C_PATH='@t6g_mb_lib.t6g(sch_1):page271_i619@pure_quanta.q_res(chips)';

PART_NAME
 R3777 'Q_RES_0402LF-33,5%,1/16W,CHIP,CS03302JB29':;

SECTION_NUMBER 1
 '@T6G_MB_LIB.T6G(SCH_1):PAGE271_I624@PURE_QUANTA.Q_RES(CHIPS)':
 C_PATH='@t6g_mb_lib.t6g(sch_1):page271_i624@pure_quanta.q_res(chips)';

PART_NAME
 R3776 'Q_RES_0402LF-33,5%,1/16W,CHIP,CS03302JB29':;

SECTION_NUMBER 1
 '@T6G_MB_LIB.T6G(SCH_1):PAGE271_I623@PURE_QUANTA.Q_RES(CHIPS)':
 C_PATH='@t6g_mb_lib.t6g(sch_1):page271_i623@pure_quanta.q_res(chips)';

PART_NAME
 R3771 'Q_RES_0402LF-33,5%,1/16W,CHIP,CS03302JB29':;

SECTION_NUMBER 1
 '@T6G_MB_LIB.T6G(SCH_1):PAGE271_I630@PURE_QUANTA.Q_RES(CHIPS)':
 C_PATH='@t6g_mb_lib.t6g(sch_1):page271_i630@pure_quanta.q_res(chips)';

PART_NAME
 R3770 'Q_RES_0402LF-33,5%,1/16W,CHIP,CS03302JB29':;

SECTION_NUMBER 1
 '@T6G_MB_LIB.T6G(SCH_1):PAGE271_I628@PURE_QUANTA.Q_RES(CHIPS)':
 C_PATH='@t6g_mb_lib.t6g(sch_1):page271_i628@pure_quanta.q_res(chips)';

PART_NAME
 R3769 'Q_RES_0402LF-33,5%,1/16W,CHIP,CS03302JB29':;

SECTION_NUMBER 1
 '@T6G_MB_LIB.T6G(SCH_1):PAGE271_I611@PURE_QUANTA.Q_RES(CHIPS)':
 C_PATH='@t6g_mb_lib.t6g(sch_1):page271_i611@pure_quanta.q_res(chips)';

PART_NAME
 R3768 'Q_RES_0402LF-33,5%,1/16W,CHIP,CS03302JB29':;

SECTION_NUMBER 1
 '@T6G_MB_LIB.T6G(SCH_1):PAGE271_I612@PURE_QUANTA.Q_RES(CHIPS)':
 C_PATH='@t6g_mb_lib.t6g(sch_1):page271_i612@pure_quanta.q_res(chips)';

PART_NAME
 R3767 'Q_RES_0402LF-33,5%,1/16W,CHIP,CS03302JB29':;

SECTION_NUMBER 1
 '@T6G_MB_LIB.T6G(SCH_1):PAGE271_I615@PURE_QUANTA.Q_RES(CHIPS)':
 C_PATH='@t6g_mb_lib.t6g(sch_1):page271_i615@pure_quanta.q_res(chips)';

PART_NAME
 R3757 'Q_RES_0402LF-10K,1%,1/16W,CHIP,TMP_QCS31002FB26':;

SECTION_NUMBER 1
 '@T6G_MB_LIB.T6G(SCH_1):PAGE271_I607@PURE_QUANTA.Q_RES(CHIPS)':
 C_PATH='@t6g_mb_lib.t6g(sch_1):page271_i607@pure_quanta.q_res(chips)';

PART_NAME
 R3756 'Q_RES_0402LF-10K,1%,1/16W,CHIP,TMP_QCS31002FB26':;

SECTION_NUMBER 1
 '@T6G_MB_LIB.T6G(SCH_1):PAGE271_I606@PURE_QUANTA.Q_RES(CHIPS)':
 C_PATH='@t6g_mb_lib.t6g(sch_1):page271_i606@pure_quanta.q_res(chips)';

PART_NAME
 R3755 'Q_RES_0402LF-10K,1%,1/16W,CHIP,TMP_QCS31002FB26':;

SECTION_NUMBER 1
 '@T6G_MB_LIB.T6G(SCH_1):PAGE271_I605@PURE_QUANTA.Q_RES(CHIPS)':
 C_PATH='@t6g_mb_lib.t6g(sch_1):page271_i605@pure_quanta.q_res(chips)';

PART_NAME
 R3754 'Q_RES_0402LF-10K,1%,1/16W,CHIP,TMP_QCS31002FB26':;

SECTION_NUMBER 1
 '@T6G_MB_LIB.T6G(SCH_1):PAGE271_I604@PURE_QUANTA.Q_RES(CHIPS)':
 C_PATH='@t6g_mb_lib.t6g(sch_1):page271_i604@pure_quanta.q_res(chips)';

PART_NAME
 R3738 'Q_RES_0402LF-0,5%,1/16W,CHIP,CS00002JB38':;

SECTION_NUMBER 1
 '@T6G_MB_LIB.T6G(SCH_1):PAGE271_I675@PURE_QUANTA.Q_RES(CHIPS)':
 C_PATH='@t6g_mb_lib.t6g(sch_1):page271_i675@pure_quanta.q_res(chips)';

PART_NAME
 R3678 'Q_RES_0402LF-0,5%,1/16W,CHIP,CS00002JB38':;

SECTION_NUMBER 1
 '@T6G_MB_LIB.T6G(SCH_1):PAGE271_I676@PURE_QUANTA.Q_RES(CHIPS)':
 C_PATH='@t6g_mb_lib.t6g(sch_1):page271_i676@pure_quanta.q_res(chips)';

PART_NAME
 R3543 'Q_RES_0402LF-10K,1%,1/16W,CHIP,TMP_QCS31002FB26':;

SECTION_NUMBER 1
 '@T6G_MB_LIB.T6G(SCH_1):PAGE271_I564@PURE_QUANTA.Q_RES(CHIPS)':
 C_PATH='@t6g_mb_lib.t6g(sch_1):page271_i564@pure_quanta.q_res(chips)';

PART_NAME
 R1906 'Q_RES_0402LF-10K,1%,1/16W,EMPTY,TMP_QCS31002FB26':;

SECTION_NUMBER 1
 '@T6G_MB_LIB.T6G(SCH_1):PAGE271_I482@PURE_QUANTA.Q_RES(CHIPS)':
 C_PATH='@t6g_mb_lib.t6g(sch_1):page271_i482@pure_quanta.q_res(chips)';

PART_NAME
 R1905 'Q_RES_0402LF-1K,1%,1/16W,EMPTY,TMP_QCS21002FB24':;

SECTION_NUMBER 1
 '@T6G_MB_LIB.T6G(SCH_1):PAGE271_I481@PURE_QUANTA.Q_RES(CHIPS)':
 C_PATH='@t6g_mb_lib.t6g(sch_1):page271_i481@pure_quanta.q_res(chips)';

PART_NAME
 R1857 'Q_RES_0402LF-10K,1%,1/16W,CHIP,TMP_QCS31002FB26':;

SECTION_NUMBER 1
 '@T6G_MB_LIB.T6G(SCH_1):PAGE271_I556@PURE_QUANTA.Q_RES(CHIPS)':
 C_PATH='@t6g_mb_lib.t6g(sch_1):page271_i556@pure_quanta.q_res(chips)';

PART_NAME
 R1856 'Q_RES_0402LF-100,1%,1/16W,CHIP,TMP_QCS11002FB22':;

SECTION_NUMBER 1
 '@T6G_MB_LIB.T6G(SCH_1):PAGE271_I568@PURE_QUANTA.Q_RES(CHIPS)':
 C_PATH='@t6g_mb_lib.t6g(sch_1):page271_i568@pure_quanta.q_res(chips)';

PART_NAME
 R1855 'Q_RES_0402LF-10K,1%,1/16W,CHIP,TMP_QCS31002FB26':;

SECTION_NUMBER 1
 '@T6G_MB_LIB.T6G(SCH_1):PAGE271_I559@PURE_QUANTA.Q_RES(CHIPS)':
 C_PATH='@t6g_mb_lib.t6g(sch_1):page271_i559@pure_quanta.q_res(chips)';

PART_NAME
 R1854 'Q_RES_0402LF-10K,1%,1/16W,CHIP,TMP_QCS31002FB26':;

SECTION_NUMBER 1
 '@T6G_MB_LIB.T6G(SCH_1):PAGE271_I573@PURE_QUANTA.Q_RES(CHIPS)':
 C_PATH='@t6g_mb_lib.t6g(sch_1):page271_i573@pure_quanta.q_res(chips)';

PART_NAME
 R1845 'Q_RES_0402LF-0,5%,1/16W,CHIP,CS00002JB38':;

SECTION_NUMBER 1
 '@T6G_MB_LIB.T6G(SCH_1):PAGE271_I452@PURE_QUANTA.Q_RES(CHIPS)':
 C_PATH='@t6g_mb_lib.t6g(sch_1):page271_i452@pure_quanta.q_res(chips)';

PART_NAME
 R1833 'Q_RES_0402LF-0,5%,1/16W,CHIP,CS00002JB38':;

SECTION_NUMBER 1
 '@T6G_MB_LIB.T6G(SCH_1):PAGE271_I453@PURE_QUANTA.Q_RES(CHIPS)':
 C_PATH='@t6g_mb_lib.t6g(sch_1):page271_i453@pure_quanta.q_res(chips)';

PART_NAME
 R1816 'Q_RES_0402LF-0,5%,1/16W,CHIP,CS00002JB38':;

SECTION_NUMBER 1
 '@T6G_MB_LIB.T6G(SCH_1):PAGE271_I447@PURE_QUANTA.Q_RES(CHIPS)':
 C_PATH='@t6g_mb_lib.t6g(sch_1):page271_i447@pure_quanta.q_res(chips)';

PART_NAME
 R1815 'Q_RES_0402LF-0,5%,1/16W,CHIP,CS00002JB38':;

SECTION_NUMBER 1
 '@T6G_MB_LIB.T6G(SCH_1):PAGE271_I446@PURE_QUANTA.Q_RES(CHIPS)':
 C_PATH='@t6g_mb_lib.t6g(sch_1):page271_i446@pure_quanta.q_res(chips)';

PART_NAME
 R1801 'Q_RES_0402LF-0,5%,1/16W,CHIP,CS00002JB38':;

SECTION_NUMBER 1
 '@T6G_MB_LIB.T6G(SCH_1):PAGE271_I328@PURE_QUANTA.Q_RES(CHIPS)':
 C_PATH='@t6g_mb_lib.t6g(sch_1):page271_i328@pure_quanta.q_res(chips)';

PART_NAME
 R1798 'Q_RES_0402LF-0,5%,1/16W,CHIP,CS00002JB38':;

SECTION_NUMBER 1
 '@T6G_MB_LIB.T6G(SCH_1):PAGE271_I450@PURE_QUANTA.Q_RES(CHIPS)':
 C_PATH='@t6g_mb_lib.t6g(sch_1):page271_i450@pure_quanta.q_res(chips)';

PART_NAME
 R1797 'Q_RES_0402LF-0,5%,1/16W,CHIP,CS00002JB38':;

SECTION_NUMBER 1
 '@T6G_MB_LIB.T6G(SCH_1):PAGE271_I449@PURE_QUANTA.Q_RES(CHIPS)':
 C_PATH='@t6g_mb_lib.t6g(sch_1):page271_i449@pure_quanta.q_res(chips)';

PART_NAME
 R1789 'Q_RES_0402LF-0,5%,1/16W,CHIP,CS00002JB38':;

SECTION_NUMBER 1
 '@T6G_MB_LIB.T6G(SCH_1):PAGE271_I451@PURE_QUANTA.Q_RES(CHIPS)':
 C_PATH='@t6g_mb_lib.t6g(sch_1):page271_i451@pure_quanta.q_res(chips)';

PART_NAME
 R1711 'Q_RES_0402LF-0,5%,1/16W,CHIP,CS00002JB38':;

SECTION_NUMBER 1
 '@T6G_MB_LIB.T6G(SCH_1):PAGE271_I448@PURE_QUANTA.Q_RES(CHIPS)':
 C_PATH='@t6g_mb_lib.t6g(sch_1):page271_i448@pure_quanta.q_res(chips)';

PART_NAME
 R1040 'Q_RES_0402LF-0,5%,1/16W,CHIP,CS00002JB38':;

SECTION_NUMBER 1
 '@T6G_MB_LIB.T6G(SCH_1):PAGE271_I499@PURE_QUANTA.Q_RES(CHIPS)':
 C_PATH='@t6g_mb_lib.t6g(sch_1):page271_i499@pure_quanta.q_res(chips)';

PART_NAME
 R891 'Q_RES_0402LF-0,5%,1/16W,CHIP,CS00002JB38':;

SECTION_NUMBER 1
 '@T6G_MB_LIB.T6G(SCH_1):PAGE271_I498@PURE_QUANTA.Q_RES(CHIPS)':
 C_PATH='@t6g_mb_lib.t6g(sch_1):page271_i498@pure_quanta.q_res(chips)';

PART_NAME
 R142 'Q_RES_0402LF-0,5%,1/16W,CHIP,CS00002JB38':;

SECTION_NUMBER 1
 '@T6G_MB_LIB.T6G(SCH_1):PAGE271_I486@PURE_QUANTA.Q_RES(CHIPS)':
 C_PATH='@t6g_mb_lib.t6g(sch_1):page271_i486@pure_quanta.q_res(chips)';

PART_NAME
 Q102 'MOSFET_PCH_GDS_ESD_PROTECTED-DMP2045U-7,SMLF,IC,BAM20450000':;

SECTION_NUMBER 1
 '@T6G_MB_LIB.T6G(SCH_1):PAGE271_I553@PURE_QUANTA.MOSFET_PCH_GDS_ESD_PROTECTED(CHIPS)':
 C_PATH='@t6g_mb_lib.t6g(sch_1):page271_i553@pure_quanta.mosfet_pch_gds_esd_prot~
ected(chips)';

PART_NAME
 Q101 'MOSFET_NCH_DUAL-2N7002KDW,SMLF,IC,BAM70020047':;

SECTION_NUMBER 1
 '@T6G_MB_LIB.T6G(SCH_1):PAGE271_I570@PURE_QUANTA.MOSFET_NCH_DUAL(CHIPS)':
 C_PATH='@t6g_mb_lib.t6g(sch_1):page271_i570@pure_quanta.mosfet_nch_dual(chips)';

SECTION_NUMBER 2
 '@T6G_MB_LIB.T6G(SCH_1):PAGE271_I563@PURE_QUANTA.MOSFET_NCH_DUAL(CHIPS)':
 C_PATH='@t6g_mb_lib.t6g(sch_1):page271_i563@pure_quanta.mosfet_nch_dual(chips)';

PART_NAME
 Q89 'MOSFET_NCH_DUAL-2N7002KDW,SMLF,IC,BAM70020047':;

SECTION_NUMBER 1
 '@T6G_MB_LIB.T6G(SCH_1):PAGE271_I495@PURE_QUANTA.MOSFET_NCH_DUAL(CHIPS)':
 C_PATH='@t6g_mb_lib.t6g(sch_1):page271_i495@pure_quanta.mosfet_nch_dual(chips)';

SECTION_NUMBER 2
 '@T6G_MB_LIB.T6G(SCH_1):PAGE271_I494@PURE_QUANTA.MOSFET_NCH_DUAL(CHIPS)':
 C_PATH='@t6g_mb_lib.t6g(sch_1):page271_i494@pure_quanta.mosfet_nch_dual(chips)';

PART_NAME
 Q87 'MOSFET_NCH_DUAL-2N7002KDW,SMLF,IC,BAM70020047':;

SECTION_NUMBER 1
 '@T6G_MB_LIB.T6G(SCH_1):PAGE271_I479@PURE_QUANTA.MOSFET_NCH_DUAL(CHIPS)':
 C_PATH='@t6g_mb_lib.t6g(sch_1):page271_i479@pure_quanta.mosfet_nch_dual(chips)';

SECTION_NUMBER 2
 '@T6G_MB_LIB.T6G(SCH_1):PAGE271_I477@PURE_QUANTA.MOSFET_NCH_DUAL(CHIPS)':
 C_PATH='@t6g_mb_lib.t6g(sch_1):page271_i477@pure_quanta.mosfet_nch_dual(chips)';

PART_NAME
 Q44 'MOSFET_PCH_GDS_ESD_PROTECTED-DMP2045U-7,SMLF,IC,BAM20450000':;

SECTION_NUMBER 1
 '@T6G_MB_LIB.T6G(SCH_1):PAGE271_I560@PURE_QUANTA.MOSFET_PCH_GDS_ESD_PROTECTED(CHIPS)':
 C_PATH='@t6g_mb_lib.t6g(sch_1):page271_i560@pure_quanta.mosfet_pch_gds_esd_prot~
ected(chips)';

PART_NAME
 J70 'SCONN168_623403212-SCONN168_6-2340321-2,SMLF,IO,DFHSG8FS003':;

SECTION_NUMBER 1
 '@T6G_MB_LIB.T6G(SCH_1):PAGE271_I324@PURE_QUANTA.SCONN168_623403212(CHIPS)':
 C_PATH='@t6g_mb_lib.t6g(sch_1):page271_i324@pure_quanta.sconn168_623403212(chip~
s)';

PART_NAME
 C1435 'Q_CAP_0402-0.22UF,16V,10%,X7R,CH4223K1B00':;

SECTION_NUMBER 1
 '@T6G_MB_LIB.T6G(SCH_1):PAGE271_I557@PURE_QUANTA.Q_CAP(CHIPS)':
 C_PATH='@t6g_mb_lib.t6g(sch_1):page271_i557@pure_quanta.q_cap(chips)';

PART_NAME
 C1434 'Q_CAP_0402-0.22UF,16V,10%,X7R,CH4223K1B00':;

SECTION_NUMBER 1
 '@T6G_MB_LIB.T6G(SCH_1):PAGE271_I565@PURE_QUANTA.Q_CAP(CHIPS)':
 C_PATH='@t6g_mb_lib.t6g(sch_1):page271_i565@pure_quanta.q_cap(chips)';

PART_NAME
 C1352 'Q_CAP_C0805-10UF,25V,10%,X6S,CH6104KEA00':;

SECTION_NUMBER 1
 '@T6G_MB_LIB.T6G(SCH_1):PAGE271_I551@PURE_QUANTA.Q_CAP(CHIPS)':
 C_PATH='@t6g_mb_lib.t6g(sch_1):page271_i551@pure_quanta.q_cap(chips)';

PART_NAME
 C1348 'Q_CAP_0402-0.22UF,16V,10%,EMPTY,CH4223K1B00':;

SECTION_NUMBER 1
 '@T6G_MB_LIB.T6G(SCH_1):PAGE271_I561@PURE_QUANTA.Q_CAP(CHIPS)':
 C_PATH='@t6g_mb_lib.t6g(sch_1):page271_i561@pure_quanta.q_cap(chips)';

PART_NAME
 C1302 'Q_CAP_C0402-10UF,4V,20%,X6S,CH610KMEB09':;

SECTION_NUMBER 1
 '@T6G_MB_LIB.T6G(SCH_1):PAGE271_I488@PURE_QUANTA.Q_CAP(CHIPS)':
 C_PATH='@t6g_mb_lib.t6g(sch_1):page271_i488@pure_quanta.q_cap(chips)';

PART_NAME
 U73 'MOSFET_N_SMLF-BSS138K,BSS138K,IC,BAM138K0000':;

SECTION_NUMBER 1
 '@T6G_MB_LIB.T6G(SCH_1):PAGE304_I32@PURE_QUANTA.MOSFET_N(CHIPS)':
 C_PATH='@t6g_mb_lib.t6g(sch_1):page304_i32@pure_quanta.mosfet_n(chips)';

PART_NAME
 R2336 'Q_RES_0402LF-26.1K,1%,1/16W,CHIP,CS32612FB09':;

SECTION_NUMBER 1
 '@T6G_MB_LIB.T6G(SCH_1):PAGE304_I29@PURE_QUANTA.Q_RES(CHIPS)':
 C_PATH='@t6g_mb_lib.t6g(sch_1):page304_i29@pure_quanta.q_res(chips)';

PART_NAME
 R2334 'Q_RES_0402LF-0,5%,1/16W,CHIP,CS00002JB38':;

SECTION_NUMBER 1
 '@T6G_MB_LIB.T6G(SCH_1):PAGE304_I28@PURE_QUANTA.Q_RES(CHIPS)':
 C_PATH='@t6g_mb_lib.t6g(sch_1):page304_i28@pure_quanta.q_res(chips)';

PART_NAME
 R2332 'Q_RES_0402LF-2K,1%,1/16W,CHIP,TMP_QCS22002FB19':;

SECTION_NUMBER 1
 '@T6G_MB_LIB.T6G(SCH_1):PAGE304_I16@PURE_QUANTA.Q_RES(CHIPS)':
 C_PATH='@t6g_mb_lib.t6g(sch_1):page304_i16@pure_quanta.q_res(chips)';

PART_NAME
 R2330 'Q_RES_0402LF-10K,1%,1/16W,EMPTY,TMP_QCS31002FB26':;

SECTION_NUMBER 1
 '@T6G_MB_LIB.T6G(SCH_1):PAGE304_I7@PURE_QUANTA.Q_RES(CHIPS)':
 C_PATH='@t6g_mb_lib.t6g(sch_1):page304_i7@pure_quanta.q_res(chips)';

PART_NAME
 PU79 'MPQ8633AGLEC807Z-MPQ8633AGLE-C807-Z,SMLF,IC,AL008633007':;

SECTION_NUMBER 1
 '@T6G_MB_LIB.T6G(SCH_1):PAGE304_I13@PURE_QUANTA.MPQ8633AGLEC807Z(CHIPS)':
 C_PATH='@t6g_mb_lib.t6g(sch_1):page304_i13@pure_quanta.mpq8633aglec807z(chips)';

PART_NAME
 PR1337 'Q_RES_0402LF-36K,1%,1/16W,CHIP,CS33602FB15':;

SECTION_NUMBER 1
 '@T6G_MB_LIB.T6G(SCH_1):PAGE304_I33@PURE_QUANTA.Q_RES(CHIPS)':
 C_PATH='@t6g_mb_lib.t6g(sch_1):page304_i33@pure_quanta.q_res(chips)';

PART_NAME
 PR1336 'Q_RES_0402LF-9.31K,1%,1/16W,CHIP,CS29312FB13':;

SECTION_NUMBER 1
 '@T6G_MB_LIB.T6G(SCH_1):PAGE304_I12@PURE_QUANTA.Q_RES(CHIPS)':
 C_PATH='@t6g_mb_lib.t6g(sch_1):page304_i12@pure_quanta.q_res(chips)';

PART_NAME
 PR1335 'Q_RES_0402LF-0,5%,1/16W,CHIP,CS00002JB38':;

SECTION_NUMBER 1
 '@T6G_MB_LIB.T6G(SCH_1):PAGE304_I5@PURE_QUANTA.Q_RES(CHIPS)':
 C_PATH='@t6g_mb_lib.t6g(sch_1):page304_i5@pure_quanta.q_res(chips)';

PART_NAME
 PR1310 'Q_RES_0402LF-18.2K,0.1%,1/16W,CHIP,CS31822BB00':;

SECTION_NUMBER 1
 '@T6G_MB_LIB.T6G(SCH_1):PAGE304_I22@PURE_QUANTA.Q_RES(CHIPS)':
 C_PATH='@t6g_mb_lib.t6g(sch_1):page304_i22@pure_quanta.q_res(chips)';

PART_NAME
 PR1309 'Q_RES_0402LF-10K,1%,1/16W,CHIP,TMP_QCS31002FB26':;

SECTION_NUMBER 1
 '@T6G_MB_LIB.T6G(SCH_1):PAGE304_I25@PURE_QUANTA.Q_RES(CHIPS)':
 C_PATH='@t6g_mb_lib.t6g(sch_1):page304_i25@pure_quanta.q_res(chips)';

PART_NAME
 PL118 'Q_INDUCTOR_SMLF-1UH,IND,CV-10B0MZ13':;

SECTION_NUMBER 1
 '@T6G_MB_LIB.T6G(SCH_1):PAGE304_I24@PURE_QUANTA.Q_INDUCTOR(CHIPS)':
 C_PATH='@t6g_mb_lib.t6g(sch_1):page304_i24@pure_quanta.q_inductor(chips)';

PART_NAME
 PC2643 'Q_CAP_C0402-1UF,25V,10%,X6S,CH5104KEB02':;

SECTION_NUMBER 1
 '@T6G_MB_LIB.T6G(SCH_1):PAGE304_I2@PURE_QUANTA.Q_CAP(CHIPS)':
 C_PATH='@t6g_mb_lib.t6g(sch_1):page304_i2@pure_quanta.q_cap(chips)';

PART_NAME
 PC1258 'Q_CAPP_THLF-560UF,6.3V,20%,OSCON,CC75601MD18':;

SECTION_NUMBER 1
 '@T6G_MB_LIB.T6G(SCH_1):PAGE304_I42@PURE_QUANTA.Q_CAPP(CHIPS)':
 C_PATH='@t6g_mb_lib.t6g(sch_1):page304_i42@pure_quanta.q_capp(chips)';

PART_NAME
 PC1257 'Q_CAP_0805-22UF,4V,20%,X6S,TMP_QCH622KMEA01':;

SECTION_NUMBER 1
 '@T6G_MB_LIB.T6G(SCH_1):PAGE304_I39@PURE_QUANTA.Q_CAP(CHIPS)':
 C_PATH='@t6g_mb_lib.t6g(sch_1):page304_i39@pure_quanta.q_cap(chips)';

PART_NAME
 PC1256 'Q_CAP_0805-22UF,4V,20%,X6S,TMP_QCH622KMEA01':;

SECTION_NUMBER 1
 '@T6G_MB_LIB.T6G(SCH_1):PAGE304_I38@PURE_QUANTA.Q_CAP(CHIPS)':
 C_PATH='@t6g_mb_lib.t6g(sch_1):page304_i38@pure_quanta.q_cap(chips)';

PART_NAME
 PC1255 'Q_CAP_0805-22UF,4V,20%,X6S,TMP_QCH622KMEA01':;

SECTION_NUMBER 1
 '@T6G_MB_LIB.T6G(SCH_1):PAGE304_I37@PURE_QUANTA.Q_CAP(CHIPS)':
 C_PATH='@t6g_mb_lib.t6g(sch_1):page304_i37@pure_quanta.q_cap(chips)';

PART_NAME
 PC1254 'Q_CAP_0402-0.1UF,25V,10%,X7R,CH4104K1B00':;

SECTION_NUMBER 1
 '@T6G_MB_LIB.T6G(SCH_1):PAGE304_I34@PURE_QUANTA.Q_CAP(CHIPS)':
 C_PATH='@t6g_mb_lib.t6g(sch_1):page304_i34@pure_quanta.q_cap(chips)';

PART_NAME
 PC1253 'Q_CAP_0402-100PF,50V,5%,NPO,CH11006JB00':;

SECTION_NUMBER 1
 '@T6G_MB_LIB.T6G(SCH_1):PAGE304_I30@PURE_QUANTA.Q_CAP(CHIPS)':
 C_PATH='@t6g_mb_lib.t6g(sch_1):page304_i30@pure_quanta.q_cap(chips)';

PART_NAME
 PC1252 'Q_CAP_0402-0.22UF,16V,10%,X7R,CH4223K1B00':;

SECTION_NUMBER 1
 '@T6G_MB_LIB.T6G(SCH_1):PAGE304_I23@PURE_QUANTA.Q_CAP(CHIPS)':
 C_PATH='@t6g_mb_lib.t6g(sch_1):page304_i23@pure_quanta.q_cap(chips)';

PART_NAME
 PC1251 'Q_CAP_0402-0.1UF,25V,10%,X7R,CH4104K1B00':;

SECTION_NUMBER 1
 '@T6G_MB_LIB.T6G(SCH_1):PAGE304_I20@PURE_QUANTA.Q_CAP(CHIPS)':
 C_PATH='@t6g_mb_lib.t6g(sch_1):page304_i20@pure_quanta.q_cap(chips)';

PART_NAME
 PC1249 'Q_CAP_0402-0.1UF,25V,10%,X7R,CH4104K1B00':;

SECTION_NUMBER 1
 '@T6G_MB_LIB.T6G(SCH_1):PAGE304_I18@PURE_QUANTA.Q_CAP(CHIPS)':
 C_PATH='@t6g_mb_lib.t6g(sch_1):page304_i18@pure_quanta.q_cap(chips)';

PART_NAME
 PC1248 'Q_CAP_C0805-22UF,16V,20%,X6S,CH6223MEA00':;

SECTION_NUMBER 1
 '@T6G_MB_LIB.T6G(SCH_1):PAGE304_I17@PURE_QUANTA.Q_CAP(CHIPS)':
 C_PATH='@t6g_mb_lib.t6g(sch_1):page304_i17@pure_quanta.q_cap(chips)';

PART_NAME
 PC1247 'Q_CAP_C0805-22UF,16V,20%,X6S,CH6223MEA00':;

SECTION_NUMBER 1
 '@T6G_MB_LIB.T6G(SCH_1):PAGE304_I10@PURE_QUANTA.Q_CAP(CHIPS)':
 C_PATH='@t6g_mb_lib.t6g(sch_1):page304_i10@pure_quanta.q_cap(chips)';

PART_NAME
 PC831 'Q_CAP_C0805-22UF,16V,20%,X6S,CH6223MEA00':;

SECTION_NUMBER 1
 '@T6G_MB_LIB.T6G(SCH_1):PAGE304_I44@PURE_QUANTA.Q_CAP(CHIPS)':
 C_PATH='@t6g_mb_lib.t6g(sch_1):page304_i44@pure_quanta.q_cap(chips)';

PART_NAME
 C1301 'Q_CAP_0402-1000PF,50V,5%,X7R,TMP_QCH21006JB10':;

SECTION_NUMBER 1
 '@T6G_MB_LIB.T6G(SCH_1):PAGE304_I27@PURE_QUANTA.Q_CAP(CHIPS)':
 C_PATH='@t6g_mb_lib.t6g(sch_1):page304_i27@pure_quanta.q_cap(chips)';

PART_NAME
 C1300 'Q_CAP_0402-1000PF,50V,5%,EMPTY,TMP_QCH21006JB10':;

SECTION_NUMBER 1
 '@T6G_MB_LIB.T6G(SCH_1):PAGE304_I14@PURE_QUANTA.Q_CAP(CHIPS)':
 C_PATH='@t6g_mb_lib.t6g(sch_1):page304_i14@pure_quanta.q_cap(chips)';

PART_NAME
 R2387 'Q_RES_0402LF-0,5%,1/16W,CHIP,CS00002JB38':;

SECTION_NUMBER 1
 '@T6G_MB_LIB.T6G(SCH_1):PAGE323_I183@PURE_QUANTA.Q_RES(CHIPS)':
 C_PATH='@t6g_mb_lib.t6g(sch_1):page323_i183@pure_quanta.q_res(chips)';

PART_NAME
 R2385 'Q_RES_0402LF-2K,1%,1/16W,CHIP,TMP_QCS22002FB19':;

SECTION_NUMBER 1
 '@T6G_MB_LIB.T6G(SCH_1):PAGE323_I168@PURE_QUANTA.Q_RES(CHIPS)':
 C_PATH='@t6g_mb_lib.t6g(sch_1):page323_i168@pure_quanta.q_res(chips)';

PART_NAME
 R2384 'Q_RES_0402LF-10K,1%,1/16W,EMPTY,TMP_QCS31002FB26':;

SECTION_NUMBER 1
 '@T6G_MB_LIB.T6G(SCH_1):PAGE323_I161@PURE_QUANTA.Q_RES(CHIPS)':
 C_PATH='@t6g_mb_lib.t6g(sch_1):page323_i161@pure_quanta.q_res(chips)';

PART_NAME
 PU82 'MPQ8626GDZ-MPQ8626GD-Z,SMLF,IC,AL008626000':;

SECTION_NUMBER 1
 '@T6G_MB_LIB.T6G(SCH_1):PAGE323_I198@PURE_QUANTA.MPQ8626GDZ(CHIPS)':
 C_PATH='@t6g_mb_lib.t6g(sch_1):page323_i198@pure_quanta.mpq8626gdz(chips)';

PART_NAME
 PR2222 'Q_RES_0402LF-9.09K,1%,1/16W,CHIP,CS29092FB27':;

SECTION_NUMBER 1
 '@T6G_MB_LIB.T6G(SCH_1):PAGE323_I177@PURE_QUANTA.Q_RES(CHIPS)':
 C_PATH='@t6g_mb_lib.t6g(sch_1):page323_i177@pure_quanta.q_res(chips)';

PART_NAME
 PR2220 'Q_RES_0402LF-60.4K,1%,1/16W,CHIP,CS36042FB10':;

SECTION_NUMBER 1
 '@T6G_MB_LIB.T6G(SCH_1):PAGE323_I171@PURE_QUANTA.Q_RES(CHIPS)':
 C_PATH='@t6g_mb_lib.t6g(sch_1):page323_i171@pure_quanta.q_res(chips)';

PART_NAME
 PR1320 'Q_RES_0402LF-10K,1%,1/16W,CHIP,TMP_QCS31002FB26':;

SECTION_NUMBER 1
 '@T6G_MB_LIB.T6G(SCH_1):PAGE323_I187@PURE_QUANTA.Q_RES(CHIPS)':
 C_PATH='@t6g_mb_lib.t6g(sch_1):page323_i187@pure_quanta.q_res(chips)';

PART_NAME
 PR502 'Q_RES_0402LF-8.25K,1%,1/16W,CHIP,CS28252FB03':;

SECTION_NUMBER 1
 '@T6G_MB_LIB.T6G(SCH_1):PAGE323_I190@PURE_QUANTA.Q_RES(CHIPS)':
 C_PATH='@t6g_mb_lib.t6g(sch_1):page323_i190@pure_quanta.q_res(chips)';

PART_NAME
 PR51 'Q_RES_0402LF-12.4K,1%,1/16W,CHIP,CS31242FB13':;

SECTION_NUMBER 1
 '@T6G_MB_LIB.T6G(SCH_1):PAGE323_I180@PURE_QUANTA.Q_RES(CHIPS)':
 C_PATH='@t6g_mb_lib.t6g(sch_1):page323_i180@pure_quanta.q_res(chips)';

PART_NAME
 PL121 'Q_INDUCTOR_SMLF-1UH,IND,CV-10B0MZ13':;

SECTION_NUMBER 1
 '@T6G_MB_LIB.T6G(SCH_1):PAGE323_I182@PURE_QUANTA.Q_INDUCTOR(CHIPS)':
 C_PATH='@t6g_mb_lib.t6g(sch_1):page323_i182@pure_quanta.q_inductor(chips)';

PART_NAME
 PC2222 'Q_CAP_C0402-1UF,25V,10%,X6S,CH5104KEB02':;

SECTION_NUMBER 1
 '@T6G_MB_LIB.T6G(SCH_1):PAGE323_I174@PURE_QUANTA.Q_CAP(CHIPS)':
 C_PATH='@t6g_mb_lib.t6g(sch_1):page323_i174@pure_quanta.q_cap(chips)';

PART_NAME
 PC1287 'Q_CAP_0805-22UF,4V,20%,X6S,TMP_QCH622KMEA01':;

SECTION_NUMBER 1
 '@T6G_MB_LIB.T6G(SCH_1):PAGE323_I194@PURE_QUANTA.Q_CAP(CHIPS)':
 C_PATH='@t6g_mb_lib.t6g(sch_1):page323_i194@pure_quanta.q_cap(chips)';

PART_NAME
 PC1286 'Q_CAP_0805-22UF,4V,20%,X6S,TMP_QCH622KMEA01':;

SECTION_NUMBER 1
 '@T6G_MB_LIB.T6G(SCH_1):PAGE323_I193@PURE_QUANTA.Q_CAP(CHIPS)':
 C_PATH='@t6g_mb_lib.t6g(sch_1):page323_i193@pure_quanta.q_cap(chips)';

PART_NAME
 PC1285 'Q_CAP_0805-22UF,4V,20%,X6S,TMP_QCH622KMEA01':;

SECTION_NUMBER 1
 '@T6G_MB_LIB.T6G(SCH_1):PAGE323_I192@PURE_QUANTA.Q_CAP(CHIPS)':
 C_PATH='@t6g_mb_lib.t6g(sch_1):page323_i192@pure_quanta.q_cap(chips)';

PART_NAME
 PC1284 'Q_CAP_C0402-100NF,50V,10%,X7R,CH4106K1B01':;

SECTION_NUMBER 1
 '@T6G_MB_LIB.T6G(SCH_1):PAGE323_I184@PURE_QUANTA.Q_CAP(CHIPS)':
 C_PATH='@t6g_mb_lib.t6g(sch_1):page323_i184@pure_quanta.q_cap(chips)';

PART_NAME
 PC1283 'Q_CAP_0402-0.22UF,16V,10%,X7R,CH4223K1B00':;

SECTION_NUMBER 1
 '@T6G_MB_LIB.T6G(SCH_1):PAGE323_I181@PURE_QUANTA.Q_CAP(CHIPS)':
 C_PATH='@t6g_mb_lib.t6g(sch_1):page323_i181@pure_quanta.q_cap(chips)';

PART_NAME
 PC1282 'Q_CAP_C0402-100NF,50V,10%,X7R,CH4106K1B01':;

SECTION_NUMBER 1
 '@T6G_MB_LIB.T6G(SCH_1):PAGE323_I175@PURE_QUANTA.Q_CAP(CHIPS)':
 C_PATH='@t6g_mb_lib.t6g(sch_1):page323_i175@pure_quanta.q_cap(chips)';

PART_NAME
 PC1281 'Q_CAP_C0805-22UF,16V,20%,X6S,CH6223MEA00':;

SECTION_NUMBER 1
 '@T6G_MB_LIB.T6G(SCH_1):PAGE323_I170@PURE_QUANTA.Q_CAP(CHIPS)':
 C_PATH='@t6g_mb_lib.t6g(sch_1):page323_i170@pure_quanta.q_cap(chips)';

PART_NAME
 PC1280 'Q_CAP_C0805-22UF,16V,20%,X6S,CH6223MEA00':;

SECTION_NUMBER 1
 '@T6G_MB_LIB.T6G(SCH_1):PAGE323_I169@PURE_QUANTA.Q_CAP(CHIPS)':
 C_PATH='@t6g_mb_lib.t6g(sch_1):page323_i169@pure_quanta.q_cap(chips)';

PART_NAME
 PC1207 'Q_CAP_0805-22UF,4V,20%,X6S,TMP_QCH622KMEA01':;

SECTION_NUMBER 1
 '@T6G_MB_LIB.T6G(SCH_1):PAGE323_I196@PURE_QUANTA.Q_CAP(CHIPS)':
 C_PATH='@t6g_mb_lib.t6g(sch_1):page323_i196@pure_quanta.q_cap(chips)';

PART_NAME
 PC238 'Q_CAP_0402-680PF,50V,10%,X7R,TMP_QCH16806KB17':;

SECTION_NUMBER 1
 '@T6G_MB_LIB.T6G(SCH_1):PAGE323_I189@PURE_QUANTA.Q_CAP(CHIPS)':
 C_PATH='@t6g_mb_lib.t6g(sch_1):page323_i189@pure_quanta.q_cap(chips)';

PART_NAME
 PC28 'Q_CAP_0402-3300PF,50V,10%,X7R,TMP_QCH2336K1B12':;

SECTION_NUMBER 1
 '@T6G_MB_LIB.T6G(SCH_1):PAGE323_I179@PURE_QUANTA.Q_CAP(CHIPS)':
 C_PATH='@t6g_mb_lib.t6g(sch_1):page323_i179@pure_quanta.q_cap(chips)';

PART_NAME
 C1308 'Q_CAP_0402-1000PF,50V,5%,EMPTY,TMP_QCH21006JB10':;

SECTION_NUMBER 1
 '@T6G_MB_LIB.T6G(SCH_1):PAGE323_I166@PURE_QUANTA.Q_CAP(CHIPS)':
 C_PATH='@t6g_mb_lib.t6g(sch_1):page323_i166@pure_quanta.q_cap(chips)';

PART_NAME
 C1297 'Q_CAP_0402-1000PF,50V,5%,X7R,TMP_QCH21006JB10':;

SECTION_NUMBER 1
 '@T6G_MB_LIB.T6G(SCH_1):PAGE323_I186@PURE_QUANTA.Q_CAP(CHIPS)':
 C_PATH='@t6g_mb_lib.t6g(sch_1):page323_i186@pure_quanta.q_cap(chips)';

PART_NAME
 R2338 'Q_RES_0402LF-10K,1%,1/16W,EMPTY,TMP_QCS31002FB26':;

SECTION_NUMBER 1
 '@T6G_MB_LIB.T6G(SCH_1):PAGE305_I156@PURE_QUANTA.Q_RES(CHIPS)':
 C_PATH='@t6g_mb_lib.t6g(sch_1):page305_i156@pure_quanta.q_res(chips)';

PART_NAME
 R1652 'Q_RES_0402LF-0,5%,1/16W,CHIP,CS00002JB38':;

SECTION_NUMBER 1
 '@T6G_MB_LIB.T6G(SCH_1):PAGE305_I173@PURE_QUANTA.Q_RES(CHIPS)':
 C_PATH='@t6g_mb_lib.t6g(sch_1):page305_i173@pure_quanta.q_res(chips)';

PART_NAME
 R1445 'Q_RES_0402LF-2K,1%,1/16W,CHIP,TMP_QCS22002FB19':;

SECTION_NUMBER 1
 '@T6G_MB_LIB.T6G(SCH_1):PAGE305_I155@PURE_QUANTA.Q_RES(CHIPS)':
 C_PATH='@t6g_mb_lib.t6g(sch_1):page305_i155@pure_quanta.q_res(chips)';

PART_NAME
 PU81 'MPQ8626GDZ-MPQ8626GD-Z,SMLF,IC,AL008626000':;

SECTION_NUMBER 1
 '@T6G_MB_LIB.T6G(SCH_1):PAGE305_I190@PURE_QUANTA.MPQ8626GDZ(CHIPS)':
 C_PATH='@t6g_mb_lib.t6g(sch_1):page305_i190@pure_quanta.mpq8626gdz(chips)';

PART_NAME
 PR1317 'Q_RES_0402LF-10K,1%,1/16W,CHIP,TMP_QCS31002FB26':;

SECTION_NUMBER 1
 '@T6G_MB_LIB.T6G(SCH_1):PAGE305_I174@PURE_QUANTA.Q_RES(CHIPS)':
 C_PATH='@t6g_mb_lib.t6g(sch_1):page305_i174@pure_quanta.q_res(chips)';

PART_NAME
 PR1303 'Q_RES_0402LF-9.09K,1%,1/16W,CHIP,CS29092FB27':;

SECTION_NUMBER 1
 '@T6G_MB_LIB.T6G(SCH_1):PAGE305_I161@PURE_QUANTA.Q_RES(CHIPS)':
 C_PATH='@t6g_mb_lib.t6g(sch_1):page305_i161@pure_quanta.q_res(chips)';

PART_NAME
 PR1301 'Q_RES_0402LF-60.4K,1%,1/16W,CHIP,CS36042FB10':;

SECTION_NUMBER 1
 '@T6G_MB_LIB.T6G(SCH_1):PAGE305_I162@PURE_QUANTA.Q_RES(CHIPS)':
 C_PATH='@t6g_mb_lib.t6g(sch_1):page305_i162@pure_quanta.q_res(chips)';

PART_NAME
 PR501 'Q_RES_0402LF-8.25K,1%,1/16W,CHIP,CS28252FB03':;

SECTION_NUMBER 1
 '@T6G_MB_LIB.T6G(SCH_1):PAGE305_I182@PURE_QUANTA.Q_RES(CHIPS)':
 C_PATH='@t6g_mb_lib.t6g(sch_1):page305_i182@pure_quanta.q_res(chips)';

PART_NAME
 PR50 'Q_RES_0402LF-12.4K,1%,1/16W,CHIP,CS31242FB13':;

SECTION_NUMBER 1
 '@T6G_MB_LIB.T6G(SCH_1):PAGE305_I172@PURE_QUANTA.Q_RES(CHIPS)':
 C_PATH='@t6g_mb_lib.t6g(sch_1):page305_i172@pure_quanta.q_res(chips)';

PART_NAME
 PL120 'Q_INDUCTOR_SMLF-1UH,IND,CV-10B0MZ13':;

SECTION_NUMBER 1
 '@T6G_MB_LIB.T6G(SCH_1):PAGE305_I180@PURE_QUANTA.Q_INDUCTOR(CHIPS)':
 C_PATH='@t6g_mb_lib.t6g(sch_1):page305_i180@pure_quanta.q_inductor(chips)';

PART_NAME
 PC2221 'Q_CAP_C0402-1UF,25V,10%,X6S,CH5104KEB02':;

SECTION_NUMBER 1
 '@T6G_MB_LIB.T6G(SCH_1):PAGE305_I159@PURE_QUANTA.Q_CAP(CHIPS)':
 C_PATH='@t6g_mb_lib.t6g(sch_1):page305_i159@pure_quanta.q_cap(chips)';

PART_NAME
 PC1279 'Q_CAP_0805-22UF,4V,20%,X6S,TMP_QCH622KMEA01':;

SECTION_NUMBER 1
 '@T6G_MB_LIB.T6G(SCH_1):PAGE305_I186@PURE_QUANTA.Q_CAP(CHIPS)':
 C_PATH='@t6g_mb_lib.t6g(sch_1):page305_i186@pure_quanta.q_cap(chips)';

PART_NAME
 PC1278 'Q_CAP_0805-22UF,4V,20%,X6S,TMP_QCH622KMEA01':;

SECTION_NUMBER 1
 '@T6G_MB_LIB.T6G(SCH_1):PAGE305_I185@PURE_QUANTA.Q_CAP(CHIPS)':
 C_PATH='@t6g_mb_lib.t6g(sch_1):page305_i185@pure_quanta.q_cap(chips)';

PART_NAME
 PC1277 'Q_CAP_0805-22UF,4V,20%,X6S,TMP_QCH622KMEA01':;

SECTION_NUMBER 1
 '@T6G_MB_LIB.T6G(SCH_1):PAGE305_I184@PURE_QUANTA.Q_CAP(CHIPS)':
 C_PATH='@t6g_mb_lib.t6g(sch_1):page305_i184@pure_quanta.q_cap(chips)';

PART_NAME
 PC1276 'Q_CAP_C0402-100NF,50V,10%,X7R,CH4106K1B01':;

SECTION_NUMBER 1
 '@T6G_MB_LIB.T6G(SCH_1):PAGE305_I183@PURE_QUANTA.Q_CAP(CHIPS)':
 C_PATH='@t6g_mb_lib.t6g(sch_1):page305_i183@pure_quanta.q_cap(chips)';

PART_NAME
 PC1275 'Q_CAP_0402-0.22UF,16V,10%,X7R,CH4223K1B00':;

SECTION_NUMBER 1
 '@T6G_MB_LIB.T6G(SCH_1):PAGE305_I176@PURE_QUANTA.Q_CAP(CHIPS)':
 C_PATH='@t6g_mb_lib.t6g(sch_1):page305_i176@pure_quanta.q_cap(chips)';

PART_NAME
 PC1274 'Q_CAP_C0402-100NF,50V,10%,X7R,CH4106K1B01':;

SECTION_NUMBER 1
 '@T6G_MB_LIB.T6G(SCH_1):PAGE305_I166@PURE_QUANTA.Q_CAP(CHIPS)':
 C_PATH='@t6g_mb_lib.t6g(sch_1):page305_i166@pure_quanta.q_cap(chips)';

PART_NAME
 PC1273 'Q_CAP_C0805-22UF,16V,20%,X6S,CH6223MEA00':;

SECTION_NUMBER 1
 '@T6G_MB_LIB.T6G(SCH_1):PAGE305_I165@PURE_QUANTA.Q_CAP(CHIPS)':
 C_PATH='@t6g_mb_lib.t6g(sch_1):page305_i165@pure_quanta.q_cap(chips)';

PART_NAME
 PC1272 'Q_CAP_C0805-22UF,16V,20%,X6S,CH6223MEA00':;

SECTION_NUMBER 1
 '@T6G_MB_LIB.T6G(SCH_1):PAGE305_I164@PURE_QUANTA.Q_CAP(CHIPS)':
 C_PATH='@t6g_mb_lib.t6g(sch_1):page305_i164@pure_quanta.q_cap(chips)';

PART_NAME
 PC1206 'Q_CAP_0805-22UF,4V,20%,X6S,TMP_QCH622KMEA01':;

SECTION_NUMBER 1
 '@T6G_MB_LIB.T6G(SCH_1):PAGE305_I188@PURE_QUANTA.Q_CAP(CHIPS)':
 C_PATH='@t6g_mb_lib.t6g(sch_1):page305_i188@pure_quanta.q_cap(chips)';

PART_NAME
 PC237 'Q_CAP_0402-680PF,50V,10%,X7R,TMP_QCH16806KB17':;

SECTION_NUMBER 1
 '@T6G_MB_LIB.T6G(SCH_1):PAGE305_I179@PURE_QUANTA.Q_CAP(CHIPS)':
 C_PATH='@t6g_mb_lib.t6g(sch_1):page305_i179@pure_quanta.q_cap(chips)';

PART_NAME
 PC27 'Q_CAP_0402-3300PF,50V,10%,X7R,TMP_QCH2336K1B12':;

SECTION_NUMBER 1
 '@T6G_MB_LIB.T6G(SCH_1):PAGE305_I169@PURE_QUANTA.Q_CAP(CHIPS)':
 C_PATH='@t6g_mb_lib.t6g(sch_1):page305_i169@pure_quanta.q_cap(chips)';

PART_NAME
 C1307 'Q_CAP_0402-1000PF,50V,5%,EMPTY,TMP_QCH21006JB10':;

SECTION_NUMBER 1
 '@T6G_MB_LIB.T6G(SCH_1):PAGE305_I154@PURE_QUANTA.Q_CAP(CHIPS)':
 C_PATH='@t6g_mb_lib.t6g(sch_1):page305_i154@pure_quanta.q_cap(chips)';

PART_NAME
 C1296 'Q_CAP_0402-1000PF,50V,5%,X7R,TMP_QCH21006JB10':;

SECTION_NUMBER 1
 '@T6G_MB_LIB.T6G(SCH_1):PAGE305_I178@PURE_QUANTA.Q_CAP(CHIPS)':
 C_PATH='@t6g_mb_lib.t6g(sch_1):page305_i178@pure_quanta.q_cap(chips)';

PART_NAME
 R1649 'Q_RES_0402LF-2K,1%,1/16W,CHIP,TMP_QCS22002FB19':;

SECTION_NUMBER 1
 '@T6G_MB_LIB.T6G(SCH_1):PAGE285_I161@PURE_QUANTA.Q_RES(CHIPS)':
 C_PATH='@t6g_mb_lib.t6g(sch_1):page285_i161@pure_quanta.q_res(chips)';

PART_NAME
 PU73 'MPQ8633BGLEC838Z-MPQ8633BGLE-C838-Z,SMLF,IC,AL008633005':;

SECTION_NUMBER 1
 '@T6G_MB_LIB.T6G(SCH_1):PAGE285_I169@PURE_QUANTA.MPQ8633BGLEC838Z(CHIPS)':
 C_PATH='@s6q_mb_lib.s6q(sch_1):page285_i169@pure_quanta.mpq8633bglec838z(chips)~
';

PART_NAME
 PR2390 'Q_RES_0402LF-0,5%,1/16W,CHIP,CS00002JB38':;

SECTION_NUMBER 1
 '@T6G_MB_LIB.T6G(SCH_1):PAGE285_I181@PURE_QUANTA.Q_RES(CHIPS)':
 C_PATH='@t6g_mb_lib.t6g(sch_1):page285_i181@pure_quanta.q_res(chips)';

PART_NAME
 PR1650 'Q_RES_0402LF-0,5%,1/16W,CHIP,CS00002JB38':;

SECTION_NUMBER 1
 '@T6G_MB_LIB.T6G(SCH_1):PAGE285_I180@PURE_QUANTA.Q_RES(CHIPS)':
 C_PATH='@t6g_mb_lib.t6g(sch_1):page285_i180@pure_quanta.q_res(chips)';

PART_NAME
 PR1647 'Q_RES_0402LF-10K,1%,1/16W,EMPTY,TMP_QCS31002FB26':;

SECTION_NUMBER 1
 '@T6G_MB_LIB.T6G(SCH_1):PAGE285_I163@PURE_QUANTA.Q_RES(CHIPS)':
 C_PATH='@t6g_mb_lib.t6g(sch_1):page285_i163@pure_quanta.q_res(chips)';

PART_NAME
 PR1389 'Q_RES_0402LF-0,5%,1/16W,CHIP,CS00002JB38':;

SECTION_NUMBER 1
 '@T6G_MB_LIB.T6G(SCH_1):PAGE285_I158@PURE_QUANTA.Q_RES(CHIPS)':
 C_PATH='@t6g_mb_lib.t6g(sch_1):page285_i158@pure_quanta.q_res(chips)';

PART_NAME
 PR1388 'Q_RES_0402LF-0,5%,1/16W,EMPTY,CS00002JB38':;

SECTION_NUMBER 1
 '@T6G_MB_LIB.T6G(SCH_1):PAGE285_I162@PURE_QUANTA.Q_RES(CHIPS)':
 C_PATH='@t6g_mb_lib.t6g(sch_1):page285_i162@pure_quanta.q_res(chips)';

PART_NAME
 PR1328 'Q_RES_0402LF-7.32K,1%,1/16W,CHIP,TMP_QCS27322FB12':;

SECTION_NUMBER 1
 '@T6G_MB_LIB.T6G(SCH_1):PAGE285_I178@PURE_QUANTA.Q_RES(CHIPS)':
 C_PATH='@t6g_mb_lib.t6g(sch_1):page285_i178@pure_quanta.q_res(chips)';

PART_NAME
 PR1327 'Q_RES_0402LF-6.81K,1%,1/16W,CHIP,CS26812FB13':;

SECTION_NUMBER 1
 '@T6G_MB_LIB.T6G(SCH_1):PAGE285_I168@PURE_QUANTA.Q_RES(CHIPS)':
 C_PATH='@t6g_mb_lib.t6g(sch_1):page285_i168@pure_quanta.q_res(chips)';

PART_NAME
 PR1326 'Q_RES_0402LF-0,5%,1/16W,CHIP,CS00002JB38':;

SECTION_NUMBER 1
 '@T6G_MB_LIB.T6G(SCH_1):PAGE285_I156@PURE_QUANTA.Q_RES(CHIPS)':
 C_PATH='@t6g_mb_lib.t6g(sch_1):page285_i156@pure_quanta.q_res(chips)';

PART_NAME
 PR187 'Q_RES_0402LF-10K,1%,1/16W,CHIP,TMP_QCS31002FB26':;

SECTION_NUMBER 1
 '@T6G_MB_LIB.T6G(SCH_1):PAGE285_I173@PURE_QUANTA.Q_RES(CHIPS)':
 C_PATH='@t6g_mb_lib.t6g(sch_1):page285_i173@pure_quanta.q_res(chips)';

PART_NAME
 PR186 'Q_RES_0402LF-10K,1%,1/16W,CHIP,TMP_QCS31002FB26':;

SECTION_NUMBER 1
 '@T6G_MB_LIB.T6G(SCH_1):PAGE285_I176@PURE_QUANTA.Q_RES(CHIPS)':
 C_PATH='@t6g_mb_lib.t6g(sch_1):page285_i176@pure_quanta.q_res(chips)';

PART_NAME
 PL150 'Q_INDUCTOR_SMLF-300NH/33A,IND,CV+30Y0KZ05':;

SECTION_NUMBER 1
 '@T6G_MB_LIB.T6G(SCH_1):PAGE285_I179@PURE_QUANTA.Q_INDUCTOR(CHIPS)':
 C_PATH='@t6g_mb_lib.t6g(sch_1):page285_i179@pure_quanta.q_inductor(chips)';

PART_NAME
 PL110 'Q_INDUCTOR_SMLF-100NH/16A,IND,CV+10G0MZ04':;

SECTION_NUMBER 1
 '@T6G_MB_LIB.T6G(SCH_1):PAGE285_I146@PURE_QUANTA.Q_INDUCTOR(CHIPS)':
 C_PATH='@t6g_mb_lib.t6g(sch_1):page285_i146@pure_quanta.q_inductor(chips)';

PART_NAME
 PJ62 'Q_SHORT_SM-EMPTY,SHORT6':;

SECTION_NUMBER 1
 '@T6G_MB_LIB.T6G(SCH_1):PAGE285_I191@PURE_QUANTA.Q_SHORT(CHIPS)':
 C_PATH='@t6g_mb_lib.t6g(sch_1):page285_i191@pure_quanta.q_short(chips)';

PART_NAME
 PC1230 'Q_CAPP_THLF-560UF,2.5V,20%,OSCON,CC7560JMD18':;

SECTION_NUMBER 1
 '@T6G_MB_LIB.T6G(SCH_1):PAGE285_I185@PURE_QUANTA.Q_CAPP(CHIPS)':
 C_PATH='@t6g_mb_lib.t6g(sch_1):page285_i185@pure_quanta.q_capp(chips)';

PART_NAME
 PC1229 'Q_CAPP_RDLLF-470UF,2V,20%,EMPTY,CH747RM8811':;

SECTION_NUMBER 1
 '@T6G_MB_LIB.T6G(SCH_1):PAGE285_I194@PURE_QUANTA.Q_CAPP(CHIPS)':
 C_PATH='@t6g_mb_lib.t6g(sch_1):page285_i194@pure_quanta.q_capp(chips)';

PART_NAME
 PC1227 'Q_CAPP_THLF-560UF,2.5V,20%,OSCON,CC7560JMD18':;

SECTION_NUMBER 1
 '@T6G_MB_LIB.T6G(SCH_1):PAGE285_I184@PURE_QUANTA.Q_CAPP(CHIPS)':
 C_PATH='@t6g_mb_lib.t6g(sch_1):page285_i184@pure_quanta.q_capp(chips)';

PART_NAME
 PC1226 'Q_CAP_0805-47UF,4V,20%,X6S,CH647KMEA00':;

SECTION_NUMBER 1
 '@T6G_MB_LIB.T6G(SCH_1):PAGE285_I192@PURE_QUANTA.Q_CAP(CHIPS)':
 C_PATH='@t6g_mb_lib.t6g(sch_1):page285_i192@pure_quanta.q_cap(chips)';

PART_NAME
 PC1225 'Q_CAP_0805-47UF,4V,20%,X6S,CH647KMEA00':;

SECTION_NUMBER 1
 '@T6G_MB_LIB.T6G(SCH_1):PAGE285_I188@PURE_QUANTA.Q_CAP(CHIPS)':
 C_PATH='@t6g_mb_lib.t6g(sch_1):page285_i188@pure_quanta.q_cap(chips)';

PART_NAME
 PC1224 'Q_CAP_0402-0.1UF,25V,10%,X7R,CH4104K1B00':;

SECTION_NUMBER 1
 '@T6G_MB_LIB.T6G(SCH_1):PAGE285_I187@PURE_QUANTA.Q_CAP(CHIPS)':
 C_PATH='@t6g_mb_lib.t6g(sch_1):page285_i187@pure_quanta.q_cap(chips)';

PART_NAME
 PC1223 'Q_CAP_C0402-470PF,50V,5%,NPO,CH1476J0B08':;

SECTION_NUMBER 1
 '@T6G_MB_LIB.T6G(SCH_1):PAGE285_I174@PURE_QUANTA.Q_CAP(CHIPS)':
 C_PATH='@t6g_mb_lib.t6g(sch_1):page285_i174@pure_quanta.q_cap(chips)';

PART_NAME
 PC1222 'Q_CAP_0402-0.22UF,16V,10%,X7R,CH4223K1B00':;

SECTION_NUMBER 1
 '@T6G_MB_LIB.T6G(SCH_1):PAGE285_I175@PURE_QUANTA.Q_CAP(CHIPS)':
 C_PATH='@t6g_mb_lib.t6g(sch_1):page285_i175@pure_quanta.q_cap(chips)';

PART_NAME
 PC1221 'Q_CAP_0402-0.1UF,25V,10%,X7R,CH4104K1B00':;

SECTION_NUMBER 1
 '@T6G_MB_LIB.T6G(SCH_1):PAGE285_I171@PURE_QUANTA.Q_CAP(CHIPS)':
 C_PATH='@t6g_mb_lib.t6g(sch_1):page285_i171@pure_quanta.q_cap(chips)';

PART_NAME
 PC1219 'Q_CAP_0402-0.1UF,25V,10%,X7R,CH4104K1B00':;

SECTION_NUMBER 1
 '@T6G_MB_LIB.T6G(SCH_1):PAGE285_I166@PURE_QUANTA.Q_CAP(CHIPS)':
 C_PATH='@t6g_mb_lib.t6g(sch_1):page285_i166@pure_quanta.q_cap(chips)';

PART_NAME
 PC1218 'Q_CAP_C0805-22UF,16V,20%,X6S,CH6223MEA00':;

SECTION_NUMBER 1
 '@T6G_MB_LIB.T6G(SCH_1):PAGE285_I165@PURE_QUANTA.Q_CAP(CHIPS)':
 C_PATH='@t6g_mb_lib.t6g(sch_1):page285_i165@pure_quanta.q_cap(chips)';

PART_NAME
 PC1217 'Q_CAP_C0805-22UF,16V,20%,X6S,CH6223MEA00':;

SECTION_NUMBER 1
 '@T6G_MB_LIB.T6G(SCH_1):PAGE285_I164@PURE_QUANTA.Q_CAP(CHIPS)':
 C_PATH='@t6g_mb_lib.t6g(sch_1):page285_i164@pure_quanta.q_cap(chips)';

PART_NAME
 PC1216 'Q_CAP_C0805-22UF,16V,20%,X6S,CH6223MEA00':;

SECTION_NUMBER 1
 '@T6G_MB_LIB.T6G(SCH_1):PAGE285_I155@PURE_QUANTA.Q_CAP(CHIPS)':
 C_PATH='@t6g_mb_lib.t6g(sch_1):page285_i155@pure_quanta.q_cap(chips)';

PART_NAME
 PC1215 'Q_CAPP_SMLF-100UF,16V,20%,OSCON,CC71003MZ32':;

SECTION_NUMBER 1
 '@T6G_MB_LIB.T6G(SCH_1):PAGE285_I153@PURE_QUANTA.Q_CAPP(CHIPS)':
 C_PATH='@t6g_mb_lib.t6g(sch_1):page285_i153@pure_quanta.q_capp(chips)';

PART_NAME
 PC117 'Q_CAPP_RDLLF-470UF,2V,20%,C_POSCAP,CH747RM8811':;

SECTION_NUMBER 1
 '@T6G_MB_LIB.T6G(SCH_1):PAGE285_I182@PURE_QUANTA.Q_CAPP(CHIPS)':
 C_PATH='@t6g_mb_lib.t6g(sch_1):page285_i182@pure_quanta.q_capp(chips)';

PART_NAME
 PC113 'Q_CAP_C0402-1UF,25V,10%,X6S,CH5104KEB02':;

SECTION_NUMBER 1
 '@T6G_MB_LIB.T6G(SCH_1):PAGE285_I149@PURE_QUANTA.Q_CAP(CHIPS)':
 C_PATH='@t6g_mb_lib.t6g(sch_1):page285_i149@pure_quanta.q_cap(chips)';

PART_NAME
 C1286 'Q_CAP_0402-1000PF,50V,5%,EMPTY,TMP_QCH21006JB10':;

SECTION_NUMBER 1
 '@T6G_MB_LIB.T6G(SCH_1):PAGE285_I160@PURE_QUANTA.Q_CAP(CHIPS)':
 C_PATH='@t6g_mb_lib.t6g(sch_1):page285_i160@pure_quanta.q_cap(chips)';

PART_NAME
 U191 'SN74LVC1G08DBVR_SMLF-SN74LVC1G08DBVR,IC,AL1G0008012':;

SECTION_NUMBER 1
 '@T6G_MB_LIB.T6G(SCH_1):PAGE143_I368@PURE_QUANTA.SN74LVC1G08DBVR(CHIPS)':
 C_PATH='@t6g_mb_lib.t6g(sch_1):page143_i368@pure_quanta.sn74lvc1g08dbvr(chips)';

PART_NAME
 R3790 'Q_RES_0402LF-0,5%,1/16W,EMPTY,CS00002JB38':;

SECTION_NUMBER 1
 '@T6G_MB_LIB.T6G(SCH_1):PAGE143_I409@PURE_QUANTA.Q_RES(CHIPS)':
 C_PATH='@t6g_mb_lib.t6g(sch_1):page143_i409@pure_quanta.q_res(chips)';

PART_NAME
 R3789 'Q_RES_0402LF-0,5%,1/16W,CHIP,CS00002JB38':;

SECTION_NUMBER 1
 '@T6G_MB_LIB.T6G(SCH_1):PAGE143_I408@PURE_QUANTA.Q_RES(CHIPS)':
 C_PATH='@t6g_mb_lib.t6g(sch_1):page143_i408@pure_quanta.q_res(chips)';

PART_NAME
 R3533 'Q_RES_0402LF-100K,5%,1/16W,CHIP,CS41002JB20':;

SECTION_NUMBER 1
 '@T6G_MB_LIB.T6G(SCH_1):PAGE143_I377@PURE_QUANTA.Q_RES(CHIPS)':
 C_PATH='@t6g_mb_lib.t6g(sch_1):page143_i377@pure_quanta.q_res(chips)';

PART_NAME
 R3532 'Q_RES_0402LF-10K,1%,1/16W,CHIP,TMP_QCS31002FB26':;

SECTION_NUMBER 1
 '@T6G_MB_LIB.T6G(SCH_1):PAGE143_I376@PURE_QUANTA.Q_RES(CHIPS)':
 C_PATH='@t6g_mb_lib.t6g(sch_1):page143_i376@pure_quanta.q_res(chips)';

PART_NAME
 R1988 'Q_RES_0402LF-100,1%,1/16W,CHIP,TMP_QCS11002FB22':;

SECTION_NUMBER 1
 '@T6G_MB_LIB.T6G(SCH_1):PAGE143_I287@PURE_QUANTA.Q_RES(CHIPS)':
 C_PATH='@t6g_mb_lib.t6g(sch_1):page143_i287@pure_quanta.q_res(chips)';

PART_NAME
 R1987 'Q_RES_0402LF-10K,1%,1/16W,EMPTY,TMP_QCS31002FB26':;

SECTION_NUMBER 1
 '@T6G_MB_LIB.T6G(SCH_1):PAGE143_I284@PURE_QUANTA.Q_RES(CHIPS)':
 C_PATH='@t6g_mb_lib.t6g(sch_1):page143_i284@pure_quanta.q_res(chips)';

PART_NAME
 R1923 'Q_RES_0402LF-4.7K,5%,1/16W,CHIP,TMP_QCS24702JB38':;

SECTION_NUMBER 1
 '@T6G_MB_LIB.T6G(SCH_1):PAGE143_I306@PURE_QUANTA.Q_RES(CHIPS)':
 C_PATH='@t6g_mb_lib.t6g(sch_1):page143_i306@pure_quanta.q_res(chips)';

PART_NAME
 R1922 'Q_RES_0402LF-1K,1%,1/16W,EMPTY,TMP_QCS21002FB24':;

SECTION_NUMBER 1
 '@T6G_MB_LIB.T6G(SCH_1):PAGE143_I305@PURE_QUANTA.Q_RES(CHIPS)':
 C_PATH='@t6g_mb_lib.t6g(sch_1):page143_i305@pure_quanta.q_res(chips)';

PART_NAME
 R1921 'Q_RES_0402LF-0,5%,1/16W,CHIP,CS00002JB38':;

SECTION_NUMBER 1
 '@T6G_MB_LIB.T6G(SCH_1):PAGE143_I272@PURE_QUANTA.Q_RES(CHIPS)':
 C_PATH='@t6g_mb_lib.t6g(sch_1):page143_i272@pure_quanta.q_res(chips)';

PART_NAME
 R1918 'Q_RES_0402LF-0,5%,1/16W,CHIP,CS00002JB38':;

SECTION_NUMBER 1
 '@T6G_MB_LIB.T6G(SCH_1):PAGE143_I270@PURE_QUANTA.Q_RES(CHIPS)':
 C_PATH='@t6g_mb_lib.t6g(sch_1):page143_i270@pure_quanta.q_res(chips)';

PART_NAME
 R1915 'Q_RES_0402LF-0,5%,1/16W,CHIP,CS00002JB38':;

SECTION_NUMBER 1
 '@T6G_MB_LIB.T6G(SCH_1):PAGE143_I268@PURE_QUANTA.Q_RES(CHIPS)':
 C_PATH='@t6g_mb_lib.t6g(sch_1):page143_i268@pure_quanta.q_res(chips)';

PART_NAME
 R1913 'Q_RES_0402LF-100,1%,1/16W,CHIP,TMP_QCS11002FB22':;

SECTION_NUMBER 1
 '@T6G_MB_LIB.T6G(SCH_1):PAGE143_I318@PURE_QUANTA.Q_RES(CHIPS)':
 C_PATH='@t6g_mb_lib.t6g(sch_1):page143_i318@pure_quanta.q_res(chips)';

PART_NAME
 R1529 'Q_RES_0402LF-0,5%,1/16W,CHIP,CS00002JB38':;

SECTION_NUMBER 1
 '@T6G_MB_LIB.T6G(SCH_1):PAGE143_I90@PURE_QUANTA.Q_RES(CHIPS)':
 C_PATH='@t6g_mb_lib.t6g(sch_1):page143_i90@pure_quanta.q_res(chips)';

PART_NAME
 R1493 'Q_RES_0402LF-0,5%,1/16W,CHIP,CS00002JB38':;

SECTION_NUMBER 1
 '@T6G_MB_LIB.T6G(SCH_1):PAGE143_I89@PURE_QUANTA.Q_RES(CHIPS)':
 C_PATH='@t6g_mb_lib.t6g(sch_1):page143_i89@pure_quanta.q_res(chips)';

PART_NAME
 R925 'Q_RES_0402LF-0,5%,1/16W,CHIP,CS00002JB38':;

SECTION_NUMBER 1
 '@T6G_MB_LIB.T6G(SCH_1):PAGE143_I260@PURE_QUANTA.Q_RES(CHIPS)':
 C_PATH='@t6g_mb_lib.t6g(sch_1):page143_i260@pure_quanta.q_res(chips)';

PART_NAME
 R881 'Q_RES_0402LF-100K,5%,1/16W,CHIP,CS41002JB20':;

SECTION_NUMBER 1
 '@T6G_MB_LIB.T6G(SCH_1):PAGE143_I378@PURE_QUANTA.Q_RES(CHIPS)':
 C_PATH='@t6g_mb_lib.t6g(sch_1):page143_i378@pure_quanta.q_res(chips)';

PART_NAME
 R451 'Q_RES_0402LF-0,5%,1/16W,CHIP,CS00002JB38':;

SECTION_NUMBER 1
 '@T6G_MB_LIB.T6G(SCH_1):PAGE143_I271@PURE_QUANTA.Q_RES(CHIPS)':
 C_PATH='@t6g_mb_lib.t6g(sch_1):page143_i271@pure_quanta.q_res(chips)';

PART_NAME
 R449 'Q_RES_0402LF-0,5%,1/16W,CHIP,CS00002JB38':;

SECTION_NUMBER 1
 '@T6G_MB_LIB.T6G(SCH_1):PAGE143_I269@PURE_QUANTA.Q_RES(CHIPS)':
 C_PATH='@t6g_mb_lib.t6g(sch_1):page143_i269@pure_quanta.q_res(chips)';

PART_NAME
 R439 'Q_RES_0402LF-0,5%,1/16W,EMPTY,CS00002JB38':;

SECTION_NUMBER 1
 '@T6G_MB_LIB.T6G(SCH_1):PAGE143_I308@PURE_QUANTA.Q_RES(CHIPS)':
 C_PATH='@t6g_mb_lib.t6g(sch_1):page143_i308@pure_quanta.q_res(chips)';

PART_NAME
 R438 'Q_RES_0402LF-1K,1%,1/16W,EMPTY,TMP_QCS21002FB24':;

SECTION_NUMBER 1
 '@T6G_MB_LIB.T6G(SCH_1):PAGE143_I307@PURE_QUANTA.Q_RES(CHIPS)':
 C_PATH='@t6g_mb_lib.t6g(sch_1):page143_i307@pure_quanta.q_res(chips)';

PART_NAME
 R430 'Q_RES_0402LF-4.7K,1%,1/16W,EMPTY,CS24702FB10':;

SECTION_NUMBER 1
 '@T6G_MB_LIB.T6G(SCH_1):PAGE143_I315@PURE_QUANTA.Q_RES(CHIPS)':
 C_PATH='@t6g_mb_lib.t6g(sch_1):page143_i315@pure_quanta.q_res(chips)';

PART_NAME
 R427 'Q_RES_0402LF-100,1%,1/16W,CHIP,TMP_QCS11002FB22':;

SECTION_NUMBER 1
 '@T6G_MB_LIB.T6G(SCH_1):PAGE143_I320@PURE_QUANTA.Q_RES(CHIPS)':
 C_PATH='@t6g_mb_lib.t6g(sch_1):page143_i320@pure_quanta.q_res(chips)';

PART_NAME
 R426 'Q_RES_0402LF-4.7K,1%,1/16W,EMPTY,CS24702FB10':;

SECTION_NUMBER 1
 '@T6G_MB_LIB.T6G(SCH_1):PAGE143_I317@PURE_QUANTA.Q_RES(CHIPS)':
 C_PATH='@t6g_mb_lib.t6g(sch_1):page143_i317@pure_quanta.q_res(chips)';

PART_NAME
 J81 'SCONN168_623403214-SCONN168_6-2340321-4,SMLF,IO,DFHSG8FS012':;

SECTION_NUMBER 1
 '@T6G_MB_LIB.T6G(SCH_1):PAGE143_I1@PURE_QUANTA.SCONN168_623403214(CHIPS)':
 C_PATH='@s6q_mb_lib.s6q(sch_1):page143_i1@pure_quanta.sconn168_623403214(chips)~
';

PART_NAME
 C2819 'Q_CAP_0402-0.1UF,25V,10%,X7R,CH4104K1B00':;

SECTION_NUMBER 1
 '@T6G_MB_LIB.T6G(SCH_1):PAGE143_I367@PURE_QUANTA.Q_CAP(CHIPS)':
 C_PATH='@t6g_mb_lib.t6g(sch_1):page143_i367@pure_quanta.q_cap(chips)';

PART_NAME
 C2432 'Q_CAP_0402-0.1UF,25V,10%,X7R,CH4104K1B00':;

SECTION_NUMBER 1
 '@T6G_MB_LIB.T6G(SCH_1):PAGE143_I289@PURE_QUANTA.Q_CAP(CHIPS)':
 C_PATH='@t6g_mb_lib.t6g(sch_1):page143_i289@pure_quanta.q_cap(chips)';

PART_NAME
 C2431 'Q_CAP_0402-0.1UF,25V,10%,X7R,CH4104K1B00':;

SECTION_NUMBER 1
 '@T6G_MB_LIB.T6G(SCH_1):PAGE143_I295@PURE_QUANTA.Q_CAP(CHIPS)':
 C_PATH='@t6g_mb_lib.t6g(sch_1):page143_i295@pure_quanta.q_cap(chips)';

PART_NAME
 C2430 'Q_CAP_0402-0.1UF,25V,10%,X7R,CH4104K1B00':;

SECTION_NUMBER 1
 '@T6G_MB_LIB.T6G(SCH_1):PAGE143_I297@PURE_QUANTA.Q_CAP(CHIPS)':
 C_PATH='@t6g_mb_lib.t6g(sch_1):page143_i297@pure_quanta.q_cap(chips)';

PART_NAME
 C2429 'Q_CAP_0402-0.1UF,25V,10%,X7R,CH4104K1B00':;

SECTION_NUMBER 1
 '@T6G_MB_LIB.T6G(SCH_1):PAGE143_I298@PURE_QUANTA.Q_CAP(CHIPS)':
 C_PATH='@t6g_mb_lib.t6g(sch_1):page143_i298@pure_quanta.q_cap(chips)';

PART_NAME
 C2428 'Q_CAP_0402-0.1UF,25V,10%,X7R,CH4104K1B00':;

SECTION_NUMBER 1
 '@T6G_MB_LIB.T6G(SCH_1):PAGE143_I299@PURE_QUANTA.Q_CAP(CHIPS)':
 C_PATH='@t6g_mb_lib.t6g(sch_1):page143_i299@pure_quanta.q_cap(chips)';

PART_NAME
 C2427 'Q_CAP_C0805-22UF,16V,20%,X6S,CH6223MEA00':;

SECTION_NUMBER 1
 '@T6G_MB_LIB.T6G(SCH_1):PAGE143_I301@PURE_QUANTA.Q_CAP(CHIPS)':
 C_PATH='@t6g_mb_lib.t6g(sch_1):page143_i301@pure_quanta.q_cap(chips)';

PART_NAME
 C2426 'Q_CAP_C0805-22UF,16V,20%,X6S,CH6223MEA00':;

SECTION_NUMBER 1
 '@T6G_MB_LIB.T6G(SCH_1):PAGE143_I302@PURE_QUANTA.Q_CAP(CHIPS)':
 C_PATH='@t6g_mb_lib.t6g(sch_1):page143_i302@pure_quanta.q_cap(chips)';

PART_NAME
 C1284 'Q_CAP_0402-0.1UF,25V,10%,X7R,CH4104K1B00':;

SECTION_NUMBER 1
 '@T6G_MB_LIB.T6G(SCH_1):PAGE143_I291@PURE_QUANTA.Q_CAP(CHIPS)':
 C_PATH='@t6g_mb_lib.t6g(sch_1):page143_i291@pure_quanta.q_cap(chips)';

PART_NAME
 C1283 'Q_CAP_0402-0.1UF,25V,10%,X7R,CH4104K1B00':;

SECTION_NUMBER 1
 '@T6G_MB_LIB.T6G(SCH_1):PAGE143_I293@PURE_QUANTA.Q_CAP(CHIPS)':
 C_PATH='@t6g_mb_lib.t6g(sch_1):page143_i293@pure_quanta.q_cap(chips)';

PART_NAME
 C1282 'Q_CAP_0402-0.1UF,25V,10%,X7R,CH4104K1B00':;

SECTION_NUMBER 1
 '@T6G_MB_LIB.T6G(SCH_1):PAGE143_I294@PURE_QUANTA.Q_CAP(CHIPS)':
 C_PATH='@t6g_mb_lib.t6g(sch_1):page143_i294@pure_quanta.q_cap(chips)';

PART_NAME
 R3720 'Q_RES_0402LF-100K,5%,1/16W,CHIP,CS41002JB20':;

SECTION_NUMBER 1
 '@T6G_MB_LIB.T6G(SCH_1):PAGE140_I545@PURE_QUANTA.Q_RES(CHIPS)':
 C_PATH='@t6g_mb_lib.t6g(sch_1):page140_i545@pure_quanta.q_res(chips)';

PART_NAME
 R3549 'Q_RES_0402LF-0,5%,1/16W,CHIP,CS00002JB38':;

SECTION_NUMBER 1
 '@T6G_MB_LIB.T6G(SCH_1):PAGE140_I538@PURE_QUANTA.Q_RES(CHIPS)':
 C_PATH='@t6g_mb_lib.t6g(sch_1):page140_i538@pure_quanta.q_res(chips)';

PART_NAME
 R1912 'Q_RES_0402LF-100,1%,1/16W,CHIP,TMP_QCS11002FB22':;

SECTION_NUMBER 1
 '@T6G_MB_LIB.T6G(SCH_1):PAGE140_I523@PURE_QUANTA.Q_RES(CHIPS)':
 C_PATH='@t6g_mb_lib.t6g(sch_1):page140_i523@pure_quanta.q_res(chips)';

PART_NAME
 R1911 'Q_RES_0402LF-10K,1%,1/16W,EMPTY,TMP_QCS31002FB26':;

SECTION_NUMBER 1
 '@T6G_MB_LIB.T6G(SCH_1):PAGE140_I522@PURE_QUANTA.Q_RES(CHIPS)':
 C_PATH='@t6g_mb_lib.t6g(sch_1):page140_i522@pure_quanta.q_res(chips)';

PART_NAME
 R1910 'Q_RES_0402LF-100,1%,1/16W,CHIP,TMP_QCS11002FB22':;

SECTION_NUMBER 1
 '@T6G_MB_LIB.T6G(SCH_1):PAGE140_I514@PURE_QUANTA.Q_RES(CHIPS)':
 C_PATH='@t6g_mb_lib.t6g(sch_1):page140_i514@pure_quanta.q_res(chips)';

PART_NAME
 R1909 'Q_RES_0402LF-4.7K,1%,1/16W,EMPTY,CS24702FB10':;

SECTION_NUMBER 1
 '@T6G_MB_LIB.T6G(SCH_1):PAGE140_I512@PURE_QUANTA.Q_RES(CHIPS)':
 C_PATH='@t6g_mb_lib.t6g(sch_1):page140_i512@pure_quanta.q_res(chips)';

PART_NAME
 R1908 'Q_RES_0402LF-100,1%,1/16W,CHIP,TMP_QCS11002FB22':;

SECTION_NUMBER 1
 '@T6G_MB_LIB.T6G(SCH_1):PAGE140_I516@PURE_QUANTA.Q_RES(CHIPS)':
 C_PATH='@t6g_mb_lib.t6g(sch_1):page140_i516@pure_quanta.q_res(chips)';

PART_NAME
 R1907 'Q_RES_0402LF-4.7K,1%,1/16W,EMPTY,CS24702FB10':;

SECTION_NUMBER 1
 '@T6G_MB_LIB.T6G(SCH_1):PAGE140_I513@PURE_QUANTA.Q_RES(CHIPS)':
 C_PATH='@t6g_mb_lib.t6g(sch_1):page140_i513@pure_quanta.q_res(chips)';

PART_NAME
 R1671 'Q_RES_0402LF-0,5%,1/16W,EMPTY,CS00002JB38':;

SECTION_NUMBER 1
 '@T6G_MB_LIB.T6G(SCH_1):PAGE140_I536@PURE_QUANTA.Q_RES(CHIPS)':
 C_PATH='@t6g_mb_lib.t6g(sch_1):page140_i536@pure_quanta.q_res(chips)';

PART_NAME
 R1511 'Q_RES_0402LF-0,5%,1/16W,CHIP,CS00002JB38':;

SECTION_NUMBER 1
 '@T6G_MB_LIB.T6G(SCH_1):PAGE140_I354@PURE_QUANTA.Q_RES(CHIPS)':
 C_PATH='@t6g_mb_lib.t6g(sch_1):page140_i354@pure_quanta.q_res(chips)';

PART_NAME
 R1510 'Q_RES_0402LF-0,5%,1/16W,CHIP,CS00002JB38':;

SECTION_NUMBER 1
 '@T6G_MB_LIB.T6G(SCH_1):PAGE140_I451@PURE_QUANTA.Q_RES(CHIPS)':
 C_PATH='@t6g_mb_lib.t6g(sch_1):page140_i451@pure_quanta.q_res(chips)';

PART_NAME
 R880 'Q_RES_0402LF-100K,5%,1/16W,CHIP,CS41002JB20':;

SECTION_NUMBER 1
 '@T6G_MB_LIB.T6G(SCH_1):PAGE140_I546@PURE_QUANTA.Q_RES(CHIPS)':
 C_PATH='@t6g_mb_lib.t6g(sch_1):page140_i546@pure_quanta.q_res(chips)';

PART_NAME
 R879 'Q_RES_0402LF-10K,1%,1/16W,CHIP,TMP_QCS31002FB26':;

SECTION_NUMBER 1
 '@T6G_MB_LIB.T6G(SCH_1):PAGE140_I544@PURE_QUANTA.Q_RES(CHIPS)':
 C_PATH='@t6g_mb_lib.t6g(sch_1):page140_i544@pure_quanta.q_res(chips)';

PART_NAME
 R445 'Q_RES_0402LF-0,5%,1/16W,CHIP,CS00002JB38':;

SECTION_NUMBER 1
 '@T6G_MB_LIB.T6G(SCH_1):PAGE140_I355@PURE_QUANTA.Q_RES(CHIPS)':
 C_PATH='@t6g_mb_lib.t6g(sch_1):page140_i355@pure_quanta.q_res(chips)';

PART_NAME
 R429 'Q_RES_0402LF-0,5%,1/16W,CHIP,CS00002JB38':;

SECTION_NUMBER 1
 '@T6G_MB_LIB.T6G(SCH_1):PAGE140_I449@PURE_QUANTA.Q_RES(CHIPS)':
 C_PATH='@t6g_mb_lib.t6g(sch_1):page140_i449@pure_quanta.q_res(chips)';

PART_NAME
 R425 'Q_RES_0402LF-33,5%,1/16W,CHIP,CS03302JB29':;

SECTION_NUMBER 1
 '@T6G_MB_LIB.T6G(SCH_1):PAGE140_I350@PURE_QUANTA.Q_RES(CHIPS)':
 C_PATH='@t6g_mb_lib.t6g(sch_1):page140_i350@pure_quanta.q_res(chips)';

PART_NAME
 R424 'Q_RES_0402LF-33,5%,1/16W,CHIP,CS03302JB29':;

SECTION_NUMBER 1
 '@T6G_MB_LIB.T6G(SCH_1):PAGE140_I349@PURE_QUANTA.Q_RES(CHIPS)':
 C_PATH='@t6g_mb_lib.t6g(sch_1):page140_i349@pure_quanta.q_res(chips)';

PART_NAME
 R423 'Q_RES_0402LF-0,5%,1/16W,EMPTY,CS00002JB38':;

SECTION_NUMBER 1
 '@T6G_MB_LIB.T6G(SCH_1):PAGE140_I505@PURE_QUANTA.Q_RES(CHIPS)':
 C_PATH='@t6g_mb_lib.t6g(sch_1):page140_i505@pure_quanta.q_res(chips)';

PART_NAME
 R422 'Q_RES_0402LF-1K,1%,1/16W,EMPTY,TMP_QCS21002FB24':;

SECTION_NUMBER 1
 '@T6G_MB_LIB.T6G(SCH_1):PAGE140_I504@PURE_QUANTA.Q_RES(CHIPS)':
 C_PATH='@t6g_mb_lib.t6g(sch_1):page140_i504@pure_quanta.q_res(chips)';

PART_NAME
 R421 'Q_RES_0402LF-4.7K,5%,1/16W,CHIP,TMP_QCS24702JB38':;

SECTION_NUMBER 1
 '@T6G_MB_LIB.T6G(SCH_1):PAGE140_I500@PURE_QUANTA.Q_RES(CHIPS)':
 C_PATH='@t6g_mb_lib.t6g(sch_1):page140_i500@pure_quanta.q_res(chips)';

PART_NAME
 R420 'Q_RES_0402LF-1K,1%,1/16W,EMPTY,TMP_QCS21002FB24':;

SECTION_NUMBER 1
 '@T6G_MB_LIB.T6G(SCH_1):PAGE140_I499@PURE_QUANTA.Q_RES(CHIPS)':
 C_PATH='@t6g_mb_lib.t6g(sch_1):page140_i499@pure_quanta.q_res(chips)';

PART_NAME
 R418 'Q_RES_0402LF-0,5%,1/16W,CHIP,CS00002JB38':;

SECTION_NUMBER 1
 '@T6G_MB_LIB.T6G(SCH_1):PAGE140_I452@PURE_QUANTA.Q_RES(CHIPS)':
 C_PATH='@t6g_mb_lib.t6g(sch_1):page140_i452@pure_quanta.q_res(chips)';

PART_NAME
 R417 'Q_RES_0402LF-0,5%,1/16W,CHIP,CS00002JB38':;

SECTION_NUMBER 1
 '@T6G_MB_LIB.T6G(SCH_1):PAGE140_I450@PURE_QUANTA.Q_RES(CHIPS)':
 C_PATH='@t6g_mb_lib.t6g(sch_1):page140_i450@pure_quanta.q_res(chips)';

PART_NAME
 J80 'SCONN168_623403214-SCONN168_6-2340321-4,SMLF,IO,DFHSG8FS012':;

SECTION_NUMBER 1
 '@T6G_MB_LIB.T6G(SCH_1):PAGE140_I526@PURE_QUANTA.SCONN168_623403214(CHIPS)':
 C_PATH='@t6g_mb_lib.t6g(sch_1):page140_i526@pure_quanta.sconn168_623403214(chip~
s)';

PART_NAME
 C2425 'Q_CAP_0402-0.1UF,25V,10%,X7R,CH4104K1B00':;

SECTION_NUMBER 1
 '@T6G_MB_LIB.T6G(SCH_1):PAGE140_I486@PURE_QUANTA.Q_CAP(CHIPS)':
 C_PATH='@t6g_mb_lib.t6g(sch_1):page140_i486@pure_quanta.q_cap(chips)';

PART_NAME
 C2424 'Q_CAP_0402-0.1UF,25V,10%,X7R,CH4104K1B00':;

SECTION_NUMBER 1
 '@T6G_MB_LIB.T6G(SCH_1):PAGE140_I487@PURE_QUANTA.Q_CAP(CHIPS)':
 C_PATH='@t6g_mb_lib.t6g(sch_1):page140_i487@pure_quanta.q_cap(chips)';

PART_NAME
 C2423 'Q_CAP_0402-0.1UF,25V,10%,X7R,CH4104K1B00':;

SECTION_NUMBER 1
 '@T6G_MB_LIB.T6G(SCH_1):PAGE140_I489@PURE_QUANTA.Q_CAP(CHIPS)':
 C_PATH='@t6g_mb_lib.t6g(sch_1):page140_i489@pure_quanta.q_cap(chips)';

PART_NAME
 C2422 'Q_CAP_0402-0.1UF,25V,10%,X7R,CH4104K1B00':;

SECTION_NUMBER 1
 '@T6G_MB_LIB.T6G(SCH_1):PAGE140_I490@PURE_QUANTA.Q_CAP(CHIPS)':
 C_PATH='@t6g_mb_lib.t6g(sch_1):page140_i490@pure_quanta.q_cap(chips)';

PART_NAME
 C2421 'Q_CAP_0402-0.1UF,25V,10%,X7R,CH4104K1B00':;

SECTION_NUMBER 1
 '@T6G_MB_LIB.T6G(SCH_1):PAGE140_I494@PURE_QUANTA.Q_CAP(CHIPS)':
 C_PATH='@t6g_mb_lib.t6g(sch_1):page140_i494@pure_quanta.q_cap(chips)';

PART_NAME
 C2420 'Q_CAP_C0805-22UF,16V,20%,X6S,CH6223MEA00':;

SECTION_NUMBER 1
 '@T6G_MB_LIB.T6G(SCH_1):PAGE140_I495@PURE_QUANTA.Q_CAP(CHIPS)':
 C_PATH='@t6g_mb_lib.t6g(sch_1):page140_i495@pure_quanta.q_cap(chips)';

PART_NAME
 C2419 'Q_CAP_C0805-22UF,16V,20%,X6S,CH6223MEA00':;

SECTION_NUMBER 1
 '@T6G_MB_LIB.T6G(SCH_1):PAGE140_I496@PURE_QUANTA.Q_CAP(CHIPS)':
 C_PATH='@t6g_mb_lib.t6g(sch_1):page140_i496@pure_quanta.q_cap(chips)';

PART_NAME
 C1240 'Q_CAP_0402-0.1UF,25V,10%,X7R,CH4104K1B00':;

SECTION_NUMBER 1
 '@T6G_MB_LIB.T6G(SCH_1):PAGE140_I476@PURE_QUANTA.Q_CAP(CHIPS)':
 C_PATH='@t6g_mb_lib.t6g(sch_1):page140_i476@pure_quanta.q_cap(chips)';

PART_NAME
 C1239 'Q_CAP_0402-0.1UF,25V,10%,X7R,CH4104K1B00':;

SECTION_NUMBER 1
 '@T6G_MB_LIB.T6G(SCH_1):PAGE140_I484@PURE_QUANTA.Q_CAP(CHIPS)':
 C_PATH='@t6g_mb_lib.t6g(sch_1):page140_i484@pure_quanta.q_cap(chips)';

PART_NAME
 C1238 'Q_CAP_0402-0.1UF,25V,10%,X7R,CH4104K1B00':;

SECTION_NUMBER 1
 '@T6G_MB_LIB.T6G(SCH_1):PAGE140_I485@PURE_QUANTA.Q_CAP(CHIPS)':
 C_PATH='@t6g_mb_lib.t6g(sch_1):page140_i485@pure_quanta.q_cap(chips)';

PART_NAME
 C2554 'Q_CAP_DIFFBUS_C0201-DIFF BUS_0.22UF,6.3V,20%,X6S,SP_CH4221MEE01':;

SECTION_NUMBER 1
 '@T6G_MB_LIB.T6G(SCH_1):PAGE144_I103@PURE_QUANTA.Q_CAP_DIFFBUS(CHIPS)':
 C_PATH='@t6g_mb_lib.t6g(sch_1):page144_i103@pure_quanta.q_cap_diffbus(chips)';

PART_NAME
 C2553 'Q_CAP_DIFFBUS_C0201-DIFF BUS_0.22UF,6.3V,20%,X6S,SP_CH4221MEE01':
;

SECTION_NUMBER 1
 '@T6G_MB_LIB.T6G(SCH_1):PAGE144_I3@PURE_QUANTA.Q_CAP_DIFFBUS(CHIPS)':
 C_PATH='@t6g_mb_lib.t6g(sch_1):page144_i3@pure_quanta.q_cap_diffbus(chips)';

PART_NAME
 C2552 'Q_CAP_DIFFBUS_C0201-DIFF BUS_0.22UF,6.3V,20%,X6S,SP_CH4221MEE01':
;

SECTION_NUMBER 1
 '@T6G_MB_LIB.T6G(SCH_1):PAGE144_I18@PURE_QUANTA.Q_CAP_DIFFBUS(CHIPS)':
 C_PATH='@t6g_mb_lib.t6g(sch_1):page144_i18@pure_quanta.q_cap_diffbus(chips)';

PART_NAME
 C2551 'Q_CAP_DIFFBUS_C0201-DIFF BUS_0.22UF,6.3V,20%,X6S,SP_CH4221MEE01':
;

SECTION_NUMBER 1
 '@T6G_MB_LIB.T6G(SCH_1):PAGE144_I19@PURE_QUANTA.Q_CAP_DIFFBUS(CHIPS)':
 C_PATH='@t6g_mb_lib.t6g(sch_1):page144_i19@pure_quanta.q_cap_diffbus(chips)';

PART_NAME
 C2550 'Q_CAP_DIFFBUS_C0201-DIFF BUS_0.22UF,6.3V,20%,X6S,SP_CH4221MEE01':
;

SECTION_NUMBER 1
 '@T6G_MB_LIB.T6G(SCH_1):PAGE144_I20@PURE_QUANTA.Q_CAP_DIFFBUS(CHIPS)':
 C_PATH='@t6g_mb_lib.t6g(sch_1):page144_i20@pure_quanta.q_cap_diffbus(chips)';

PART_NAME
 C2549 'Q_CAP_DIFFBUS_C0201-DIFF BUS_0.22UF,6.3V,20%,X6S,SP_CH4221MEE01':
;

SECTION_NUMBER 1
 '@T6G_MB_LIB.T6G(SCH_1):PAGE144_I24@PURE_QUANTA.Q_CAP_DIFFBUS(CHIPS)':
 C_PATH='@t6g_mb_lib.t6g(sch_1):page144_i24@pure_quanta.q_cap_diffbus(chips)';

PART_NAME
 C2548 'Q_CAP_DIFFBUS_C0201-DIFF BUS_0.22UF,6.3V,20%,X6S,SP_CH4221MEE01':
;

SECTION_NUMBER 1
 '@T6G_MB_LIB.T6G(SCH_1):PAGE144_I25@PURE_QUANTA.Q_CAP_DIFFBUS(CHIPS)':
 C_PATH='@t6g_mb_lib.t6g(sch_1):page144_i25@pure_quanta.q_cap_diffbus(chips)';

PART_NAME
 C2547 'Q_CAP_DIFFBUS_C0201-DIFF BUS_0.22UF,6.3V,20%,X6S,SP_CH4221MEE01':
;

SECTION_NUMBER 1
 '@T6G_MB_LIB.T6G(SCH_1):PAGE144_I44@PURE_QUANTA.Q_CAP_DIFFBUS(CHIPS)':
 C_PATH='@t6g_mb_lib.t6g(sch_1):page144_i44@pure_quanta.q_cap_diffbus(chips)';

PART_NAME
 C2546 'Q_CAP_DIFFBUS_C0201-DIFF BUS_0.22UF,6.3V,20%,X6S,SP_CH4221MEE01':;

SECTION_NUMBER 1
 '@T6G_MB_LIB.T6G(SCH_1):PAGE144_I101@PURE_QUANTA.Q_CAP_DIFFBUS(CHIPS)':
 C_PATH='@t6g_mb_lib.t6g(sch_1):page144_i101@pure_quanta.q_cap_diffbus(chips)';

PART_NAME
 C2545 'Q_CAP_DIFFBUS_C0201-DIFF BUS_0.22UF,6.3V,20%,X6S,SP_CH4221MEE01':
;

SECTION_NUMBER 1
 '@T6G_MB_LIB.T6G(SCH_1):PAGE144_I21@PURE_QUANTA.Q_CAP_DIFFBUS(CHIPS)':
 C_PATH='@t6g_mb_lib.t6g(sch_1):page144_i21@pure_quanta.q_cap_diffbus(chips)';

PART_NAME
 C2544 'Q_CAP_DIFFBUS_C0201-DIFF BUS_0.22UF,6.3V,20%,X6S,SP_CH4221MEE01':
;

SECTION_NUMBER 1
 '@T6G_MB_LIB.T6G(SCH_1):PAGE144_I22@PURE_QUANTA.Q_CAP_DIFFBUS(CHIPS)':
 C_PATH='@t6g_mb_lib.t6g(sch_1):page144_i22@pure_quanta.q_cap_diffbus(chips)';

PART_NAME
 C1335 'Q_CAP_DIFFBUS_C0201-DIFF BUS_0.22UF,6.3V,20%,X6S,SP_CH4221MEE01':;

SECTION_NUMBER 1
 '@T6G_MB_LIB.T6G(SCH_1):PAGE144_I53@PURE_QUANTA.Q_CAP_DIFFBUS(CHIPS)':
 C_PATH='@t6g_mb_lib.t6g(sch_1):page144_i53@pure_quanta.q_cap_diffbus(chips)';

PART_NAME
 C1334 'Q_CAP_DIFFBUS_C0201-DIFF BUS_0.22UF,6.3V,20%,X6S,SP_CH4221MEE01':
;

SECTION_NUMBER 1
 '@T6G_MB_LIB.T6G(SCH_1):PAGE144_I69@PURE_QUANTA.Q_CAP_DIFFBUS(CHIPS)':
 C_PATH='@t6g_mb_lib.t6g(sch_1):page144_i69@pure_quanta.q_cap_diffbus(chips)';

PART_NAME
 C1326 'Q_CAP_DIFFBUS_C0201-DIFF BUS_0.22UF,6.3V,20%,X6S,SP_CH4221MEE01':
;

SECTION_NUMBER 1
 '@T6G_MB_LIB.T6G(SCH_1):PAGE144_I100@PURE_QUANTA.Q_CAP_DIFFBUS(CHIPS)':
 C_PATH='@t6g_mb_lib.t6g(sch_1):page144_i100@pure_quanta.q_cap_diffbus(chips)';

PART_NAME
 C1304 'Q_CAP_DIFFBUS_C0201-DIFF BUS_0.22UF,6.3V,20%,X6S,SP_CH4221MEE01':
;

SECTION_NUMBER 1
 '@T6G_MB_LIB.T6G(SCH_1):PAGE144_I73@PURE_QUANTA.Q_CAP_DIFFBUS(CHIPS)':
 C_PATH='@t6g_mb_lib.t6g(sch_1):page144_i73@pure_quanta.q_cap_diffbus(chips)';

PART_NAME
 C1303 'Q_CAP_DIFFBUS_C0201-DIFF BUS_0.22UF,6.3V,20%,X6S,SP_CH4221MEE01':
;

SECTION_NUMBER 1
 '@T6G_MB_LIB.T6G(SCH_1):PAGE144_I80@PURE_QUANTA.Q_CAP_DIFFBUS(CHIPS)':
 C_PATH='@t6g_mb_lib.t6g(sch_1):page144_i80@pure_quanta.q_cap_diffbus(chips)';

PART_NAME
 C1299 'Q_CAP_DIFFBUS_C0201-DIFF BUS_0.22UF,6.3V,20%,X6S,SP_CH4221MEE01':
;

SECTION_NUMBER 1
 '@T6G_MB_LIB.T6G(SCH_1):PAGE144_I83@PURE_QUANTA.Q_CAP_DIFFBUS(CHIPS)':
 C_PATH='@t6g_mb_lib.t6g(sch_1):page144_i83@pure_quanta.q_cap_diffbus(chips)';

PART_NAME
 C1295 'Q_CAP_DIFFBUS_C0201-DIFF BUS_0.22UF,6.3V,20%,X6S,SP_CH4221MEE01':
;

SECTION_NUMBER 1
 '@T6G_MB_LIB.T6G(SCH_1):PAGE144_I93@PURE_QUANTA.Q_CAP_DIFFBUS(CHIPS)':
 C_PATH='@t6g_mb_lib.t6g(sch_1):page144_i93@pure_quanta.q_cap_diffbus(chips)';

PART_NAME
 C1294 'Q_CAP_DIFFBUS_C0201-DIFF BUS_0.22UF,6.3V,20%,X6S,SP_CH4221MEE01':
;

SECTION_NUMBER 1
 '@T6G_MB_LIB.T6G(SCH_1):PAGE144_I96@PURE_QUANTA.Q_CAP_DIFFBUS(CHIPS)':
 C_PATH='@t6g_mb_lib.t6g(sch_1):page144_i96@pure_quanta.q_cap_diffbus(chips)';

PART_NAME
 C1285 'Q_CAP_DIFFBUS_C0201-DIFF BUS_0.22UF,6.3V,20%,X6S,SP_CH4221MEE01':
;

SECTION_NUMBER 1
 '@T6G_MB_LIB.T6G(SCH_1):PAGE144_I55@PURE_QUANTA.Q_CAP_DIFFBUS(CHIPS)':
 C_PATH='@t6g_mb_lib.t6g(sch_1):page144_i55@pure_quanta.q_cap_diffbus(chips)';

PART_NAME
 C1281 'Q_CAP_DIFFBUS_C0201-DIFF BUS_0.22UF,6.3V,20%,X6S,SP_CH4221MEE01':
;

SECTION_NUMBER 1
 '@T6G_MB_LIB.T6G(SCH_1):PAGE144_I67@PURE_QUANTA.Q_CAP_DIFFBUS(CHIPS)':
 C_PATH='@t6g_mb_lib.t6g(sch_1):page144_i67@pure_quanta.q_cap_diffbus(chips)';

PART_NAME
 C1280 'Q_CAP_DIFFBUS_C0201-DIFF BUS_0.22UF,6.3V,20%,X6S,SP_CH4221MEE01':
;

SECTION_NUMBER 1
 '@T6G_MB_LIB.T6G(SCH_1):PAGE144_I68@PURE_QUANTA.Q_CAP_DIFFBUS(CHIPS)':
 C_PATH='@t6g_mb_lib.t6g(sch_1):page144_i68@pure_quanta.q_cap_diffbus(chips)';

PART_NAME
 C1279 'Q_CAP_DIFFBUS_C0201-DIFF BUS_0.22UF,6.3V,20%,X6S,SP_CH4221MEE01':
;

SECTION_NUMBER 1
 '@T6G_MB_LIB.T6G(SCH_1):PAGE144_I77@PURE_QUANTA.Q_CAP_DIFFBUS(CHIPS)':
 C_PATH='@t6g_mb_lib.t6g(sch_1):page144_i77@pure_quanta.q_cap_diffbus(chips)';

PART_NAME
 C1278 'Q_CAP_DIFFBUS_C0201-DIFF BUS_0.22UF,6.3V,20%,X6S,SP_CH4221MEE01':
;

SECTION_NUMBER 1
 '@T6G_MB_LIB.T6G(SCH_1):PAGE144_I79@PURE_QUANTA.Q_CAP_DIFFBUS(CHIPS)':
 C_PATH='@t6g_mb_lib.t6g(sch_1):page144_i79@pure_quanta.q_cap_diffbus(chips)';

PART_NAME
 C1277 'Q_CAP_DIFFBUS_C0201-DIFF BUS_0.22UF,6.3V,20%,X6S,SP_CH4221MEE01':
;

SECTION_NUMBER 1
 '@T6G_MB_LIB.T6G(SCH_1):PAGE144_I78@PURE_QUANTA.Q_CAP_DIFFBUS(CHIPS)':
 C_PATH='@t6g_mb_lib.t6g(sch_1):page144_i78@pure_quanta.q_cap_diffbus(chips)';

PART_NAME
 C1276 'Q_CAP_DIFFBUS_C0201-DIFF BUS_0.22UF,6.3V,20%,X6S,SP_CH4221MEE01':
;

SECTION_NUMBER 1
 '@T6G_MB_LIB.T6G(SCH_1):PAGE144_I91@PURE_QUANTA.Q_CAP_DIFFBUS(CHIPS)':
 C_PATH='@t6g_mb_lib.t6g(sch_1):page144_i91@pure_quanta.q_cap_diffbus(chips)';

PART_NAME
 C1237 'Q_CAP_DIFFBUS_C0201-DIFF BUS_0.22UF,6.3V,20%,X6S,SP_CH4221MEE01':
;

SECTION_NUMBER 1
 '@T6G_MB_LIB.T6G(SCH_1):PAGE144_I4@PURE_QUANTA.Q_CAP_DIFFBUS(CHIPS)':
 C_PATH='@t6g_mb_lib.t6g(sch_1):page144_i4@pure_quanta.q_cap_diffbus(chips)';

PART_NAME
 C1236 'Q_CAP_DIFFBUS_C0201-DIFF BUS_0.22UF,6.3V,20%,X6S,SP_CH4221MEE01':
;

SECTION_NUMBER 1
 '@T6G_MB_LIB.T6G(SCH_1):PAGE144_I16@PURE_QUANTA.Q_CAP_DIFFBUS(CHIPS)':
 C_PATH='@t6g_mb_lib.t6g(sch_1):page144_i16@pure_quanta.q_cap_diffbus(chips)';

PART_NAME
 C1199 'Q_CAP_DIFFBUS_C0201-DIFF BUS_0.22UF,6.3V,20%,X6S,SP_CH4221MEE01':
;

SECTION_NUMBER 1
 '@T6G_MB_LIB.T6G(SCH_1):PAGE144_I17@PURE_QUANTA.Q_CAP_DIFFBUS(CHIPS)':
 C_PATH='@t6g_mb_lib.t6g(sch_1):page144_i17@pure_quanta.q_cap_diffbus(chips)';

PART_NAME
 C1196 'Q_CAP_DIFFBUS_C0201-DIFF BUS_0.22UF,6.3V,20%,X6S,SP_CH4221MEE01':
;

SECTION_NUMBER 1
 '@T6G_MB_LIB.T6G(SCH_1):PAGE144_I23@PURE_QUANTA.Q_CAP_DIFFBUS(CHIPS)':
 C_PATH='@t6g_mb_lib.t6g(sch_1):page144_i23@pure_quanta.q_cap_diffbus(chips)';

PART_NAME
 C1195 'Q_CAP_DIFFBUS_C0201-DIFF BUS_0.22UF,6.3V,20%,X6S,SP_CH4221MEE01':
;

SECTION_NUMBER 1
 '@T6G_MB_LIB.T6G(SCH_1):PAGE144_I42@PURE_QUANTA.Q_CAP_DIFFBUS(CHIPS)':
 C_PATH='@t6g_mb_lib.t6g(sch_1):page144_i42@pure_quanta.q_cap_diffbus(chips)';

PART_NAME
 C1194 'Q_CAP_DIFFBUS_C0201-DIFF BUS_0.22UF,6.3V,20%,X6S,SP_CH4221MEE01':;

SECTION_NUMBER 1
 '@T6G_MB_LIB.T6G(SCH_1):PAGE144_I102@PURE_QUANTA.Q_CAP_DIFFBUS(CHIPS)':
 C_PATH='@t6g_mb_lib.t6g(sch_1):page144_i102@pure_quanta.q_cap_diffbus(chips)';

PART_NAME
 R1464 'Q_RES_0402LF-0,5%,1/16W,CHIP,CS00002JB38':;

SECTION_NUMBER 1
 '@T6G_MB_LIB.T6G(SCH_1):PAGE186_I273@PURE_QUANTA.Q_RES(CHIPS)':
 C_PATH='@t6g_mb_lib.t6g(sch_1):page186_i273@pure_quanta.q_res(chips)';

PART_NAME
 R1463 'Q_RES_0402LF-0,5%,1/16W,CHIP,CS00002JB38':;

SECTION_NUMBER 1
 '@T6G_MB_LIB.T6G(SCH_1):PAGE186_I263@PURE_QUANTA.Q_RES(CHIPS)':
 C_PATH='@t6g_mb_lib.t6g(sch_1):page186_i263@pure_quanta.q_res(chips)';

PART_NAME
 L10 'Q_INDUCTOR_SMLF-BLM18PG121SN1D/2000MA,EMPTY,CX8PG121009':;

SECTION_NUMBER 1
 '@T6G_MB_LIB.T6G(SCH_1):PAGE186_I279@PURE_QUANTA.Q_INDUCTOR(CHIPS)':
 C_PATH='@t6g_mb_lib.t6g(sch_1):page186_i279@pure_quanta.q_inductor(chips)';

PART_NAME
 L2 'Q_INDUCTOR_SMLF-BLM18PG121SN1D/2000MA,EMPTY,CX8PG121009':;

SECTION_NUMBER 1
 '@T6G_MB_LIB.T6G(SCH_1):PAGE186_I264@PURE_QUANTA.Q_INDUCTOR(CHIPS)':
 C_PATH='@t6g_mb_lib.t6g(sch_1):page186_i264@pure_quanta.q_inductor(chips)';

PART_NAME
 C1273 'Q_CAP_0805-47UF,4V,20%,X6S,CH647KMEA00':;

SECTION_NUMBER 1
 '@T6G_MB_LIB.T6G(SCH_1):PAGE186_I293@PURE_QUANTA.Q_CAP(CHIPS)':
 C_PATH='@t6g_mb_lib.t6g(sch_1):page186_i293@pure_quanta.q_cap(chips)';

PART_NAME
 C1272 'Q_CAP_0805-47UF,4V,20%,X6S,CH647KMEA00':;

SECTION_NUMBER 1
 '@T6G_MB_LIB.T6G(SCH_1):PAGE186_I252@PURE_QUANTA.Q_CAP(CHIPS)':
 C_PATH='@t6g_mb_lib.t6g(sch_1):page186_i252@pure_quanta.q_cap(chips)';

PART_NAME
 C1266 'Q_CAP_C0402-10UF,4V,20%,X6S,CH610KMEB09':;

SECTION_NUMBER 1
 '@T6G_MB_LIB.T6G(SCH_1):PAGE186_I295@PURE_QUANTA.Q_CAP(CHIPS)':
 C_PATH='@t6g_mb_lib.t6g(sch_1):page186_i295@pure_quanta.q_cap(chips)';

PART_NAME
 C1265 'Q_CAP_0402-1UF,6.3V,10%,EMPTY,CH5101K1B01':;

SECTION_NUMBER 1
 '@T6G_MB_LIB.T6G(SCH_1):PAGE186_I274@PURE_QUANTA.Q_CAP(CHIPS)':
 C_PATH='@t6g_mb_lib.t6g(sch_1):page186_i274@pure_quanta.q_cap(chips)';

PART_NAME
 C1264 'Q_CAP_0402-1UF,6.3V,10%,EMPTY,CH5101K1B01':;

SECTION_NUMBER 1
 '@T6G_MB_LIB.T6G(SCH_1):PAGE186_I255@PURE_QUANTA.Q_CAP(CHIPS)':
 C_PATH='@t6g_mb_lib.t6g(sch_1):page186_i255@pure_quanta.q_cap(chips)';

PART_NAME
 C1263 'Q_CAP_C0402-10UF,4V,20%,X6S,CH610KMEB09':;

SECTION_NUMBER 1
 '@T6G_MB_LIB.T6G(SCH_1):PAGE186_I297@PURE_QUANTA.Q_CAP(CHIPS)':
 C_PATH='@t6g_mb_lib.t6g(sch_1):page186_i297@pure_quanta.q_cap(chips)';

PART_NAME
 C1262 'Q_CAP_C0402-10UF,4V,20%,X6S,CH610KMEB09':;

SECTION_NUMBER 1
 '@T6G_MB_LIB.T6G(SCH_1):PAGE186_I260@PURE_QUANTA.Q_CAP(CHIPS)':
 C_PATH='@t6g_mb_lib.t6g(sch_1):page186_i260@pure_quanta.q_cap(chips)';

PART_NAME
 C1261 'Q_CAP_C0603-10UF,6.3V,20%,X6S,CH6101ME900':;

SECTION_NUMBER 1
 '@T6G_MB_LIB.T6G(SCH_1):PAGE186_I277@PURE_QUANTA.Q_CAP(CHIPS)':
 C_PATH='@t6g_mb_lib.t6g(sch_1):page186_i277@pure_quanta.q_cap(chips)';

PART_NAME
 C1260 'Q_CAP_C0603-10UF,6.3V,20%,X6S,CH6101ME900':;

SECTION_NUMBER 1
 '@T6G_MB_LIB.T6G(SCH_1):PAGE186_I257@PURE_QUANTA.Q_CAP(CHIPS)':
 C_PATH='@t6g_mb_lib.t6g(sch_1):page186_i257@pure_quanta.q_cap(chips)';

PART_NAME
 C1259 'Q_CAP_0805-47UF,4V,20%,X6S,CH647KMEA00':;

SECTION_NUMBER 1
 '@T6G_MB_LIB.T6G(SCH_1):PAGE186_I298@PURE_QUANTA.Q_CAP(CHIPS)':
 C_PATH='@t6g_mb_lib.t6g(sch_1):page186_i298@pure_quanta.q_cap(chips)';

PART_NAME
 C1258 'Q_CAP_0805-47UF,4V,20%,X6S,CH647KMEA00':;

SECTION_NUMBER 1
 '@T6G_MB_LIB.T6G(SCH_1):PAGE186_I261@PURE_QUANTA.Q_CAP(CHIPS)':
 C_PATH='@t6g_mb_lib.t6g(sch_1):page186_i261@pure_quanta.q_cap(chips)';

PART_NAME
 C1257 'Q_CAP_0402-1UF,6.3V,10%,EMPTY,CH5101K1B01':;

SECTION_NUMBER 1
 '@T6G_MB_LIB.T6G(SCH_1):PAGE186_I278@PURE_QUANTA.Q_CAP(CHIPS)':
 C_PATH='@t6g_mb_lib.t6g(sch_1):page186_i278@pure_quanta.q_cap(chips)';

PART_NAME
 C1256 'Q_CAP_0402-1UF,6.3V,10%,EMPTY,CH5101K1B01':;

SECTION_NUMBER 1
 '@T6G_MB_LIB.T6G(SCH_1):PAGE186_I265@PURE_QUANTA.Q_CAP(CHIPS)':
 C_PATH='@t6g_mb_lib.t6g(sch_1):page186_i265@pure_quanta.q_cap(chips)';

PART_NAME
 C1255 'Q_CAP_C0603-10UF,6.3V,20%,X6S,CH6101ME900':;

SECTION_NUMBER 1
 '@T6G_MB_LIB.T6G(SCH_1):PAGE186_I300@PURE_QUANTA.Q_CAP(CHIPS)':
 C_PATH='@t6g_mb_lib.t6g(sch_1):page186_i300@pure_quanta.q_cap(chips)';

PART_NAME
 C1254 'Q_CAP_C0603-10UF,6.3V,20%,X6S,CH6101ME900':;

SECTION_NUMBER 1
 '@T6G_MB_LIB.T6G(SCH_1):PAGE186_I269@PURE_QUANTA.Q_CAP(CHIPS)':
 C_PATH='@t6g_mb_lib.t6g(sch_1):page186_i269@pure_quanta.q_cap(chips)';

PART_NAME
 C1253 'Q_CAP_0402-1UF,6.3V,10%,EMPTY,CH5101K1B01':;

SECTION_NUMBER 1
 '@T6G_MB_LIB.T6G(SCH_1):PAGE186_I281@PURE_QUANTA.Q_CAP(CHIPS)':
 C_PATH='@t6g_mb_lib.t6g(sch_1):page186_i281@pure_quanta.q_cap(chips)';

PART_NAME
 C1252 'Q_CAP_C0603-10UF,6.3V,20%,X6S,CH6101ME900':;

SECTION_NUMBER 1
 '@T6G_MB_LIB.T6G(SCH_1):PAGE186_I301@PURE_QUANTA.Q_CAP(CHIPS)':
 C_PATH='@t6g_mb_lib.t6g(sch_1):page186_i301@pure_quanta.q_cap(chips)';

PART_NAME
 C1251 'Q_CAP_C0603-10UF,6.3V,20%,X6S,CH6101ME900':;

SECTION_NUMBER 1
 '@T6G_MB_LIB.T6G(SCH_1):PAGE186_I271@PURE_QUANTA.Q_CAP(CHIPS)':
 C_PATH='@t6g_mb_lib.t6g(sch_1):page186_i271@pure_quanta.q_cap(chips)';

PART_NAME
 C1250 'Q_CAP_0402-1UF,6.3V,10%,EMPTY,CH5101K1B01':;

SECTION_NUMBER 1
 '@T6G_MB_LIB.T6G(SCH_1):PAGE186_I267@PURE_QUANTA.Q_CAP(CHIPS)':
 C_PATH='@t6g_mb_lib.t6g(sch_1):page186_i267@pure_quanta.q_cap(chips)';

PART_NAME
 C1249 'Q_CAP_0805-47UF,4V,20%,X6S,CH647KMEA00':;

SECTION_NUMBER 1
 '@T6G_MB_LIB.T6G(SCH_1):PAGE186_I289@PURE_QUANTA.Q_CAP(CHIPS)':
 C_PATH='@t6g_mb_lib.t6g(sch_1):page186_i289@pure_quanta.q_cap(chips)';

PART_NAME
 C1248 'Q_CAP_0805-47UF,4V,20%,X6S,CH647KMEA00':;

SECTION_NUMBER 1
 '@T6G_MB_LIB.T6G(SCH_1):PAGE186_I284@PURE_QUANTA.Q_CAP(CHIPS)':
 C_PATH='@t6g_mb_lib.t6g(sch_1):page186_i284@pure_quanta.q_cap(chips)';

PART_NAME
 C1247 'Q_CAP_0805-47UF,4V,20%,X6S,CH647KMEA00':;

SECTION_NUMBER 1
 '@T6G_MB_LIB.T6G(SCH_1):PAGE186_I291@PURE_QUANTA.Q_CAP(CHIPS)':
 C_PATH='@t6g_mb_lib.t6g(sch_1):page186_i291@pure_quanta.q_cap(chips)';

PART_NAME
 C1246 'Q_CAP_0805-47UF,4V,20%,X6S,CH647KMEA00':;

SECTION_NUMBER 1
 '@T6G_MB_LIB.T6G(SCH_1):PAGE186_I286@PURE_QUANTA.Q_CAP(CHIPS)':
 C_PATH='@t6g_mb_lib.t6g(sch_1):page186_i286@pure_quanta.q_cap(chips)';

PART_NAME
 C1245 'Q_CAP_0805-47UF,4V,20%,X6S,CH647KMEA00':;

SECTION_NUMBER 1
 '@T6G_MB_LIB.T6G(SCH_1):PAGE186_I302@PURE_QUANTA.Q_CAP(CHIPS)':
 C_PATH='@t6g_mb_lib.t6g(sch_1):page186_i302@pure_quanta.q_cap(chips)';

PART_NAME
 C1244 'Q_CAP_0805-47UF,4V,20%,X6S,CH647KMEA00':;

SECTION_NUMBER 1
 '@T6G_MB_LIB.T6G(SCH_1):PAGE186_I288@PURE_QUANTA.Q_CAP(CHIPS)':
 C_PATH='@t6g_mb_lib.t6g(sch_1):page186_i288@pure_quanta.q_cap(chips)';

PART_NAME
 C1243 'Q_CAP_0805-47UF,4V,20%,X6S,CH647KMEA00':;

SECTION_NUMBER 1
 '@T6G_MB_LIB.T6G(SCH_1):PAGE186_I308@PURE_QUANTA.Q_CAP(CHIPS)':
 C_PATH='@t6g_mb_lib.t6g(sch_1):page186_i308@pure_quanta.q_cap(chips)';

PART_NAME
 C1242 'Q_CAP_C0402-2.2UF,10V,10%,X6S,CH5222KEB01':;

SECTION_NUMBER 1
 '@T6G_MB_LIB.T6G(SCH_1):PAGE186_I306@PURE_QUANTA.Q_CAP(CHIPS)':
 C_PATH='@t6g_mb_lib.t6g(sch_1):page186_i306@pure_quanta.q_cap(chips)';

PART_NAME
 C1231 'Q_CAP_C0402-10UF,4V,20%,X6S,CH610KMEB09':;

SECTION_NUMBER 1
 '@T6G_MB_LIB.T6G(SCH_1):PAGE186_I304@PURE_QUANTA.Q_CAP(CHIPS)':
 C_PATH='@t6g_mb_lib.t6g(sch_1):page186_i304@pure_quanta.q_cap(chips)';

PART_NAME
 C1228 'Q_CAP_C0402-10UF,4V,20%,X6S,CH610KMEB09':;

SECTION_NUMBER 1
 '@T6G_MB_LIB.T6G(SCH_1):PAGE186_I310@PURE_QUANTA.Q_CAP(CHIPS)':
 C_PATH='@t6g_mb_lib.t6g(sch_1):page186_i310@pure_quanta.q_cap(chips)';

PART_NAME
 C1214 'Q_CAP_C0402-2.2UF,10V,10%,X6S,CH5222KEB01':;

SECTION_NUMBER 1
 '@T6G_MB_LIB.T6G(SCH_1):PAGE186_I327@PURE_QUANTA.Q_CAP(CHIPS)':
 C_PATH='@t6g_mb_lib.t6g(sch_1):page186_i327@pure_quanta.q_cap(chips)';

PART_NAME
 C1210 'Q_CAP_C0402-10UF,4V,20%,X6S,CH610KMEB09':;

SECTION_NUMBER 1
 '@T6G_MB_LIB.T6G(SCH_1):PAGE186_I324@PURE_QUANTA.Q_CAP(CHIPS)':
 C_PATH='@t6g_mb_lib.t6g(sch_1):page186_i324@pure_quanta.q_cap(chips)';

PART_NAME
 C1207 'Q_CAP_C0402-10UF,4V,20%,X6S,CH610KMEB09':;

SECTION_NUMBER 1
 '@T6G_MB_LIB.T6G(SCH_1):PAGE186_I315@PURE_QUANTA.Q_CAP(CHIPS)':
 C_PATH='@t6g_mb_lib.t6g(sch_1):page186_i315@pure_quanta.q_cap(chips)';

PART_NAME
 C1206 'Q_CAP_C0402-10UF,4V,20%,X6S,CH610KMEB09':;

SECTION_NUMBER 1
 '@T6G_MB_LIB.T6G(SCH_1):PAGE186_I343@PURE_QUANTA.Q_CAP(CHIPS)':
 C_PATH='@t6g_mb_lib.t6g(sch_1):page186_i343@pure_quanta.q_cap(chips)';

PART_NAME
 C1205 'Q_CAP_C0402-10UF,4V,20%,X6S,CH610KMEB09':;

SECTION_NUMBER 1
 '@T6G_MB_LIB.T6G(SCH_1):PAGE186_I313@PURE_QUANTA.Q_CAP(CHIPS)':
 C_PATH='@t6g_mb_lib.t6g(sch_1):page186_i313@pure_quanta.q_cap(chips)';

PART_NAME
 C1204 'Q_CAP_C0402-2.2UF,10V,10%,X6S,CH5222KEB01':;

SECTION_NUMBER 1
 '@T6G_MB_LIB.T6G(SCH_1):PAGE186_I328@PURE_QUANTA.Q_CAP(CHIPS)':
 C_PATH='@t6g_mb_lib.t6g(sch_1):page186_i328@pure_quanta.q_cap(chips)';

PART_NAME
 C1203 'Q_CAP_C0402-10UF,4V,20%,X6S,CH610KMEB09':;

SECTION_NUMBER 1
 '@T6G_MB_LIB.T6G(SCH_1):PAGE186_I326@PURE_QUANTA.Q_CAP(CHIPS)':
 C_PATH='@t6g_mb_lib.t6g(sch_1):page186_i326@pure_quanta.q_cap(chips)';

PART_NAME
 C1202 'Q_CAP_C0603-22UF,4V,20%,X6S,CH622KME901':;

SECTION_NUMBER 1
 '@T6G_MB_LIB.T6G(SCH_1):PAGE186_I317@PURE_QUANTA.Q_CAP(CHIPS)':
 C_PATH='@t6g_mb_lib.t6g(sch_1):page186_i317@pure_quanta.q_cap(chips)';

PART_NAME
 C1201 'Q_CAP_C0603-22UF,4V,20%,X6S,CH622KME901':;

SECTION_NUMBER 1
 '@T6G_MB_LIB.T6G(SCH_1):PAGE186_I345@PURE_QUANTA.Q_CAP(CHIPS)':
 C_PATH='@t6g_mb_lib.t6g(sch_1):page186_i345@pure_quanta.q_cap(chips)';

PART_NAME
 C1200 'Q_CAP_C0402-2.2UF,10V,10%,X6S,CH5222KEB01':;

SECTION_NUMBER 1
 '@T6G_MB_LIB.T6G(SCH_1):PAGE186_I332@PURE_QUANTA.Q_CAP(CHIPS)':
 C_PATH='@t6g_mb_lib.t6g(sch_1):page186_i332@pure_quanta.q_cap(chips)';

PART_NAME
 C1198 'Q_CAP_C0603-22UF,4V,20%,X6S,CH622KME901':;

SECTION_NUMBER 1
 '@T6G_MB_LIB.T6G(SCH_1):PAGE186_I329@PURE_QUANTA.Q_CAP(CHIPS)':
 C_PATH='@t6g_mb_lib.t6g(sch_1):page186_i329@pure_quanta.q_cap(chips)';

PART_NAME
 C1197 'Q_CAP_C0603-22UF,4V,20%,X6S,CH622KME901':;

SECTION_NUMBER 1
 '@T6G_MB_LIB.T6G(SCH_1):PAGE186_I322@PURE_QUANTA.Q_CAP(CHIPS)':
 C_PATH='@t6g_mb_lib.t6g(sch_1):page186_i322@pure_quanta.q_cap(chips)';

PART_NAME
 C1192 'Q_CAP_C0603-22UF,4V,20%,X6S,CH622KME901':;

SECTION_NUMBER 1
 '@T6G_MB_LIB.T6G(SCH_1):PAGE186_I319@PURE_QUANTA.Q_CAP(CHIPS)':
 C_PATH='@t6g_mb_lib.t6g(sch_1):page186_i319@pure_quanta.q_cap(chips)';

PART_NAME
 C1191 'Q_CAP_C0603-22UF,4V,20%,X6S,CH622KME901':;

SECTION_NUMBER 1
 '@T6G_MB_LIB.T6G(SCH_1):PAGE186_I346@PURE_QUANTA.Q_CAP(CHIPS)':
 C_PATH='@t6g_mb_lib.t6g(sch_1):page186_i346@pure_quanta.q_cap(chips)';

PART_NAME
 C1189 'Q_CAP_C0402-2.2UF,10V,10%,X6S,CH5222KEB01':;

SECTION_NUMBER 1
 '@T6G_MB_LIB.T6G(SCH_1):PAGE186_I333@PURE_QUANTA.Q_CAP(CHIPS)':
 C_PATH='@t6g_mb_lib.t6g(sch_1):page186_i333@pure_quanta.q_cap(chips)';

PART_NAME
 C1187 'Q_CAP_C0603-22UF,4V,20%,X6S,CH622KME901':;

SECTION_NUMBER 1
 '@T6G_MB_LIB.T6G(SCH_1):PAGE186_I330@PURE_QUANTA.Q_CAP(CHIPS)':
 C_PATH='@t6g_mb_lib.t6g(sch_1):page186_i330@pure_quanta.q_cap(chips)';

PART_NAME
 C1186 'Q_CAP_C0603-22UF,4V,20%,X6S,CH622KME901':;

SECTION_NUMBER 1
 '@T6G_MB_LIB.T6G(SCH_1):PAGE186_I323@PURE_QUANTA.Q_CAP(CHIPS)':
 C_PATH='@t6g_mb_lib.t6g(sch_1):page186_i323@pure_quanta.q_cap(chips)';

PART_NAME
 C1185 'Q_CAP_C0603-22UF,4V,20%,X6S,CH622KME901':;

SECTION_NUMBER 1
 '@T6G_MB_LIB.T6G(SCH_1):PAGE186_I321@PURE_QUANTA.Q_CAP(CHIPS)':
 C_PATH='@t6g_mb_lib.t6g(sch_1):page186_i321@pure_quanta.q_cap(chips)';

PART_NAME
 C1184 'Q_CAP_C0603-22UF,4V,20%,X6S,CH622KME901':;

SECTION_NUMBER 1
 '@T6G_MB_LIB.T6G(SCH_1):PAGE186_I349@PURE_QUANTA.Q_CAP(CHIPS)':
 C_PATH='@t6g_mb_lib.t6g(sch_1):page186_i349@pure_quanta.q_cap(chips)';

PART_NAME
 C1183 'Q_CAP_C0402-2.2UF,10V,10%,X6S,CH5222KEB01':;

SECTION_NUMBER 1
 '@T6G_MB_LIB.T6G(SCH_1):PAGE186_I341@PURE_QUANTA.Q_CAP(CHIPS)':
 C_PATH='@t6g_mb_lib.t6g(sch_1):page186_i341@pure_quanta.q_cap(chips)';

PART_NAME
 C1182 'Q_CAP_C0603-22UF,4V,20%,X6S,CH622KME901':;

SECTION_NUMBER 1
 '@T6G_MB_LIB.T6G(SCH_1):PAGE186_I339@PURE_QUANTA.Q_CAP(CHIPS)':
 C_PATH='@t6g_mb_lib.t6g(sch_1):page186_i339@pure_quanta.q_cap(chips)';

PART_NAME
 C1181 'Q_CAP_C0603-22UF,4V,20%,X6S,CH622KME901':;

SECTION_NUMBER 1
 '@T6G_MB_LIB.T6G(SCH_1):PAGE186_I337@PURE_QUANTA.Q_CAP(CHIPS)':
 C_PATH='@t6g_mb_lib.t6g(sch_1):page186_i337@pure_quanta.q_cap(chips)';

PART_NAME
 C1178 'Q_CAP_C0603-22UF,4V,20%,X6S,CH622KME901':;

SECTION_NUMBER 1
 '@T6G_MB_LIB.T6G(SCH_1):PAGE186_I335@PURE_QUANTA.Q_CAP(CHIPS)':
 C_PATH='@t6g_mb_lib.t6g(sch_1):page186_i335@pure_quanta.q_cap(chips)';

PART_NAME
 S2 'SW8S_DHNF04FTVTR-SW8S_DHNF04FTVTR,SMLF,MECH,DHP00004F00':;

SECTION_NUMBER 1
 '@T6G_MB_LIB.T6G(SCH_1):PAGE191_I1@PURE_QUANTA.SW8S_DHNF04FTVTR(CHIPS)':
 C_PATH='@t6g_mb_lib.t6g(sch_1):page191_i1@pure_quanta.sw8s_dhnf04ftvtr(chips)';

PART_NAME
 S1 'SW8S_DHNF04FTVTR-SW8S_DHNF04FTVTR,SMLF,MECH,DHP00004F00':;

SECTION_NUMBER 1
 '@T6G_MB_LIB.T6G(SCH_1):PAGE191_I12@PURE_QUANTA.SW8S_DHNF04FTVTR(CHIPS)':
 C_PATH='@t6g_mb_lib.t6g(sch_1):page191_i12@pure_quanta.sw8s_dhnf04ftvtr(chips)';

PART_NAME
 R1695 'Q_RES_0402LF-10K,1%,1/16W,CHIP,TMP_QCS31002FB26':;

SECTION_NUMBER 1
 '@T6G_MB_LIB.T6G(SCH_1):PAGE191_I18@PURE_QUANTA.Q_RES(CHIPS)':
 C_PATH='@t6g_mb_lib.t6g(sch_1):page191_i18@pure_quanta.q_res(chips)';

PART_NAME
 R1694 'Q_RES_0402LF-10K,1%,1/16W,CHIP,TMP_QCS31002FB26':;

SECTION_NUMBER 1
 '@T6G_MB_LIB.T6G(SCH_1):PAGE191_I19@PURE_QUANTA.Q_RES(CHIPS)':
 C_PATH='@t6g_mb_lib.t6g(sch_1):page191_i19@pure_quanta.q_res(chips)';

PART_NAME
 R1693 'Q_RES_0402LF-10K,1%,1/16W,CHIP,TMP_QCS31002FB26':;

SECTION_NUMBER 1
 '@T6G_MB_LIB.T6G(SCH_1):PAGE191_I6@PURE_QUANTA.Q_RES(CHIPS)':
 C_PATH='@t6g_mb_lib.t6g(sch_1):page191_i6@pure_quanta.q_res(chips)';

PART_NAME
 R1692 'Q_RES_0402LF-20K,5%,1/16W,CHIP,TMP_QCS32002JB12':;

SECTION_NUMBER 1
 '@T6G_MB_LIB.T6G(SCH_1):PAGE191_I22@PURE_QUANTA.Q_RES(CHIPS)':
 C_PATH='@t6g_mb_lib.t6g(sch_1):page191_i22@pure_quanta.q_res(chips)';

PART_NAME
 R1691 'Q_RES_0402LF-10K,1%,1/16W,CHIP,TMP_QCS31002FB26':;

SECTION_NUMBER 1
 '@T6G_MB_LIB.T6G(SCH_1):PAGE191_I9@PURE_QUANTA.Q_RES(CHIPS)':
 C_PATH='@t6g_mb_lib.t6g(sch_1):page191_i9@pure_quanta.q_res(chips)';

PART_NAME
 R1690 'Q_RES_0402LF-10K,1%,1/16W,CHIP,TMP_QCS31002FB26':;

SECTION_NUMBER 1
 '@T6G_MB_LIB.T6G(SCH_1):PAGE191_I10@PURE_QUANTA.Q_RES(CHIPS)':
 C_PATH='@t6g_mb_lib.t6g(sch_1):page191_i10@pure_quanta.q_res(chips)';

PART_NAME
 R1689 'Q_RES_0402LF-10K,1%,1/16W,CHIP,TMP_QCS31002FB26':;

SECTION_NUMBER 1
 '@T6G_MB_LIB.T6G(SCH_1):PAGE191_I23@PURE_QUANTA.Q_RES(CHIPS)':
 C_PATH='@t6g_mb_lib.t6g(sch_1):page191_i23@pure_quanta.q_res(chips)';

PART_NAME
 R1688 'Q_RES_0402LF-1K,1%,1/16W,CHIP,TMP_QCS21002FB24':;

SECTION_NUMBER 1
 '@T6G_MB_LIB.T6G(SCH_1):PAGE191_I31@PURE_QUANTA.Q_RES(CHIPS)':
 C_PATH='@t6g_mb_lib.t6g(sch_1):page191_i31@pure_quanta.q_res(chips)';

PART_NAME
 R1687 'Q_RES_0402LF-1K,1%,1/16W,CHIP,TMP_QCS21002FB24':;

SECTION_NUMBER 1
 '@T6G_MB_LIB.T6G(SCH_1):PAGE191_I32@PURE_QUANTA.Q_RES(CHIPS)':
 C_PATH='@t6g_mb_lib.t6g(sch_1):page191_i32@pure_quanta.q_res(chips)';

PART_NAME
 R1686 'Q_RES_0402LF-1K,1%,1/16W,CHIP,TMP_QCS21002FB24':;

SECTION_NUMBER 1
 '@T6G_MB_LIB.T6G(SCH_1):PAGE191_I28@PURE_QUANTA.Q_RES(CHIPS)':
 C_PATH='@t6g_mb_lib.t6g(sch_1):page191_i28@pure_quanta.q_res(chips)';

PART_NAME
 R1685 'Q_RES_0402LF-1K,1%,1/16W,CHIP,TMP_QCS21002FB24':;

SECTION_NUMBER 1
 '@T6G_MB_LIB.T6G(SCH_1):PAGE191_I27@PURE_QUANTA.Q_RES(CHIPS)':
 C_PATH='@t6g_mb_lib.t6g(sch_1):page191_i27@pure_quanta.q_res(chips)';

PART_NAME
 R1684 'Q_RES_0402LF-1K,1%,1/16W,CHIP,TMP_QCS21002FB24':;

SECTION_NUMBER 1
 '@T6G_MB_LIB.T6G(SCH_1):PAGE191_I26@PURE_QUANTA.Q_RES(CHIPS)':
 C_PATH='@t6g_mb_lib.t6g(sch_1):page191_i26@pure_quanta.q_res(chips)';

PART_NAME
 R1335 'Q_RES_0402LF-1K,1%,1/16W,CHIP,TMP_QCS21002FB24':;

SECTION_NUMBER 1
 '@T6G_MB_LIB.T6G(SCH_1):PAGE191_I34@PURE_QUANTA.Q_RES(CHIPS)':
 C_PATH='@t6g_mb_lib.t6g(sch_1):page191_i34@pure_quanta.q_res(chips)';

PART_NAME
 R1334 'Q_RES_0402LF-1K,1%,1/16W,CHIP,TMP_QCS21002FB24':;

SECTION_NUMBER 1
 '@T6G_MB_LIB.T6G(SCH_1):PAGE191_I33@PURE_QUANTA.Q_RES(CHIPS)':
 C_PATH='@t6g_mb_lib.t6g(sch_1):page191_i33@pure_quanta.q_res(chips)';

PART_NAME
 C1177 'Q_CAP_C0402-1UF,25V,10%,X6S,CH5104KEB02':;

SECTION_NUMBER 1
 '@T6G_MB_LIB.T6G(SCH_1):PAGE191_I2@PURE_QUANTA.Q_CAP(CHIPS)':
 C_PATH='@t6g_mb_lib.t6g(sch_1):page191_i2@pure_quanta.q_cap(chips)';

PART_NAME
 U159 'PCA9848PW-PCA9848PW,SMLF,IC,AL009848K00':;

SECTION_NUMBER 1
 '@T6G_MB_LIB.T6G(SCH_1):PAGE277_I397@PURE_QUANTA.PCA9848PW(CHIPS)':
 C_PATH='@t6g_mb_lib.t6g(sch_1):page277_i397@pure_quanta.pca9848pw(chips)';

PART_NAME
 R3709 'Q_RES_0402LF-4.7K,5%,1/16W,CHIP,TMP_QCS24702JB38':;

SECTION_NUMBER 1
 '@T6G_MB_LIB.T6G(SCH_1):PAGE277_I388@PURE_QUANTA.Q_RES(CHIPS)':
 C_PATH='@t6g_mb_lib.t6g(sch_1):page277_i388@pure_quanta.q_res(chips)';

PART_NAME
 R3708 'Q_RES_0402LF-4.7K,5%,1/16W,CHIP,TMP_QCS24702JB38':;

SECTION_NUMBER 1
 '@T6G_MB_LIB.T6G(SCH_1):PAGE277_I387@PURE_QUANTA.Q_RES(CHIPS)':
 C_PATH='@t6g_mb_lib.t6g(sch_1):page277_i387@pure_quanta.q_res(chips)';

PART_NAME
 R3648 'Q_RES_0402LF-2.2K ,5%,1/16W,EMPTY,CS22202JB18':;

SECTION_NUMBER 1
 '@T6G_MB_LIB.T6G(SCH_1):PAGE277_I380@PURE_QUANTA.Q_RES(CHIPS)':
 C_PATH='@t6g_mb_lib.t6g(sch_1):page277_i380@pure_quanta.q_res(chips)';

PART_NAME
 R1619 'Q_RES_0402LF-33,5%,1/16W,CHIP,CS03302JB29':;

SECTION_NUMBER 1
 '@T6G_MB_LIB.T6G(SCH_1):PAGE277_I435@PURE_QUANTA.Q_RES(CHIPS)':
 C_PATH='@t6g_mb_lib.t6g(sch_1):page277_i435@pure_quanta.q_res(chips)';

PART_NAME
 R1618 'Q_RES_0402LF-0,5%,1/16W,CHIP,CS00002JB38':;

SECTION_NUMBER 1
 '@T6G_MB_LIB.T6G(SCH_1):PAGE277_I436@PURE_QUANTA.Q_RES(CHIPS)':
 C_PATH='@t6g_mb_lib.t6g(sch_1):page277_i436@pure_quanta.q_res(chips)';

PART_NAME
 R1336 'Q_RES_0402LF-2.2K ,5%,1/16W,EMPTY,CS22202JB18':;

SECTION_NUMBER 1
 '@T6G_MB_LIB.T6G(SCH_1):PAGE277_I381@PURE_QUANTA.Q_RES(CHIPS)':
 C_PATH='@t6g_mb_lib.t6g(sch_1):page277_i381@pure_quanta.q_res(chips)';

PART_NAME
 R948 'Q_RES_0402LF-10K,1%,1/16W,CHIP,TMP_QCS31002FB26':;

SECTION_NUMBER 1
 '@T6G_MB_LIB.T6G(SCH_1):PAGE277_I325@PURE_QUANTA.Q_RES(CHIPS)':
 C_PATH='@t6g_mb_lib.t6g(sch_1):page277_i325@pure_quanta.q_res(chips)';

PART_NAME
 R947 'Q_RES_0402LF-10K,1%,1/16W,CHIP,TMP_QCS31002FB26':;

SECTION_NUMBER 1
 '@T6G_MB_LIB.T6G(SCH_1):PAGE277_I326@PURE_QUANTA.Q_RES(CHIPS)':
 C_PATH='@t6g_mb_lib.t6g(sch_1):page277_i326@pure_quanta.q_res(chips)';

PART_NAME
 R946 'Q_RES_0402LF-10K,1%,1/16W,CHIP,TMP_QCS31002FB26':;

SECTION_NUMBER 1
 '@T6G_MB_LIB.T6G(SCH_1):PAGE277_I328@PURE_QUANTA.Q_RES(CHIPS)':
 C_PATH='@t6g_mb_lib.t6g(sch_1):page277_i328@pure_quanta.q_res(chips)';

PART_NAME
 R945 'Q_RES_0402LF-10K,1%,1/16W,CHIP,TMP_QCS31002FB26':;

SECTION_NUMBER 1
 '@T6G_MB_LIB.T6G(SCH_1):PAGE277_I327@PURE_QUANTA.Q_RES(CHIPS)':
 C_PATH='@t6g_mb_lib.t6g(sch_1):page277_i327@pure_quanta.q_res(chips)';

PART_NAME
 R944 'Q_RES_0402LF-10K,1%,1/16W,CHIP,TMP_QCS31002FB26':;

SECTION_NUMBER 1
 '@T6G_MB_LIB.T6G(SCH_1):PAGE277_I329@PURE_QUANTA.Q_RES(CHIPS)':
 C_PATH='@t6g_mb_lib.t6g(sch_1):page277_i329@pure_quanta.q_res(chips)';

PART_NAME
 R943 'Q_RES_0402LF-10K,1%,1/16W,CHIP,TMP_QCS31002FB26':;

SECTION_NUMBER 1
 '@T6G_MB_LIB.T6G(SCH_1):PAGE277_I330@PURE_QUANTA.Q_RES(CHIPS)':
 C_PATH='@t6g_mb_lib.t6g(sch_1):page277_i330@pure_quanta.q_res(chips)';

PART_NAME
 R942 'Q_RES_0402LF-10K,1%,1/16W,CHIP,TMP_QCS31002FB26':;

SECTION_NUMBER 1
 '@T6G_MB_LIB.T6G(SCH_1):PAGE277_I331@PURE_QUANTA.Q_RES(CHIPS)':
 C_PATH='@t6g_mb_lib.t6g(sch_1):page277_i331@pure_quanta.q_res(chips)';

PART_NAME
 R941 'Q_RES_0402LF-10K,1%,1/16W,CHIP,TMP_QCS31002FB26':;

SECTION_NUMBER 1
 '@T6G_MB_LIB.T6G(SCH_1):PAGE277_I332@PURE_QUANTA.Q_RES(CHIPS)':
 C_PATH='@t6g_mb_lib.t6g(sch_1):page277_i332@pure_quanta.q_res(chips)';

PART_NAME
 R940 'Q_RES_0402LF-10K,1%,1/16W,CHIP,TMP_QCS31002FB26':;

SECTION_NUMBER 1
 '@T6G_MB_LIB.T6G(SCH_1):PAGE277_I333@PURE_QUANTA.Q_RES(CHIPS)':
 C_PATH='@t6g_mb_lib.t6g(sch_1):page277_i333@pure_quanta.q_res(chips)';

PART_NAME
 R926 'Q_RES_0402LF-10K,1%,1/16W,CHIP,TMP_QCS31002FB26':;

SECTION_NUMBER 1
 '@T6G_MB_LIB.T6G(SCH_1):PAGE277_I334@PURE_QUANTA.Q_RES(CHIPS)':
 C_PATH='@t6g_mb_lib.t6g(sch_1):page277_i334@pure_quanta.q_res(chips)';

PART_NAME
 R924 'Q_RES_0402LF-10K,1%,1/16W,CHIP,TMP_QCS31002FB26':;

SECTION_NUMBER 1
 '@T6G_MB_LIB.T6G(SCH_1):PAGE277_I335@PURE_QUANTA.Q_RES(CHIPS)':
 C_PATH='@t6g_mb_lib.t6g(sch_1):page277_i335@pure_quanta.q_res(chips)';

PART_NAME
 R918 'Q_RES_0402LF-10K,1%,1/16W,CHIP,TMP_QCS31002FB26':;

SECTION_NUMBER 1
 '@T6G_MB_LIB.T6G(SCH_1):PAGE277_I336@PURE_QUANTA.Q_RES(CHIPS)':
 C_PATH='@t6g_mb_lib.t6g(sch_1):page277_i336@pure_quanta.q_res(chips)';

PART_NAME
 R916 'Q_RES_0402LF-10K,1%,1/16W,CHIP,TMP_QCS31002FB26':;

SECTION_NUMBER 1
 '@T6G_MB_LIB.T6G(SCH_1):PAGE277_I459@PURE_QUANTA.Q_RES(CHIPS)':
 C_PATH='@t6g_mb_lib.t6g(sch_1):page277_i459@pure_quanta.q_res(chips)';

PART_NAME
 R915 'Q_RES_0402LF-10K,1%,1/16W,CHIP,TMP_QCS31002FB26':;

SECTION_NUMBER 1
 '@T6G_MB_LIB.T6G(SCH_1):PAGE277_I460@PURE_QUANTA.Q_RES(CHIPS)':
 C_PATH='@t6g_mb_lib.t6g(sch_1):page277_i460@pure_quanta.q_res(chips)';

PART_NAME
 R914 'Q_RES_0402LF-10K,1%,1/16W,CHIP,TMP_QCS31002FB26':;

SECTION_NUMBER 1
 '@T6G_MB_LIB.T6G(SCH_1):PAGE277_I458@PURE_QUANTA.Q_RES(CHIPS)':
 C_PATH='@t6g_mb_lib.t6g(sch_1):page277_i458@pure_quanta.q_res(chips)';

PART_NAME
 R913 'Q_RES_0402LF-10K,1%,1/16W,CHIP,TMP_QCS31002FB26':;

SECTION_NUMBER 1
 '@T6G_MB_LIB.T6G(SCH_1):PAGE277_I457@PURE_QUANTA.Q_RES(CHIPS)':
 C_PATH='@t6g_mb_lib.t6g(sch_1):page277_i457@pure_quanta.q_res(chips)';

PART_NAME
 R908 'Q_RES_0402LF-0,5%,1/16W,CHIP,CS00002JB38':;

SECTION_NUMBER 1
 '@T6G_MB_LIB.T6G(SCH_1):PAGE277_I429@PURE_QUANTA.Q_RES(CHIPS)':
 C_PATH='@t6g_mb_lib.t6g(sch_1):page277_i429@pure_quanta.q_res(chips)';

PART_NAME
 R907 'Q_RES_0402LF-0,5%,1/16W,CHIP,CS00002JB38':;

SECTION_NUMBER 1
 '@T6G_MB_LIB.T6G(SCH_1):PAGE277_I428@PURE_QUANTA.Q_RES(CHIPS)':
 C_PATH='@t6g_mb_lib.t6g(sch_1):page277_i428@pure_quanta.q_res(chips)';

PART_NAME
 R906 'Q_RES_0402LF-0,5%,1/16W,CHIP,CS00002JB38':;

SECTION_NUMBER 1
 '@T6G_MB_LIB.T6G(SCH_1):PAGE277_I427@PURE_QUANTA.Q_RES(CHIPS)':
 C_PATH='@t6g_mb_lib.t6g(sch_1):page277_i427@pure_quanta.q_res(chips)';

PART_NAME
 R905 'Q_RES_0402LF-0,5%,1/16W,CHIP,CS00002JB38':;

SECTION_NUMBER 1
 '@T6G_MB_LIB.T6G(SCH_1):PAGE277_I422@PURE_QUANTA.Q_RES(CHIPS)':
 C_PATH='@t6g_mb_lib.t6g(sch_1):page277_i422@pure_quanta.q_res(chips)';

PART_NAME
 R904 'Q_RES_0402LF-0,5%,1/16W,CHIP,CS00002JB38':;

SECTION_NUMBER 1
 '@T6G_MB_LIB.T6G(SCH_1):PAGE277_I421@PURE_QUANTA.Q_RES(CHIPS)':
 C_PATH='@t6g_mb_lib.t6g(sch_1):page277_i421@pure_quanta.q_res(chips)';

PART_NAME
 R903 'Q_RES_0402LF-0,5%,1/16W,CHIP,CS00002JB38':;

SECTION_NUMBER 1
 '@T6G_MB_LIB.T6G(SCH_1):PAGE277_I420@PURE_QUANTA.Q_RES(CHIPS)':
 C_PATH='@t6g_mb_lib.t6g(sch_1):page277_i420@pure_quanta.q_res(chips)';

PART_NAME
 R902 'Q_RES_0402LF-0,5%,1/16W,CHIP,CS00002JB38':;

SECTION_NUMBER 1
 '@T6G_MB_LIB.T6G(SCH_1):PAGE277_I418@PURE_QUANTA.Q_RES(CHIPS)':
 C_PATH='@t6g_mb_lib.t6g(sch_1):page277_i418@pure_quanta.q_res(chips)';

PART_NAME
 R901 'Q_RES_0402LF-0,5%,1/16W,CHIP,CS00002JB38':;

SECTION_NUMBER 1
 '@T6G_MB_LIB.T6G(SCH_1):PAGE277_I419@PURE_QUANTA.Q_RES(CHIPS)':
 C_PATH='@t6g_mb_lib.t6g(sch_1):page277_i419@pure_quanta.q_res(chips)';

PART_NAME
 R900 'Q_RES_0402LF-0,5%,1/16W,CHIP,CS00002JB38':;

SECTION_NUMBER 1
 '@T6G_MB_LIB.T6G(SCH_1):PAGE277_I416@PURE_QUANTA.Q_RES(CHIPS)':
 C_PATH='@t6g_mb_lib.t6g(sch_1):page277_i416@pure_quanta.q_res(chips)';

PART_NAME
 R899 'Q_RES_0402LF-0,5%,1/16W,CHIP,CS00002JB38':;

SECTION_NUMBER 1
 '@T6G_MB_LIB.T6G(SCH_1):PAGE277_I417@PURE_QUANTA.Q_RES(CHIPS)':
 C_PATH='@t6g_mb_lib.t6g(sch_1):page277_i417@pure_quanta.q_res(chips)';

PART_NAME
 R897 'Q_RES_0402LF-0,5%,1/16W,CHIP,CS00002JB38':;

SECTION_NUMBER 1
 '@T6G_MB_LIB.T6G(SCH_1):PAGE277_I415@PURE_QUANTA.Q_RES(CHIPS)':
 C_PATH='@t6g_mb_lib.t6g(sch_1):page277_i415@pure_quanta.q_res(chips)';

PART_NAME
 R896 'Q_RES_0402LF-0,5%,1/16W,CHIP,CS00002JB38':;

SECTION_NUMBER 1
 '@T6G_MB_LIB.T6G(SCH_1):PAGE277_I413@PURE_QUANTA.Q_RES(CHIPS)':
 C_PATH='@t6g_mb_lib.t6g(sch_1):page277_i413@pure_quanta.q_res(chips)';

PART_NAME
 R895 'Q_RES_0402LF-0,5%,1/16W,CHIP,CS00002JB38':;

SECTION_NUMBER 1
 '@T6G_MB_LIB.T6G(SCH_1):PAGE277_I414@PURE_QUANTA.Q_RES(CHIPS)':
 C_PATH='@t6g_mb_lib.t6g(sch_1):page277_i414@pure_quanta.q_res(chips)';

PART_NAME
 R894 'Q_RES_0402LF-0,5%,1/16W,CHIP,CS00002JB38':;

SECTION_NUMBER 1
 '@T6G_MB_LIB.T6G(SCH_1):PAGE277_I412@PURE_QUANTA.Q_RES(CHIPS)':
 C_PATH='@t6g_mb_lib.t6g(sch_1):page277_i412@pure_quanta.q_res(chips)';

PART_NAME
 R893 'Q_RES_0402LF-0,5%,1/16W,CHIP,CS00002JB38':;

SECTION_NUMBER 1
 '@T6G_MB_LIB.T6G(SCH_1):PAGE277_I410@PURE_QUANTA.Q_RES(CHIPS)':
 C_PATH='@t6g_mb_lib.t6g(sch_1):page277_i410@pure_quanta.q_res(chips)';

PART_NAME
 R837 'Q_RES_0402LF-0,5%,1/16W,CHIP,CS00002JB38':;

SECTION_NUMBER 1
 '@T6G_MB_LIB.T6G(SCH_1):PAGE277_I411@PURE_QUANTA.Q_RES(CHIPS)':
 C_PATH='@t6g_mb_lib.t6g(sch_1):page277_i411@pure_quanta.q_res(chips)';

PART_NAME
 R836 'Q_RES_0402LF-10K,1%,1/16W,CHIP,TMP_QCS31002FB26':;

SECTION_NUMBER 1
 '@T6G_MB_LIB.T6G(SCH_1):PAGE277_I434@PURE_QUANTA.Q_RES(CHIPS)':
 C_PATH='@t6g_mb_lib.t6g(sch_1):page277_i434@pure_quanta.q_res(chips)';

PART_NAME
 R704 'Q_RES_0402LF-1K,1%,1/16W,CHIP,TMP_QCS21002FB24':;

SECTION_NUMBER 1
 '@T6G_MB_LIB.T6G(SCH_1):PAGE277_I449@PURE_QUANTA.Q_RES(CHIPS)':
 C_PATH='@t6g_mb_lib.t6g(sch_1):page277_i449@pure_quanta.q_res(chips)';

PART_NAME
 R703 'Q_RES_0402LF-10K,1%,1/16W,EMPTY,TMP_QCS31002FB26':;

SECTION_NUMBER 1
 '@T6G_MB_LIB.T6G(SCH_1):PAGE277_I443@PURE_QUANTA.Q_RES(CHIPS)':
 C_PATH='@t6g_mb_lib.t6g(sch_1):page277_i443@pure_quanta.q_res(chips)';

PART_NAME
 Q77 'MOSFET_NCH_DUAL-2N7002KDW,SMLF,IC,BAM70020047':;

SECTION_NUMBER 1
 '@T6G_MB_LIB.T6G(SCH_1):PAGE277_I393@PURE_QUANTA.MOSFET_NCH_DUAL(CHIPS)':
 C_PATH='@t6g_mb_lib.t6g(sch_1):page277_i393@pure_quanta.mosfet_nch_dual(chips)';

SECTION_NUMBER 2
 '@T6G_MB_LIB.T6G(SCH_1):PAGE277_I390@PURE_QUANTA.MOSFET_NCH_DUAL(CHIPS)':
 C_PATH='@t6g_mb_lib.t6g(sch_1):page277_i390@pure_quanta.mosfet_nch_dual(chips)';

PART_NAME
 JP32 'CONN3_210HP1030BR1-CONN3_210-HP1-030BR1,THLF,IO,DFHD03MS213':;

SECTION_NUMBER 1
 '@T6G_MB_LIB.T6G(SCH_1):PAGE277_I441@PURE_QUANTA.CONN3_210HP1030BR1(CHIPS)':
 C_PATH='@t6g_mb_lib.t6g(sch_1):page277_i441@pure_quanta.conn3_210hp1030br1(chip~
s)';

PART_NAME
 C1172 'Q_CAP_0402-0.1UF,25V,10%,X7R,CH4104K1B00':;

SECTION_NUMBER 1
 '@T6G_MB_LIB.T6G(SCH_1):PAGE277_I431@PURE_QUANTA.Q_CAP(CHIPS)':
 C_PATH='@t6g_mb_lib.t6g(sch_1):page277_i431@pure_quanta.q_cap(chips)';

PART_NAME
 U3 '10M25DAF484C7G-10M25DAF484C7G,SMLF,IC,AJ10M250T02':;

SECTION_NUMBER 1
 '@T6G_MB_LIB.T6G(SCH_1):PAGE238_I108@PURE_QUANTA.10M25DAF484C7G(CHIPS)':
 C_PATH='@s6q_mb_lib.s6q(sch_1):page238_i108@pure_quanta.\10m25daf484c7g\(chips)~
';

SECTION_NUMBER 2
 '@T6G_MB_LIB.T6G(SCH_1):PAGE239_I286@PURE_QUANTA.10M25DAF484C7G(CHIPS)':
 C_PATH='@s6q_mb_lib.s6q(sch_1):page239_i286@pure_quanta.\10m25daf484c7g\(chips)~
';

SECTION_NUMBER 3
 '@T6G_MB_LIB.T6G(SCH_1):PAGE240_I264@PURE_QUANTA.10M25DAF484C7G(CHIPS)':
 C_PATH='@s6q_mb_lib.s6q(sch_1):page240_i264@pure_quanta.\10m25daf484c7g\(chips)~
';

SECTION_NUMBER 4
 '@T6G_MB_LIB.T6G(SCH_1):PAGE241_I235@PURE_QUANTA.10M25DAF484C7G(CHIPS)':
 C_PATH='@s6q_mb_lib.s6q(sch_1):page241_i235@pure_quanta.\10m25daf484c7g\(chips)~
';

SECTION_NUMBER 5
 '@T6G_MB_LIB.T6G(SCH_1):PAGE242_I229@PURE_QUANTA.10M25DAF484C7G(CHIPS)':
 C_PATH='@s6q_mb_lib.s6q(sch_1):page242_i229@pure_quanta.\10m25daf484c7g\(chips)~
';

SECTION_NUMBER 6
 '@T6G_MB_LIB.T6G(SCH_1):PAGE242_I258@PURE_QUANTA.10M25DAF484C7G(CHIPS)':
 C_PATH='@s6q_mb_lib.s6q(sch_1):page242_i258@pure_quanta.\10m25daf484c7g\(chips)~
';

SECTION_NUMBER 7
 '@T6G_MB_LIB.T6G(SCH_1):PAGE243_I440@PURE_QUANTA.10M25DAF484C7G(CHIPS)':
 C_PATH='@s6q_mb_lib.s6q(sch_1):page243_i440@pure_quanta.\10m25daf484c7g\(chips)~
';

PART_NAME
 R514 'Q_RES_1206LF-0,5%,1/4W,EMPTY,CS00006J248':;

SECTION_NUMBER 1
 '@T6G_MB_LIB.T6G(SCH_1):PAGE243_I417@PURE_QUANTA.Q_RES(CHIPS)':
 C_PATH='@t6g_mb_lib.t6g(sch_1):page243_i417@pure_quanta.q_res(chips)';

PART_NAME
 R513 'Q_RES_1206LF-0,5%,1/4W,CHIP,CS00006J248':;

SECTION_NUMBER 1
 '@T6G_MB_LIB.T6G(SCH_1):PAGE243_I416@PURE_QUANTA.Q_RES(CHIPS)':
 C_PATH='@t6g_mb_lib.t6g(sch_1):page243_i416@pure_quanta.q_res(chips)';

PART_NAME
 R512 'Q_RES_1206LF-0,5%,1/4W,EMPTY,CS00006J248':;

SECTION_NUMBER 1
 '@T6G_MB_LIB.T6G(SCH_1):PAGE243_I426@PURE_QUANTA.Q_RES(CHIPS)':
 C_PATH='@t6g_mb_lib.t6g(sch_1):page243_i426@pure_quanta.q_res(chips)';

PART_NAME
 R511 'Q_RES_1206LF-0,5%,1/4W,CHIP,CS00006J248':;

SECTION_NUMBER 1
 '@T6G_MB_LIB.T6G(SCH_1):PAGE243_I425@PURE_QUANTA.Q_RES(CHIPS)':
 C_PATH='@t6g_mb_lib.t6g(sch_1):page243_i425@pure_quanta.q_res(chips)';

PART_NAME
 R510 'Q_RES_0402LF-0,5%,1/16W,CHIP,CS00002JB38':;

SECTION_NUMBER 1
 '@T6G_MB_LIB.T6G(SCH_1):PAGE243_I390@PURE_QUANTA.Q_RES(CHIPS)':
 C_PATH='@t6g_mb_lib.t6g(sch_1):page243_i390@pure_quanta.q_res(chips)';

PART_NAME
 R509 'Q_RES_0402LF-0,5%,1/16W,CHIP,CS00002JB38':;

SECTION_NUMBER 1
 '@T6G_MB_LIB.T6G(SCH_1):PAGE243_I430@PURE_QUANTA.Q_RES(CHIPS)':
 C_PATH='@t6g_mb_lib.t6g(sch_1):page243_i430@pure_quanta.q_res(chips)';

PART_NAME
 R508 'Q_RES_0402LF-0,5%,1/16W,CHIP,CS00002JB38':;

SECTION_NUMBER 1
 '@T6G_MB_LIB.T6G(SCH_1):PAGE243_I437@PURE_QUANTA.Q_RES(CHIPS)':
 C_PATH='@t6g_mb_lib.t6g(sch_1):page243_i437@pure_quanta.q_res(chips)';

PART_NAME
 R507 'Q_RES_0402LF-0,5%,1/16W,EMPTY,CS00002JB38':;

SECTION_NUMBER 1
 '@T6G_MB_LIB.T6G(SCH_1):PAGE243_I436@PURE_QUANTA.Q_RES(CHIPS)':
 C_PATH='@t6g_mb_lib.t6g(sch_1):page243_i436@pure_quanta.q_res(chips)';

PART_NAME
 L37 'Q_INDUCTOR_SMLF-BLM18PG121SN1D/2000MA,IND,CX8PG121009':;

SECTION_NUMBER 1
 '@T6G_MB_LIB.T6G(SCH_1):PAGE243_I386@PURE_QUANTA.Q_INDUCTOR(CHIPS)':
 C_PATH='@t6g_mb_lib.t6g(sch_1):page243_i386@pure_quanta.q_inductor(chips)';

PART_NAME
 L36 'Q_INDUCTOR_SMLF-BLM18PG121SN1D/2000MA,IND,CX8PG121009':;

SECTION_NUMBER 1
 '@T6G_MB_LIB.T6G(SCH_1):PAGE243_I385@PURE_QUANTA.Q_INDUCTOR(CHIPS)':
 C_PATH='@t6g_mb_lib.t6g(sch_1):page243_i385@pure_quanta.q_inductor(chips)';

PART_NAME
 C1169 'Q_CAP_0402-0.1UF,25V,10%,X7R,CH4104K1B00':;

SECTION_NUMBER 1
 '@T6G_MB_LIB.T6G(SCH_1):PAGE243_I412@PURE_QUANTA.Q_CAP(CHIPS)':
 C_PATH='@t6g_mb_lib.t6g(sch_1):page243_i412@pure_quanta.q_cap(chips)';

PART_NAME
 C1168 'Q_CAP_0402-0.1UF,25V,10%,X7R,CH4104K1B00':;

SECTION_NUMBER 1
 '@T6G_MB_LIB.T6G(SCH_1):PAGE243_I346@PURE_QUANTA.Q_CAP(CHIPS)':
 C_PATH='@t6g_mb_lib.t6g(sch_1):page243_i346@pure_quanta.q_cap(chips)';

PART_NAME
 C1167 'Q_CAP_0402-0.1UF,25V,10%,X7R,CH4104K1B00':;

SECTION_NUMBER 1
 '@T6G_MB_LIB.T6G(SCH_1):PAGE243_I339@PURE_QUANTA.Q_CAP(CHIPS)':
 C_PATH='@t6g_mb_lib.t6g(sch_1):page243_i339@pure_quanta.q_cap(chips)';

PART_NAME
 C1166 'Q_CAP_0402-0.1UF,25V,10%,X7R,CH4104K1B00':;

SECTION_NUMBER 1
 '@T6G_MB_LIB.T6G(SCH_1):PAGE243_I413@PURE_QUANTA.Q_CAP(CHIPS)':
 C_PATH='@t6g_mb_lib.t6g(sch_1):page243_i413@pure_quanta.q_cap(chips)';

PART_NAME
 C1165 'Q_CAP_0402-0.1UF,25V,10%,X7R,CH4104K1B00':;

SECTION_NUMBER 1
 '@T6G_MB_LIB.T6G(SCH_1):PAGE243_I347@PURE_QUANTA.Q_CAP(CHIPS)':
 C_PATH='@t6g_mb_lib.t6g(sch_1):page243_i347@pure_quanta.q_cap(chips)';

PART_NAME
 C1164 'Q_CAP_0402-0.1UF,25V,10%,X7R,CH4104K1B00':;

SECTION_NUMBER 1
 '@T6G_MB_LIB.T6G(SCH_1):PAGE243_I340@PURE_QUANTA.Q_CAP(CHIPS)':
 C_PATH='@t6g_mb_lib.t6g(sch_1):page243_i340@pure_quanta.q_cap(chips)';

PART_NAME
 C1163 'Q_CAP_0402-0.1UF,25V,10%,X7R,CH4104K1B00':;

SECTION_NUMBER 1
 '@T6G_MB_LIB.T6G(SCH_1):PAGE243_I338@PURE_QUANTA.Q_CAP(CHIPS)':
 C_PATH='@t6g_mb_lib.t6g(sch_1):page243_i338@pure_quanta.q_cap(chips)';

PART_NAME
 C1162 'Q_CAP_0402-0.1UF,25V,10%,X7R,CH4104K1B00':;

SECTION_NUMBER 1
 '@T6G_MB_LIB.T6G(SCH_1):PAGE243_I348@PURE_QUANTA.Q_CAP(CHIPS)':
 C_PATH='@t6g_mb_lib.t6g(sch_1):page243_i348@pure_quanta.q_cap(chips)';

PART_NAME
 C1161 'Q_CAP_0402-0.1UF,25V,10%,X7R,CH4104K1B00':;

SECTION_NUMBER 1
 '@T6G_MB_LIB.T6G(SCH_1):PAGE243_I344@PURE_QUANTA.Q_CAP(CHIPS)':
 C_PATH='@t6g_mb_lib.t6g(sch_1):page243_i344@pure_quanta.q_cap(chips)';

PART_NAME
 C1160 'Q_CAP_0402-0.1UF,25V,10%,X7R,CH4104K1B00':;

SECTION_NUMBER 1
 '@T6G_MB_LIB.T6G(SCH_1):PAGE243_I414@PURE_QUANTA.Q_CAP(CHIPS)':
 C_PATH='@t6g_mb_lib.t6g(sch_1):page243_i414@pure_quanta.q_cap(chips)';

PART_NAME
 C1159 'Q_CAP_0402-0.1UF,25V,10%,X7R,CH4104K1B00':;

SECTION_NUMBER 1
 '@T6G_MB_LIB.T6G(SCH_1):PAGE243_I341@PURE_QUANTA.Q_CAP(CHIPS)':
 C_PATH='@t6g_mb_lib.t6g(sch_1):page243_i341@pure_quanta.q_cap(chips)';

PART_NAME
 C1158 'Q_CAP_0402-0.1UF,25V,10%,X7R,CH4104K1B00':;

SECTION_NUMBER 1
 '@T6G_MB_LIB.T6G(SCH_1):PAGE243_I349@PURE_QUANTA.Q_CAP(CHIPS)':
 C_PATH='@t6g_mb_lib.t6g(sch_1):page243_i349@pure_quanta.q_cap(chips)';

PART_NAME
 C1157 'Q_CAP_0402-0.1UF,25V,10%,X7R,CH4104K1B00':;

SECTION_NUMBER 1
 '@T6G_MB_LIB.T6G(SCH_1):PAGE243_I345@PURE_QUANTA.Q_CAP(CHIPS)':
 C_PATH='@t6g_mb_lib.t6g(sch_1):page243_i345@pure_quanta.q_cap(chips)';

PART_NAME
 C1156 'Q_CAP_0402-0.1UF,25V,10%,X7R,CH4104K1B00':;

SECTION_NUMBER 1
 '@T6G_MB_LIB.T6G(SCH_1):PAGE243_I342@PURE_QUANTA.Q_CAP(CHIPS)':
 C_PATH='@t6g_mb_lib.t6g(sch_1):page243_i342@pure_quanta.q_cap(chips)';

PART_NAME
 C1155 'Q_CAP_0402-0.1UF,25V,10%,X7R,CH4104K1B00':;

SECTION_NUMBER 1
 '@T6G_MB_LIB.T6G(SCH_1):PAGE243_I369@PURE_QUANTA.Q_CAP(CHIPS)':
 C_PATH='@t6g_mb_lib.t6g(sch_1):page243_i369@pure_quanta.q_cap(chips)';

PART_NAME
 C1154 'Q_CAP_0402-0.1UF,25V,10%,X7R,CH4104K1B00':;

SECTION_NUMBER 1
 '@T6G_MB_LIB.T6G(SCH_1):PAGE243_I363@PURE_QUANTA.Q_CAP(CHIPS)':
 C_PATH='@t6g_mb_lib.t6g(sch_1):page243_i363@pure_quanta.q_cap(chips)';

PART_NAME
 C1153 'Q_CAP_0402-0.1UF,25V,10%,X7R,CH4104K1B00':;

SECTION_NUMBER 1
 '@T6G_MB_LIB.T6G(SCH_1):PAGE243_I370@PURE_QUANTA.Q_CAP(CHIPS)':
 C_PATH='@t6g_mb_lib.t6g(sch_1):page243_i370@pure_quanta.q_cap(chips)';

PART_NAME
 C1152 'Q_CAP_0402-0.1UF,25V,10%,X7R,CH4104K1B00':;

SECTION_NUMBER 1
 '@T6G_MB_LIB.T6G(SCH_1):PAGE243_I364@PURE_QUANTA.Q_CAP(CHIPS)':
 C_PATH='@t6g_mb_lib.t6g(sch_1):page243_i364@pure_quanta.q_cap(chips)';

PART_NAME
 C1151 'Q_CAP_0402-0.1UF,25V,10%,X7R,CH4104K1B00':;

SECTION_NUMBER 1
 '@T6G_MB_LIB.T6G(SCH_1):PAGE243_I371@PURE_QUANTA.Q_CAP(CHIPS)':
 C_PATH='@t6g_mb_lib.t6g(sch_1):page243_i371@pure_quanta.q_cap(chips)';

PART_NAME
 C1150 'Q_CAP_0402-0.1UF,25V,10%,X7R,CH4104K1B00':;

SECTION_NUMBER 1
 '@T6G_MB_LIB.T6G(SCH_1):PAGE243_I367@PURE_QUANTA.Q_CAP(CHIPS)':
 C_PATH='@t6g_mb_lib.t6g(sch_1):page243_i367@pure_quanta.q_cap(chips)';

PART_NAME
 C1149 'Q_CAP_0402-0.1UF,25V,10%,X7R,CH4104K1B00':;

SECTION_NUMBER 1
 '@T6G_MB_LIB.T6G(SCH_1):PAGE243_I365@PURE_QUANTA.Q_CAP(CHIPS)':
 C_PATH='@t6g_mb_lib.t6g(sch_1):page243_i365@pure_quanta.q_cap(chips)';

PART_NAME
 C1148 'Q_CAP_0402-0.1UF,25V,10%,X7R,CH4104K1B00':;

SECTION_NUMBER 1
 '@T6G_MB_LIB.T6G(SCH_1):PAGE243_I352@PURE_QUANTA.Q_CAP(CHIPS)':
 C_PATH='@t6g_mb_lib.t6g(sch_1):page243_i352@pure_quanta.q_cap(chips)';

PART_NAME
 C1147 'Q_CAP_0402-0.1UF,25V,10%,X7R,CH4104K1B00':;

SECTION_NUMBER 1
 '@T6G_MB_LIB.T6G(SCH_1):PAGE243_I372@PURE_QUANTA.Q_CAP(CHIPS)':
 C_PATH='@t6g_mb_lib.t6g(sch_1):page243_i372@pure_quanta.q_cap(chips)';

PART_NAME
 C1146 'Q_CAP_0402-0.1UF,25V,10%,X7R,CH4104K1B00':;

SECTION_NUMBER 1
 '@T6G_MB_LIB.T6G(SCH_1):PAGE243_I368@PURE_QUANTA.Q_CAP(CHIPS)':
 C_PATH='@t6g_mb_lib.t6g(sch_1):page243_i368@pure_quanta.q_cap(chips)';

PART_NAME
 C1145 'Q_CAP_0402-0.1UF,25V,10%,X7R,CH4104K1B00':;

SECTION_NUMBER 1
 '@T6G_MB_LIB.T6G(SCH_1):PAGE243_I366@PURE_QUANTA.Q_CAP(CHIPS)':
 C_PATH='@t6g_mb_lib.t6g(sch_1):page243_i366@pure_quanta.q_cap(chips)';

PART_NAME
 C1144 'Q_CAP_0402-0.1UF,25V,10%,X7R,CH4104K1B00':;

SECTION_NUMBER 1
 '@T6G_MB_LIB.T6G(SCH_1):PAGE243_I353@PURE_QUANTA.Q_CAP(CHIPS)':
 C_PATH='@t6g_mb_lib.t6g(sch_1):page243_i353@pure_quanta.q_cap(chips)';

PART_NAME
 C1143 'Q_CAP_0402-0.1UF,25V,10%,X7R,CH4104K1B00':;

SECTION_NUMBER 1
 '@T6G_MB_LIB.T6G(SCH_1):PAGE243_I381@PURE_QUANTA.Q_CAP(CHIPS)':
 C_PATH='@t6g_mb_lib.t6g(sch_1):page243_i381@pure_quanta.q_cap(chips)';

PART_NAME
 C1142 'Q_CAP_0402-0.1UF,25V,10%,X7R,CH4104K1B00':;

SECTION_NUMBER 1
 '@T6G_MB_LIB.T6G(SCH_1):PAGE243_I375@PURE_QUANTA.Q_CAP(CHIPS)':
 C_PATH='@t6g_mb_lib.t6g(sch_1):page243_i375@pure_quanta.q_cap(chips)';

PART_NAME
 C1141 'Q_CAP_0402-0.1UF,25V,10%,X7R,CH4104K1B00':;

SECTION_NUMBER 1
 '@T6G_MB_LIB.T6G(SCH_1):PAGE243_I373@PURE_QUANTA.Q_CAP(CHIPS)':
 C_PATH='@t6g_mb_lib.t6g(sch_1):page243_i373@pure_quanta.q_cap(chips)';

PART_NAME
 C1140 'Q_CAP_0402-0.1UF,25V,10%,X7R,CH4104K1B00':;

SECTION_NUMBER 1
 '@T6G_MB_LIB.T6G(SCH_1):PAGE243_I355@PURE_QUANTA.Q_CAP(CHIPS)':
 C_PATH='@t6g_mb_lib.t6g(sch_1):page243_i355@pure_quanta.q_cap(chips)';

PART_NAME
 C1139 'Q_CAP_0402-0.1UF,25V,10%,X7R,CH4104K1B00':;

SECTION_NUMBER 1
 '@T6G_MB_LIB.T6G(SCH_1):PAGE243_I382@PURE_QUANTA.Q_CAP(CHIPS)':
 C_PATH='@t6g_mb_lib.t6g(sch_1):page243_i382@pure_quanta.q_cap(chips)';

PART_NAME
 C1138 'Q_CAP_0402-0.1UF,25V,10%,X7R,CH4104K1B00':;

SECTION_NUMBER 1
 '@T6G_MB_LIB.T6G(SCH_1):PAGE243_I376@PURE_QUANTA.Q_CAP(CHIPS)':
 C_PATH='@t6g_mb_lib.t6g(sch_1):page243_i376@pure_quanta.q_cap(chips)';

PART_NAME
 C1137 'Q_CAP_0402-0.1UF,25V,10%,X7R,CH4104K1B00':;

SECTION_NUMBER 1
 '@T6G_MB_LIB.T6G(SCH_1):PAGE243_I374@PURE_QUANTA.Q_CAP(CHIPS)':
 C_PATH='@t6g_mb_lib.t6g(sch_1):page243_i374@pure_quanta.q_cap(chips)';

PART_NAME
 C1136 'Q_CAP_0402-0.1UF,25V,10%,X7R,CH4104K1B00':;

SECTION_NUMBER 1
 '@T6G_MB_LIB.T6G(SCH_1):PAGE243_I356@PURE_QUANTA.Q_CAP(CHIPS)':
 C_PATH='@t6g_mb_lib.t6g(sch_1):page243_i356@pure_quanta.q_cap(chips)';

PART_NAME
 C1135 'Q_CAP_0402-0.1UF,25V,10%,X7R,CH4104K1B00':;

SECTION_NUMBER 1
 '@T6G_MB_LIB.T6G(SCH_1):PAGE243_I421@PURE_QUANTA.Q_CAP(CHIPS)':
 C_PATH='@t6g_mb_lib.t6g(sch_1):page243_i421@pure_quanta.q_cap(chips)';

PART_NAME
 C1134 'Q_CAP_0402-0.1UF,25V,10%,X7R,CH4104K1B00':;

SECTION_NUMBER 1
 '@T6G_MB_LIB.T6G(SCH_1):PAGE243_I336@PURE_QUANTA.Q_CAP(CHIPS)':
 C_PATH='@t6g_mb_lib.t6g(sch_1):page243_i336@pure_quanta.q_cap(chips)';

PART_NAME
 C1133 'Q_CAP_0402-0.1UF,25V,10%,X7R,CH4104K1B00':;

SECTION_NUMBER 1
 '@T6G_MB_LIB.T6G(SCH_1):PAGE243_I379@PURE_QUANTA.Q_CAP(CHIPS)':
 C_PATH='@t6g_mb_lib.t6g(sch_1):page243_i379@pure_quanta.q_cap(chips)';

PART_NAME
 C1132 'Q_CAP_0402-0.1UF,25V,10%,X7R,CH4104K1B00':;

SECTION_NUMBER 1
 '@T6G_MB_LIB.T6G(SCH_1):PAGE243_I377@PURE_QUANTA.Q_CAP(CHIPS)':
 C_PATH='@t6g_mb_lib.t6g(sch_1):page243_i377@pure_quanta.q_cap(chips)';

PART_NAME
 C1131 'Q_CAP_0402-0.1UF,25V,10%,X7R,CH4104K1B00':;

SECTION_NUMBER 1
 '@T6G_MB_LIB.T6G(SCH_1):PAGE243_I360@PURE_QUANTA.Q_CAP(CHIPS)':
 C_PATH='@t6g_mb_lib.t6g(sch_1):page243_i360@pure_quanta.q_cap(chips)';

PART_NAME
 C1130 'Q_CAP_0402-0.1UF,25V,10%,X7R,CH4104K1B00':;

SECTION_NUMBER 1
 '@T6G_MB_LIB.T6G(SCH_1):PAGE243_I357@PURE_QUANTA.Q_CAP(CHIPS)':
 C_PATH='@t6g_mb_lib.t6g(sch_1):page243_i357@pure_quanta.q_cap(chips)';

PART_NAME
 C1129 'Q_CAP_0402-0.1UF,25V,10%,X7R,CH4104K1B00':;

SECTION_NUMBER 1
 '@T6G_MB_LIB.T6G(SCH_1):PAGE243_I422@PURE_QUANTA.Q_CAP(CHIPS)':
 C_PATH='@t6g_mb_lib.t6g(sch_1):page243_i422@pure_quanta.q_cap(chips)';

PART_NAME
 C1128 'Q_CAP_0402-0.1UF,25V,10%,X7R,CH4104K1B00':;

SECTION_NUMBER 1
 '@T6G_MB_LIB.T6G(SCH_1):PAGE243_I383@PURE_QUANTA.Q_CAP(CHIPS)':
 C_PATH='@t6g_mb_lib.t6g(sch_1):page243_i383@pure_quanta.q_cap(chips)';

PART_NAME
 C1127 'Q_CAP_0402-0.1UF,25V,10%,X7R,CH4104K1B00':;

SECTION_NUMBER 1
 '@T6G_MB_LIB.T6G(SCH_1):PAGE243_I380@PURE_QUANTA.Q_CAP(CHIPS)':
 C_PATH='@t6g_mb_lib.t6g(sch_1):page243_i380@pure_quanta.q_cap(chips)';

PART_NAME
 C1126 'Q_CAP_0402-0.1UF,25V,10%,X7R,CH4104K1B00':;

SECTION_NUMBER 1
 '@T6G_MB_LIB.T6G(SCH_1):PAGE243_I378@PURE_QUANTA.Q_CAP(CHIPS)':
 C_PATH='@t6g_mb_lib.t6g(sch_1):page243_i378@pure_quanta.q_cap(chips)';

PART_NAME
 C1125 'Q_CAP_0402-0.1UF,25V,10%,X7R,CH4104K1B00':;

SECTION_NUMBER 1
 '@T6G_MB_LIB.T6G(SCH_1):PAGE243_I362@PURE_QUANTA.Q_CAP(CHIPS)':
 C_PATH='@t6g_mb_lib.t6g(sch_1):page243_i362@pure_quanta.q_cap(chips)';

PART_NAME
 C1124 'Q_CAP_0402-0.1UF,25V,10%,X7R,CH4104K1B00':;

SECTION_NUMBER 1
 '@T6G_MB_LIB.T6G(SCH_1):PAGE243_I358@PURE_QUANTA.Q_CAP(CHIPS)':
 C_PATH='@t6g_mb_lib.t6g(sch_1):page243_i358@pure_quanta.q_cap(chips)';

PART_NAME
 C1123 'Q_CAP_0402-0.1UF,25V,10%,X7R,CH4104K1B00':;

SECTION_NUMBER 1
 '@T6G_MB_LIB.T6G(SCH_1):PAGE243_I399@PURE_QUANTA.Q_CAP(CHIPS)':
 C_PATH='@t6g_mb_lib.t6g(sch_1):page243_i399@pure_quanta.q_cap(chips)';

PART_NAME
 C1122 'Q_CAP_0402-0.1UF,25V,10%,X7R,CH4104K1B00':;

SECTION_NUMBER 1
 '@T6G_MB_LIB.T6G(SCH_1):PAGE243_I393@PURE_QUANTA.Q_CAP(CHIPS)':
 C_PATH='@t6g_mb_lib.t6g(sch_1):page243_i393@pure_quanta.q_cap(chips)';

PART_NAME
 C1121 'Q_CAP_0402-0.1UF,25V,10%,X7R,CH4104K1B00':;

SECTION_NUMBER 1
 '@T6G_MB_LIB.T6G(SCH_1):PAGE243_I391@PURE_QUANTA.Q_CAP(CHIPS)':
 C_PATH='@t6g_mb_lib.t6g(sch_1):page243_i391@pure_quanta.q_cap(chips)';

PART_NAME
 C1120 'Q_CAP_0402-0.1UF,25V,10%,X7R,CH4104K1B00':;

SECTION_NUMBER 1
 '@T6G_MB_LIB.T6G(SCH_1):PAGE243_I424@PURE_QUANTA.Q_CAP(CHIPS)':
 C_PATH='@t6g_mb_lib.t6g(sch_1):page243_i424@pure_quanta.q_cap(chips)';

PART_NAME
 C1119 'Q_CAP_0402-0.1UF,25V,10%,X7R,CH4104K1B00':;

SECTION_NUMBER 1
 '@T6G_MB_LIB.T6G(SCH_1):PAGE243_I400@PURE_QUANTA.Q_CAP(CHIPS)':
 C_PATH='@t6g_mb_lib.t6g(sch_1):page243_i400@pure_quanta.q_cap(chips)';

PART_NAME
 C1118 'Q_CAP_0402-0.1UF,25V,10%,X7R,CH4104K1B00':;

SECTION_NUMBER 1
 '@T6G_MB_LIB.T6G(SCH_1):PAGE243_I394@PURE_QUANTA.Q_CAP(CHIPS)':
 C_PATH='@t6g_mb_lib.t6g(sch_1):page243_i394@pure_quanta.q_cap(chips)';

PART_NAME
 C1117 'Q_CAP_0402-0.1UF,25V,10%,X7R,CH4104K1B00':;

SECTION_NUMBER 1
 '@T6G_MB_LIB.T6G(SCH_1):PAGE243_I392@PURE_QUANTA.Q_CAP(CHIPS)':
 C_PATH='@t6g_mb_lib.t6g(sch_1):page243_i392@pure_quanta.q_cap(chips)';

PART_NAME
 C1116 'Q_CAP_C0402-2.2UF,6.3V,20%,X6S,CH5221MEB00':;

SECTION_NUMBER 1
 '@T6G_MB_LIB.T6G(SCH_1):PAGE243_I387@PURE_QUANTA.Q_CAP(CHIPS)':
 C_PATH='@t6g_mb_lib.t6g(sch_1):page243_i387@pure_quanta.q_cap(chips)';

PART_NAME
 C1115 'Q_CAP_C0402-2.2UF,6.3V,20%,X6S,CH5221MEB00':;

SECTION_NUMBER 1
 '@T6G_MB_LIB.T6G(SCH_1):PAGE243_I384@PURE_QUANTA.Q_CAP(CHIPS)':
 C_PATH='@t6g_mb_lib.t6g(sch_1):page243_i384@pure_quanta.q_cap(chips)';

PART_NAME
 C1114 'Q_CAP_0402-0.1UF,25V,10%,X7R,CH4104K1B00':;

SECTION_NUMBER 1
 '@T6G_MB_LIB.T6G(SCH_1):PAGE243_I401@PURE_QUANTA.Q_CAP(CHIPS)':
 C_PATH='@t6g_mb_lib.t6g(sch_1):page243_i401@pure_quanta.q_cap(chips)';

PART_NAME
 C1113 'Q_CAP_0402-0.1UF,25V,10%,X7R,CH4104K1B00':;

SECTION_NUMBER 1
 '@T6G_MB_LIB.T6G(SCH_1):PAGE243_I397@PURE_QUANTA.Q_CAP(CHIPS)':
 C_PATH='@t6g_mb_lib.t6g(sch_1):page243_i397@pure_quanta.q_cap(chips)';

PART_NAME
 C1112 'Q_CAP_0402-0.1UF,25V,10%,X7R,CH4104K1B00':;

SECTION_NUMBER 1
 '@T6G_MB_LIB.T6G(SCH_1):PAGE243_I395@PURE_QUANTA.Q_CAP(CHIPS)':
 C_PATH='@t6g_mb_lib.t6g(sch_1):page243_i395@pure_quanta.q_cap(chips)';

PART_NAME
 C1111 'Q_CAP_0402-0.1UF,25V,10%,X7R,CH4104K1B00':;

SECTION_NUMBER 1
 '@T6G_MB_LIB.T6G(SCH_1):PAGE243_I402@PURE_QUANTA.Q_CAP(CHIPS)':
 C_PATH='@t6g_mb_lib.t6g(sch_1):page243_i402@pure_quanta.q_cap(chips)';

PART_NAME
 C1110 'Q_CAP_0402-0.1UF,25V,10%,X7R,CH4104K1B00':;

SECTION_NUMBER 1
 '@T6G_MB_LIB.T6G(SCH_1):PAGE243_I398@PURE_QUANTA.Q_CAP(CHIPS)':
 C_PATH='@t6g_mb_lib.t6g(sch_1):page243_i398@pure_quanta.q_cap(chips)';

PART_NAME
 C1109 'Q_CAP_0402-0.1UF,25V,10%,X7R,CH4104K1B00':;

SECTION_NUMBER 1
 '@T6G_MB_LIB.T6G(SCH_1):PAGE243_I396@PURE_QUANTA.Q_CAP(CHIPS)':
 C_PATH='@t6g_mb_lib.t6g(sch_1):page243_i396@pure_quanta.q_cap(chips)';

PART_NAME
 C1108 'Q_CAP_0402-0.1UF,25V,10%,X7R,CH4104K1B00':;

SECTION_NUMBER 1
 '@T6G_MB_LIB.T6G(SCH_1):PAGE243_I409@PURE_QUANTA.Q_CAP(CHIPS)':
 C_PATH='@t6g_mb_lib.t6g(sch_1):page243_i409@pure_quanta.q_cap(chips)';

PART_NAME
 C1107 'Q_CAP_0402-0.1UF,25V,10%,X7R,CH4104K1B00':;

SECTION_NUMBER 1
 '@T6G_MB_LIB.T6G(SCH_1):PAGE243_I406@PURE_QUANTA.Q_CAP(CHIPS)':
 C_PATH='@t6g_mb_lib.t6g(sch_1):page243_i406@pure_quanta.q_cap(chips)';

PART_NAME
 C1106 'Q_CAP_0402-0.1UF,25V,10%,X7R,CH4104K1B00':;

SECTION_NUMBER 1
 '@T6G_MB_LIB.T6G(SCH_1):PAGE243_I403@PURE_QUANTA.Q_CAP(CHIPS)':
 C_PATH='@t6g_mb_lib.t6g(sch_1):page243_i403@pure_quanta.q_cap(chips)';

PART_NAME
 U157 'SN74LVC1G17DCKR-SN74LVC1G17DCKR,SMLF,IC,AL1G0017003':;

SECTION_NUMBER 1
 '@T6G_MB_LIB.T6G(SCH_1):PAGE180_I644@PURE_QUANTA.SN74LVC1G17DCKR(CHIPS)':
 C_PATH='@t6g_mb_lib.t6g(sch_1):page180_i644@pure_quanta.sn74lvc1g17dckr(chips)';

PART_NAME
 U55 '74LVC1G07GV-74LVC1G07GV,SMLF,IC,AL1G0007001':;

SECTION_NUMBER 1
 '@T6G_MB_LIB.T6G(SCH_1):PAGE180_I612@PURE_QUANTA.74LVC1G07GV(CHIPS)':
 C_PATH='@t6g_mb_lib.t6g(sch_1):page180_i612@pure_quanta.\74lvc1g07gv\(chips)';

PART_NAME
 U54 '74LVC1G07GV-74LVC1G07GV,SMLF,IC,AL1G0007001':;

SECTION_NUMBER 1
 '@T6G_MB_LIB.T6G(SCH_1):PAGE180_I617@PURE_QUANTA.74LVC1G07GV(CHIPS)':
 C_PATH='@t6g_mb_lib.t6g(sch_1):page180_i617@pure_quanta.\74lvc1g07gv\(chips)';

PART_NAME
 R3693 'Q_RES_0402LF-10K,1%,1/16W,CHIP,TMP_QCS31002FB26':;

SECTION_NUMBER 1
 '@T6G_MB_LIB.T6G(SCH_1):PAGE180_I654@PURE_QUANTA.Q_RES(CHIPS)':
 C_PATH='@t6g_mb_lib.t6g(sch_1):page180_i654@pure_quanta.q_res(chips)';

PART_NAME
 R3656 'Q_RES_0402LF-0,5%,1/16W,EMPTY,CS00002JB38':;

SECTION_NUMBER 1
 '@T6G_MB_LIB.T6G(SCH_1):PAGE180_I642@PURE_QUANTA.Q_RES(CHIPS)':
 C_PATH='@t6g_mb_lib.t6g(sch_1):page180_i642@pure_quanta.q_res(chips)';

PART_NAME
 R2671 'Q_RES_0402LF-33,5%,1/16W,CHIP,CS03302JB29':;

SECTION_NUMBER 1
 '@T6G_MB_LIB.T6G(SCH_1):PAGE180_I513@PURE_QUANTA.Q_RES(CHIPS)':
 C_PATH='@t6g_mb_lib.t6g(sch_1):page180_i513@pure_quanta.q_res(chips)';

PART_NAME
 R1900 'Q_RES_0402LF-33,5%,1/16W,CHIP,CS03302JB29':;

SECTION_NUMBER 1
 '@T6G_MB_LIB.T6G(SCH_1):PAGE180_I597@PURE_QUANTA.Q_RES(CHIPS)':
 C_PATH='@t6g_mb_lib.t6g(sch_1):page180_i597@pure_quanta.q_res(chips)';

PART_NAME
 R1828 'Q_RES_0402LF-10K,1%,1/16W,CHIP,TMP_QCS31002FB26':;

SECTION_NUMBER 1
 '@T6G_MB_LIB.T6G(SCH_1):PAGE180_I524@PURE_QUANTA.Q_RES(CHIPS)':
 C_PATH='@t6g_mb_lib.t6g(sch_1):page180_i524@pure_quanta.q_res(chips)';

PART_NAME
 R1827 'Q_RES_0402LF-33,5%,1/16W,CHIP,CS03302JB29':;

SECTION_NUMBER 1
 '@T6G_MB_LIB.T6G(SCH_1):PAGE180_I515@PURE_QUANTA.Q_RES(CHIPS)':
 C_PATH='@t6g_mb_lib.t6g(sch_1):page180_i515@pure_quanta.q_res(chips)';

PART_NAME
 R1697 'Q_RES_0402LF-10K,1%,1/16W,CHIP,TMP_QCS31002FB26':;

SECTION_NUMBER 1
 '@T6G_MB_LIB.T6G(SCH_1):PAGE180_I602@PURE_QUANTA.Q_RES(CHIPS)':
 C_PATH='@t6g_mb_lib.t6g(sch_1):page180_i602@pure_quanta.q_res(chips)';

PART_NAME
 R1696 'Q_RES_0402LF-10K,1%,1/16W,CHIP,TMP_QCS31002FB26':;

SECTION_NUMBER 1
 '@T6G_MB_LIB.T6G(SCH_1):PAGE180_I606@PURE_QUANTA.Q_RES(CHIPS)':
 C_PATH='@t6g_mb_lib.t6g(sch_1):page180_i606@pure_quanta.q_res(chips)';

PART_NAME
 R1604 'Q_RES_0402LF-2K,1%,1/16W,CHIP,TMP_QCS22002FB19':;

SECTION_NUMBER 1
 '@T6G_MB_LIB.T6G(SCH_1):PAGE180_I530@PURE_QUANTA.Q_RES(CHIPS)':
 C_PATH='@t6g_mb_lib.t6g(sch_1):page180_i530@pure_quanta.q_res(chips)';

PART_NAME
 R1603 'Q_RES_0402LF-2K,1%,1/16W,CHIP,TMP_QCS22002FB19':;

SECTION_NUMBER 1
 '@T6G_MB_LIB.T6G(SCH_1):PAGE180_I529@PURE_QUANTA.Q_RES(CHIPS)':
 C_PATH='@t6g_mb_lib.t6g(sch_1):page180_i529@pure_quanta.q_res(chips)';

PART_NAME
 R1602 'Q_RES_0402LF-2K,1%,1/16W,CHIP,TMP_QCS22002FB19':;

SECTION_NUMBER 1
 '@T6G_MB_LIB.T6G(SCH_1):PAGE180_I528@PURE_QUANTA.Q_RES(CHIPS)':
 C_PATH='@t6g_mb_lib.t6g(sch_1):page180_i528@pure_quanta.q_res(chips)';

PART_NAME
 R1601 'Q_RES_0402LF-10K,1%,1/16W,CHIP,TMP_QCS31002FB26':;

SECTION_NUMBER 1
 '@T6G_MB_LIB.T6G(SCH_1):PAGE180_I507@PURE_QUANTA.Q_RES(CHIPS)':
 C_PATH='@t6g_mb_lib.t6g(sch_1):page180_i507@pure_quanta.q_res(chips)';

PART_NAME
 R1600 'Q_RES_0402LF-33,5%,1/16W,CHIP,CS03302JB29':;

SECTION_NUMBER 1
 '@T6G_MB_LIB.T6G(SCH_1):PAGE180_I511@PURE_QUANTA.Q_RES(CHIPS)':
 C_PATH='@t6g_mb_lib.t6g(sch_1):page180_i511@pure_quanta.q_res(chips)';

PART_NAME
 R1599 'Q_RES_0402LF-2K,1%,1/16W,CHIP,TMP_QCS22002FB19':;

SECTION_NUMBER 1
 '@T6G_MB_LIB.T6G(SCH_1):PAGE180_I527@PURE_QUANTA.Q_RES(CHIPS)':
 C_PATH='@t6g_mb_lib.t6g(sch_1):page180_i527@pure_quanta.q_res(chips)';

PART_NAME
 R1598 'Q_RES_0402LF-2K,1%,1/16W,CHIP,TMP_QCS22002FB19':;

SECTION_NUMBER 1
 '@T6G_MB_LIB.T6G(SCH_1):PAGE180_I526@PURE_QUANTA.Q_RES(CHIPS)':
 C_PATH='@t6g_mb_lib.t6g(sch_1):page180_i526@pure_quanta.q_res(chips)';

PART_NAME
 R1597 'Q_RES_0402LF-2K,1%,1/16W,CHIP,TMP_QCS22002FB19':;

SECTION_NUMBER 1
 '@T6G_MB_LIB.T6G(SCH_1):PAGE180_I525@PURE_QUANTA.Q_RES(CHIPS)':
 C_PATH='@t6g_mb_lib.t6g(sch_1):page180_i525@pure_quanta.q_res(chips)';

PART_NAME
 R1596 'Q_RES_0402LF-10K,1%,1/16W,CHIP,TMP_QCS31002FB26':;

SECTION_NUMBER 1
 '@T6G_MB_LIB.T6G(SCH_1):PAGE180_I509@PURE_QUANTA.Q_RES(CHIPS)':
 C_PATH='@t6g_mb_lib.t6g(sch_1):page180_i509@pure_quanta.q_res(chips)';

PART_NAME
 R1595 'Q_RES_0402LF-10K,1%,1/16W,CHIP,TMP_QCS31002FB26':;

SECTION_NUMBER 1
 '@T6G_MB_LIB.T6G(SCH_1):PAGE180_I508@PURE_QUANTA.Q_RES(CHIPS)':
 C_PATH='@t6g_mb_lib.t6g(sch_1):page180_i508@pure_quanta.q_res(chips)';

PART_NAME
 R1593 'Q_RES_0402LF-33,5%,1/16W,CHIP,CS03302JB29':;

SECTION_NUMBER 1
 '@T6G_MB_LIB.T6G(SCH_1):PAGE180_I514@PURE_QUANTA.Q_RES(CHIPS)':
 C_PATH='@t6g_mb_lib.t6g(sch_1):page180_i514@pure_quanta.q_res(chips)';

PART_NAME
 R1592 'Q_RES_0402LF-33,5%,1/16W,CHIP,CS03302JB29':;

SECTION_NUMBER 1
 '@T6G_MB_LIB.T6G(SCH_1):PAGE180_I512@PURE_QUANTA.Q_RES(CHIPS)':
 C_PATH='@t6g_mb_lib.t6g(sch_1):page180_i512@pure_quanta.q_res(chips)';

PART_NAME
 R1583 'Q_RES_0402LF-10K,1%,1/16W,CHIP,TMP_QCS31002FB26':;

SECTION_NUMBER 1
 '@T6G_MB_LIB.T6G(SCH_1):PAGE180_I533@PURE_QUANTA.Q_RES(CHIPS)':
 C_PATH='@t6g_mb_lib.t6g(sch_1):page180_i533@pure_quanta.q_res(chips)';

PART_NAME
 R1582 'Q_RES_0402LF-2K,1%,1/16W,CHIP,TMP_QCS22002FB19':;

SECTION_NUMBER 1
 '@T6G_MB_LIB.T6G(SCH_1):PAGE180_I531@PURE_QUANTA.Q_RES(CHIPS)':
 C_PATH='@t6g_mb_lib.t6g(sch_1):page180_i531@pure_quanta.q_res(chips)';

PART_NAME
 R1581 'Q_RES_0402LF-2K,1%,1/16W,CHIP,TMP_QCS22002FB19':;

SECTION_NUMBER 1
 '@T6G_MB_LIB.T6G(SCH_1):PAGE180_I532@PURE_QUANTA.Q_RES(CHIPS)':
 C_PATH='@t6g_mb_lib.t6g(sch_1):page180_i532@pure_quanta.q_res(chips)';

PART_NAME
 R1269 'Q_RES_0402LF-4.7K,5%,1/16W,CHIP,TMP_QCS24702JB38':;

SECTION_NUMBER 1
 '@T6G_MB_LIB.T6G(SCH_1):PAGE180_I649@PURE_QUANTA.Q_RES(CHIPS)':
 C_PATH='@t6g_mb_lib.t6g(sch_1):page180_i649@pure_quanta.q_res(chips)';

PART_NAME
 R1268 'Q_RES_0402LF-33,5%,1/16W,CHIP,CS03302JB29':;

SECTION_NUMBER 1
 '@T6G_MB_LIB.T6G(SCH_1):PAGE180_I648@PURE_QUANTA.Q_RES(CHIPS)':
 C_PATH='@t6g_mb_lib.t6g(sch_1):page180_i648@pure_quanta.q_res(chips)';

PART_NAME
 R833 'Q_RES_0402LF-10K,1%,1/16W,CHIP,TMP_QCS31002FB26':;

SECTION_NUMBER 1
 '@T6G_MB_LIB.T6G(SCH_1):PAGE180_I634@PURE_QUANTA.Q_RES(CHIPS)':
 C_PATH='@t6g_mb_lib.t6g(sch_1):page180_i634@pure_quanta.q_res(chips)';

PART_NAME
 R832 'Q_RES_0402LF-10K,1%,1/16W,CHIP,TMP_QCS31002FB26':;

SECTION_NUMBER 1
 '@T6G_MB_LIB.T6G(SCH_1):PAGE180_I635@PURE_QUANTA.Q_RES(CHIPS)':
 C_PATH='@t6g_mb_lib.t6g(sch_1):page180_i635@pure_quanta.q_res(chips)';

PART_NAME
 R831 'Q_RES_0402LF-10K,1%,1/16W,CHIP,TMP_QCS31002FB26':;

SECTION_NUMBER 1
 '@T6G_MB_LIB.T6G(SCH_1):PAGE180_I631@PURE_QUANTA.Q_RES(CHIPS)':
 C_PATH='@t6g_mb_lib.t6g(sch_1):page180_i631@pure_quanta.q_res(chips)';

PART_NAME
 R830 'Q_RES_0402LF-10K,1%,1/16W,CHIP,TMP_QCS31002FB26':;

SECTION_NUMBER 1
 '@T6G_MB_LIB.T6G(SCH_1):PAGE180_I628@PURE_QUANTA.Q_RES(CHIPS)':
 C_PATH='@t6g_mb_lib.t6g(sch_1):page180_i628@pure_quanta.q_res(chips)';

PART_NAME
 R433 'Q_RES_0402LF-0,5%,1/16W,EMPTY,CS00002JB38':;

SECTION_NUMBER 1
 '@T6G_MB_LIB.T6G(SCH_1):PAGE180_I619@PURE_QUANTA.Q_RES(CHIPS)':
 C_PATH='@t6g_mb_lib.t6g(sch_1):page180_i619@pure_quanta.q_res(chips)';

PART_NAME
 R9 'Q_RES_0402LF-0,5%,1/16W,EMPTY,CS00002JB38':;

SECTION_NUMBER 1
 '@T6G_MB_LIB.T6G(SCH_1):PAGE180_I614@PURE_QUANTA.Q_RES(CHIPS)':
 C_PATH='@t6g_mb_lib.t6g(sch_1):page180_i614@pure_quanta.q_res(chips)';

PART_NAME
 C1230 'Q_CAP_0402-0.1UF,25V,10%,X7R,CH4104K1B00':;

SECTION_NUMBER 1
 '@T6G_MB_LIB.T6G(SCH_1):PAGE180_I609@PURE_QUANTA.Q_CAP(CHIPS)':
 C_PATH='@t6g_mb_lib.t6g(sch_1):page180_i609@pure_quanta.q_cap(chips)';

PART_NAME
 C1229 'Q_CAP_0402-0.1UF,25V,10%,X7R,CH4104K1B00':;

SECTION_NUMBER 1
 '@T6G_MB_LIB.T6G(SCH_1):PAGE180_I615@PURE_QUANTA.Q_CAP(CHIPS)':
 C_PATH='@t6g_mb_lib.t6g(sch_1):page180_i615@pure_quanta.q_cap(chips)';

PART_NAME
 C1104 'Q_CAP_0402-0.1UF,25V,10%,X7R,CH4104K1B00':;

SECTION_NUMBER 1
 '@T6G_MB_LIB.T6G(SCH_1):PAGE180_I645@PURE_QUANTA.Q_CAP(CHIPS)':
 C_PATH='@t6g_mb_lib.t6g(sch_1):page180_i645@pure_quanta.q_cap(chips)';

PART_NAME
 U202 'TPS2062CDR-TPS2062CDR,SMLF,IC,AL002062004':;

SECTION_NUMBER 1
 '@T6G_MB_LIB.T6G(SCH_1):PAGE268_I63@PURE_QUANTA.TPS2062CDR(CHIPS)':
 C_PATH='@t6g_mb_lib.t6g(sch_1):page268_i63@pure_quanta.tps2062cdr(chips)';

PART_NAME
 R2395 'Q_RES_0402LF-10K,5%,1/16W,CHIP,TMP_QCS31002JB28':;

SECTION_NUMBER 1
 '@T6G_MB_LIB.T6G(SCH_1):PAGE268_I72@PURE_QUANTA.Q_RES(CHIPS)':
 C_PATH='@t6g_mb_lib.t6g(sch_1):page268_i72@pure_quanta.q_res(chips)';

PART_NAME
 R2394 'Q_RES_0402LF-0,5%,1/16W,CHIP,CS00002JB38':;

SECTION_NUMBER 1
 '@T6G_MB_LIB.T6G(SCH_1):PAGE268_I66@PURE_QUANTA.Q_RES(CHIPS)':
 C_PATH='@t6g_mb_lib.t6g(sch_1):page268_i66@pure_quanta.q_res(chips)';

PART_NAME
 R1567 'Q_RES_0402LF-0,5%,1/16W,CHIP,CS00002JB38':;

SECTION_NUMBER 1
 '@T6G_MB_LIB.T6G(SCH_1):PAGE268_I67@PURE_QUANTA.Q_RES(CHIPS)':
 C_PATH='@t6g_mb_lib.t6g(sch_1):page268_i67@pure_quanta.q_res(chips)';

PART_NAME
 R1566 'Q_RES_0402LF-10K,5%,1/16W,CHIP,TMP_QCS31002JB28':;

SECTION_NUMBER 1
 '@T6G_MB_LIB.T6G(SCH_1):PAGE268_I70@PURE_QUANTA.Q_RES(CHIPS)':
 C_PATH='@t6g_mb_lib.t6g(sch_1):page268_i70@pure_quanta.q_res(chips)';

PART_NAME
 J219 'SCONN38_U10DH3830002T-SCONN38_U10DH3830002T,SMLF,IO,DFHS38FS029':;

SECTION_NUMBER 1
 '@T6G_MB_LIB.T6G(SCH_1):PAGE268_I157@PURE_QUANTA.SCONN38_U10DH3830002T(CHIPS)':
 C_PATH='@t6g_mb_lib.t6g(sch_1):page268_i157@pure_quanta.sconn38_u10dh3830002t(c~
hips)';

PART_NAME
 C2898 'Q_CAP_C0805-22UF,10V,20%,X6S,CH6222MEA00':;

SECTION_NUMBER 1
 '@T6G_MB_LIB.T6G(SCH_1):PAGE268_I155@PURE_QUANTA.Q_CAP(CHIPS)':
 C_PATH='@t6g_mb_lib.t6g(sch_1):page268_i155@pure_quanta.q_cap(chips)';

PART_NAME
 C2890 'Q_CAP_C0805-22UF,10V,20%,X6S,CH6222MEA00':;

SECTION_NUMBER 1
 '@T6G_MB_LIB.T6G(SCH_1):PAGE268_I156@PURE_QUANTA.Q_CAP(CHIPS)':
 C_PATH='@t6g_mb_lib.t6g(sch_1):page268_i156@pure_quanta.q_cap(chips)';

PART_NAME
 C2889 'Q_CAPP_SMLF-220UF,6.3V,20%,ALUM,CC72201MZ28':;

SECTION_NUMBER 1
 '@T6G_MB_LIB.T6G(SCH_1):PAGE268_I150@PURE_QUANTA.Q_CAPP(CHIPS)':
 C_PATH='@t6g_mb_lib.t6g(sch_1):page268_i150@pure_quanta.q_capp(chips)';

PART_NAME
 C2107 'Q_CAPP_RDLF-270UF,16V,20%,ALUM,CC72703MD23':
;

SECTION_NUMBER 1
 '@T6G_MB_LIB.T6G(SCH_1):PAGE268_I140@PURE_QUANTA.Q_CAPP(CHIPS)':
 C_PATH='@t6g_mb_lib.t6g(sch_1):page268_i140@pure_quanta.q_capp(chips)';

PART_NAME
 C2106 'Q_CAPP_RDLF-270UF,16V,20%,ALUM,CC72703MD23':
;

SECTION_NUMBER 1
 '@T6G_MB_LIB.T6G(SCH_1):PAGE268_I142@PURE_QUANTA.Q_CAPP(CHIPS)':
 C_PATH='@t6g_mb_lib.t6g(sch_1):page268_i142@pure_quanta.q_capp(chips)';

PART_NAME
 C2105 'Q_CAP_0402-0.1UF,25V,10%,X7R,CH4104K1B00':;

SECTION_NUMBER 1
 '@T6G_MB_LIB.T6G(SCH_1):PAGE268_I146@PURE_QUANTA.Q_CAP(CHIPS)':
 C_PATH='@t6g_mb_lib.t6g(sch_1):page268_i146@pure_quanta.q_cap(chips)';

PART_NAME
 C2104 'Q_CAP_0402-0.1UF,25V,10%,X7R,CH4104K1B00':;

SECTION_NUMBER 1
 '@T6G_MB_LIB.T6G(SCH_1):PAGE268_I148@PURE_QUANTA.Q_CAP(CHIPS)':
 C_PATH='@t6g_mb_lib.t6g(sch_1):page268_i148@pure_quanta.q_cap(chips)';

PART_NAME
 C2103 'Q_CAP_0402-470PF,50V,10%,X7R,TMP_QCH14706KB18':;

SECTION_NUMBER 1
 '@T6G_MB_LIB.T6G(SCH_1):PAGE268_I145@PURE_QUANTA.Q_CAP(CHIPS)':
 C_PATH='@t6g_mb_lib.t6g(sch_1):page268_i145@pure_quanta.q_cap(chips)';

PART_NAME
 C2092 'Q_CAP_0402-470PF,50V,10%,X7R,TMP_QCH14706KB18':;

SECTION_NUMBER 1
 '@T6G_MB_LIB.T6G(SCH_1):PAGE268_I143@PURE_QUANTA.Q_CAP(CHIPS)':
 C_PATH='@t6g_mb_lib.t6g(sch_1):page268_i143@pure_quanta.q_cap(chips)';

PART_NAME
 C1825 'Q_CAP_0402-470PF,50V,10%,X7R,TMP_QCH14706KB18':;

SECTION_NUMBER 1
 '@T6G_MB_LIB.T6G(SCH_1):PAGE268_I153@PURE_QUANTA.Q_CAP(CHIPS)':
 C_PATH='@t6g_mb_lib.t6g(sch_1):page268_i153@pure_quanta.q_cap(chips)';

PART_NAME
 C1101 'Q_CAP_C0805-10UF,16V,10%,X6S,CH6103KEA00':;

SECTION_NUMBER 1
 '@T6G_MB_LIB.T6G(SCH_1):PAGE268_I77@PURE_QUANTA.Q_CAP(CHIPS)':
 C_PATH='@t6g_mb_lib.t6g(sch_1):page268_i77@pure_quanta.q_cap(chips)';

PART_NAME
 U150 '74CBTLV3126PW-74CBTLV3126PW,SMLF,IC,AL003126K08':;

SECTION_NUMBER 1
 '@T6G_MB_LIB.T6G(SCH_1):PAGE147_I41@PURE_QUANTA.74CBTLV3126PW(CHIPS)':
 C_PATH='@t6g_mb_lib.t6g(sch_1):page147_i41@pure_quanta.\74cbtlv3126pw\(chips)';

PART_NAME
 U149 '74CBTLV3126PW-74CBTLV3126PW,SMLF,IC,AL003126K08':;

SECTION_NUMBER 1
 '@T6G_MB_LIB.T6G(SCH_1):PAGE147_I50@PURE_QUANTA.74CBTLV3126PW(CHIPS)':
 C_PATH='@t6g_mb_lib.t6g(sch_1):page147_i50@pure_quanta.\74cbtlv3126pw\(chips)';

PART_NAME
 U148 '74CBTLV3126PW-74CBTLV3126PW,SMLF,EMPTY,AL003126K08':;

SECTION_NUMBER 1
 '@T6G_MB_LIB.T6G(SCH_1):PAGE147_I30@PURE_QUANTA.74CBTLV3126PW(CHIPS)':
 C_PATH='@t6g_mb_lib.t6g(sch_1):page147_i30@pure_quanta.\74cbtlv3126pw\(chips)';

PART_NAME
 R4663 'Q_RES_0402LF-4.7K,5%,1/16W,CHIP,TMP_QCS24702JB38':;

SECTION_NUMBER 1
 '@T6G_MB_LIB.T6G(SCH_1):PAGE147_I100@PURE_QUANTA.Q_RES(CHIPS)':
 C_PATH='@t6g_mb_lib.t6g(sch_1):page147_i100@pure_quanta.q_res(chips)';

PART_NAME
 R1985 'Q_RES_0402LF-100,1%,1/16W,CHIP,TMP_QCS11002FB22':;

SECTION_NUMBER 1
 '@T6G_MB_LIB.T6G(SCH_1):PAGE147_I92@PURE_QUANTA.Q_RES(CHIPS)':
 C_PATH='@t6g_mb_lib.t6g(sch_1):page147_i92@pure_quanta.q_res(chips)';

PART_NAME
 R1904 'Q_RES_0402LF-100,1%,1/16W,CHIP,TMP_QCS11002FB22':;

SECTION_NUMBER 1
 '@T6G_MB_LIB.T6G(SCH_1):PAGE147_I94@PURE_QUANTA.Q_RES(CHIPS)':
 C_PATH='@t6g_mb_lib.t6g(sch_1):page147_i94@pure_quanta.q_res(chips)';

PART_NAME
 R1903 'Q_RES_0402LF-100,1%,1/16W,CHIP,TMP_QCS11002FB22':;

SECTION_NUMBER 1
 '@T6G_MB_LIB.T6G(SCH_1):PAGE147_I93@PURE_QUANTA.Q_RES(CHIPS)':
 C_PATH='@t6g_mb_lib.t6g(sch_1):page147_i93@pure_quanta.q_res(chips)';

PART_NAME
 R1528 'Q_RES_0402LF-1K,1%,1/16W,CHIP,TMP_QCS21002FB24':;

SECTION_NUMBER 1
 '@T6G_MB_LIB.T6G(SCH_1):PAGE147_I66@PURE_QUANTA.Q_RES(CHIPS)':
 C_PATH='@t6g_mb_lib.t6g(sch_1):page147_i66@pure_quanta.q_res(chips)';

PART_NAME
 R1527 'Q_RES_0402LF-100K,1%,1/16W,CHIP,TMP_QCS41002FB28':;

SECTION_NUMBER 1
 '@T6G_MB_LIB.T6G(SCH_1):PAGE147_I65@PURE_QUANTA.Q_RES(CHIPS)':
 C_PATH='@t6g_mb_lib.t6g(sch_1):page147_i65@pure_quanta.q_res(chips)';

PART_NAME
 R1524 'Q_RES_0402LF-100K,1%,1/16W,CHIP,TMP_QCS41002FB28':;

SECTION_NUMBER 1
 '@T6G_MB_LIB.T6G(SCH_1):PAGE147_I67@PURE_QUANTA.Q_RES(CHIPS)':
 C_PATH='@t6g_mb_lib.t6g(sch_1):page147_i67@pure_quanta.q_res(chips)';

PART_NAME
 R1523 'Q_RES_0402LF-100K,1%,1/16W,CHIP,TMP_QCS41002FB28':;

SECTION_NUMBER 1
 '@T6G_MB_LIB.T6G(SCH_1):PAGE147_I69@PURE_QUANTA.Q_RES(CHIPS)':
 C_PATH='@t6g_mb_lib.t6g(sch_1):page147_i69@pure_quanta.q_res(chips)';

PART_NAME
 R1522 'Q_RES_0402LF-100K,1%,1/16W,CHIP,TMP_QCS41002FB28':;

SECTION_NUMBER 1
 '@T6G_MB_LIB.T6G(SCH_1):PAGE147_I80@PURE_QUANTA.Q_RES(CHIPS)':
 C_PATH='@t6g_mb_lib.t6g(sch_1):page147_i80@pure_quanta.q_res(chips)';

PART_NAME
 R1521 'Q_RES_0402LF-100K,1%,1/16W,CHIP,TMP_QCS41002FB28':;

SECTION_NUMBER 1
 '@T6G_MB_LIB.T6G(SCH_1):PAGE147_I81@PURE_QUANTA.Q_RES(CHIPS)':
 C_PATH='@t6g_mb_lib.t6g(sch_1):page147_i81@pure_quanta.q_res(chips)';

PART_NAME
 R1520 'Q_RES_0402LF-100K,1%,1/16W,CHIP,TMP_QCS41002FB28':;

SECTION_NUMBER 1
 '@T6G_MB_LIB.T6G(SCH_1):PAGE147_I82@PURE_QUANTA.Q_RES(CHIPS)':
 C_PATH='@t6g_mb_lib.t6g(sch_1):page147_i82@pure_quanta.q_res(chips)';

PART_NAME
 R1519 'Q_RES_0402LF-22,1%,1/16W,CHIP,CS02202FB12':;

SECTION_NUMBER 1
 '@T6G_MB_LIB.T6G(SCH_1):PAGE147_I73@PURE_QUANTA.Q_RES(CHIPS)':
 C_PATH='@t6g_mb_lib.t6g(sch_1):page147_i73@pure_quanta.q_res(chips)';

PART_NAME
 R1518 'Q_RES_0402LF-22,1%,1/16W,CHIP,CS02202FB12':;

SECTION_NUMBER 1
 '@T6G_MB_LIB.T6G(SCH_1):PAGE147_I74@PURE_QUANTA.Q_RES(CHIPS)':
 C_PATH='@t6g_mb_lib.t6g(sch_1):page147_i74@pure_quanta.q_res(chips)';

PART_NAME
 R1517 'Q_RES_0402LF-22,1%,1/16W,CHIP,CS02202FB12':;

SECTION_NUMBER 1
 '@T6G_MB_LIB.T6G(SCH_1):PAGE147_I75@PURE_QUANTA.Q_RES(CHIPS)':
 C_PATH='@t6g_mb_lib.t6g(sch_1):page147_i75@pure_quanta.q_res(chips)';

PART_NAME
 R1516 'Q_RES_0402LF-22,1%,1/16W,CHIP,CS02202FB12':;

SECTION_NUMBER 1
 '@T6G_MB_LIB.T6G(SCH_1):PAGE147_I76@PURE_QUANTA.Q_RES(CHIPS)':
 C_PATH='@t6g_mb_lib.t6g(sch_1):page147_i76@pure_quanta.q_res(chips)';

PART_NAME
 R1515 'Q_RES_0402LF-22,1%,1/16W,CHIP,CS02202FB12':;

SECTION_NUMBER 1
 '@T6G_MB_LIB.T6G(SCH_1):PAGE147_I77@PURE_QUANTA.Q_RES(CHIPS)':
 C_PATH='@t6g_mb_lib.t6g(sch_1):page147_i77@pure_quanta.q_res(chips)';

PART_NAME
 R1514 'Q_RES_0402LF-22,1%,1/16W,CHIP,CS02202FB12':;

SECTION_NUMBER 1
 '@T6G_MB_LIB.T6G(SCH_1):PAGE147_I79@PURE_QUANTA.Q_RES(CHIPS)':
 C_PATH='@t6g_mb_lib.t6g(sch_1):page147_i79@pure_quanta.q_res(chips)';

PART_NAME
 R1513 'Q_RES_0402LF-22,1%,1/16W,CHIP,CS02202FB12':;

SECTION_NUMBER 1
 '@T6G_MB_LIB.T6G(SCH_1):PAGE147_I78@PURE_QUANTA.Q_RES(CHIPS)':
 C_PATH='@t6g_mb_lib.t6g(sch_1):page147_i78@pure_quanta.q_res(chips)';

PART_NAME
 R923 'Q_RES_0402LF-33,5%,1/16W,CHIP,CS03302JB29':;

SECTION_NUMBER 1
 '@T6G_MB_LIB.T6G(SCH_1):PAGE147_I20@PURE_QUANTA.Q_RES(CHIPS)':
 C_PATH='@t6g_mb_lib.t6g(sch_1):page147_i20@pure_quanta.q_res(chips)';

PART_NAME
 Q172 'MOSFET_NCH_DUAL-2N7002KDW,SMLF,IC,BAM70020047':;

SECTION_NUMBER 1
 '@T6G_MB_LIB.T6G(SCH_1):PAGE147_I99@PURE_QUANTA.MOSFET_NCH_DUAL(CHIPS)':
 C_PATH='@t6g_mb_lib.t6g(sch_1):page147_i99@pure_quanta.mosfet_nch_dual(chips)';

SECTION_NUMBER 2
 '@T6G_MB_LIB.T6G(SCH_1):PAGE147_I97@PURE_QUANTA.MOSFET_NCH_DUAL(CHIPS)':
 C_PATH='@t6g_mb_lib.t6g(sch_1):page147_i97@pure_quanta.mosfet_nch_dual(chips)';

PART_NAME
 Q171 'MOSFET_NCH_DUAL-2N7002KDW,SMLF,IC,BAM70020047':;

SECTION_NUMBER 1
 '@T6G_MB_LIB.T6G(SCH_1):PAGE147_I103@PURE_QUANTA.MOSFET_NCH_DUAL(CHIPS)':
 C_PATH='@t6g_mb_lib.t6g(sch_1):page147_i103@pure_quanta.mosfet_nch_dual(chips)';

SECTION_NUMBER 2
 '@T6G_MB_LIB.T6G(SCH_1):PAGE147_I101@PURE_QUANTA.MOSFET_NCH_DUAL(CHIPS)':
 C_PATH='@t6g_mb_lib.t6g(sch_1):page147_i101@pure_quanta.mosfet_nch_dual(chips)';

PART_NAME
 C1241 'Q_CAP_0402-0.1UF,25V,10%,X7R,CH4104K1B00':;

SECTION_NUMBER 1
 '@T6G_MB_LIB.T6G(SCH_1):PAGE147_I56@PURE_QUANTA.Q_CAP(CHIPS)':
 C_PATH='@t6g_mb_lib.t6g(sch_1):page147_i56@pure_quanta.q_cap(chips)';

PART_NAME
 C1095 'Q_CAP_0402-0.1UF,25V,10%,X7R,CH4104K1B00':;

SECTION_NUMBER 1
 '@T6G_MB_LIB.T6G(SCH_1):PAGE147_I43@PURE_QUANTA.Q_CAP(CHIPS)':
 C_PATH='@t6g_mb_lib.t6g(sch_1):page147_i43@pure_quanta.q_cap(chips)';

PART_NAME
 C1094 'Q_CAP_0402-0.1UF,25V,10%,X7R,CH4104K1B00':;

SECTION_NUMBER 1
 '@T6G_MB_LIB.T6G(SCH_1):PAGE147_I51@PURE_QUANTA.Q_CAP(CHIPS)':
 C_PATH='@t6g_mb_lib.t6g(sch_1):page147_i51@pure_quanta.q_cap(chips)';

PART_NAME
 U10 'PCA9848PW-PCA9848PW,SMLF,IC,AL009848K00':;

SECTION_NUMBER 1
 '@T6G_MB_LIB.T6G(SCH_1):PAGE274_I360@PURE_QUANTA.PCA9848PW(CHIPS)':
 C_PATH='@t6g_mb_lib.t6g(sch_1):page274_i360@pure_quanta.pca9848pw(chips)';

PART_NAME
 R3639 'Q_RES_0402LF-10K,1%,1/16W,EMPTY,TMP_QCS31002FB26':;

SECTION_NUMBER 1
 '@T6G_MB_LIB.T6G(SCH_1):PAGE274_I338@PURE_QUANTA.Q_RES(CHIPS)':
 C_PATH='@t6g_mb_lib.t6g(sch_1):page274_i338@pure_quanta.q_res(chips)';

PART_NAME
 R3638 'Q_RES_0402LF-10K,1%,1/16W,EMPTY,TMP_QCS31002FB26':;

SECTION_NUMBER 1
 '@T6G_MB_LIB.T6G(SCH_1):PAGE274_I339@PURE_QUANTA.Q_RES(CHIPS)':
 C_PATH='@t6g_mb_lib.t6g(sch_1):page274_i339@pure_quanta.q_res(chips)';

PART_NAME
 R3637 'Q_RES_0402LF-10K,1%,1/16W,EMPTY,TMP_QCS31002FB26':;

SECTION_NUMBER 1
 '@T6G_MB_LIB.T6G(SCH_1):PAGE274_I337@PURE_QUANTA.Q_RES(CHIPS)':
 C_PATH='@t6g_mb_lib.t6g(sch_1):page274_i337@pure_quanta.q_res(chips)';

PART_NAME
 R3636 'Q_RES_0402LF-10K,1%,1/16W,EMPTY,TMP_QCS31002FB26':;

SECTION_NUMBER 1
 '@T6G_MB_LIB.T6G(SCH_1):PAGE274_I336@PURE_QUANTA.Q_RES(CHIPS)':
 C_PATH='@t6g_mb_lib.t6g(sch_1):page274_i336@pure_quanta.q_res(chips)';

PART_NAME
 R3633 'Q_RES_0402LF-10K,1%,1/16W,CHIP,TMP_QCS31002FB26':;

SECTION_NUMBER 1
 '@T6G_MB_LIB.T6G(SCH_1):PAGE274_I332@PURE_QUANTA.Q_RES(CHIPS)':
 C_PATH='@t6g_mb_lib.t6g(sch_1):page274_i332@pure_quanta.q_res(chips)';

PART_NAME
 R3632 'Q_RES_0402LF-10K,1%,1/16W,CHIP,TMP_QCS31002FB26':;

SECTION_NUMBER 1
 '@T6G_MB_LIB.T6G(SCH_1):PAGE274_I333@PURE_QUANTA.Q_RES(CHIPS)':
 C_PATH='@t6g_mb_lib.t6g(sch_1):page274_i333@pure_quanta.q_res(chips)';

PART_NAME
 R3631 'Q_RES_0402LF-10K,1%,1/16W,CHIP,TMP_QCS31002FB26':;

SECTION_NUMBER 1
 '@T6G_MB_LIB.T6G(SCH_1):PAGE274_I330@PURE_QUANTA.Q_RES(CHIPS)':
 C_PATH='@t6g_mb_lib.t6g(sch_1):page274_i330@pure_quanta.q_res(chips)';

PART_NAME
 R3630 'Q_RES_0402LF-10K,1%,1/16W,CHIP,TMP_QCS31002FB26':;

SECTION_NUMBER 1
 '@T6G_MB_LIB.T6G(SCH_1):PAGE274_I331@PURE_QUANTA.Q_RES(CHIPS)':
 C_PATH='@t6g_mb_lib.t6g(sch_1):page274_i331@pure_quanta.q_res(chips)';

PART_NAME
 R3627 'Q_RES_0402LF-10K,1%,1/16W,CHIP,TMP_QCS31002FB26':;

SECTION_NUMBER 1
 '@T6G_MB_LIB.T6G(SCH_1):PAGE274_I326@PURE_QUANTA.Q_RES(CHIPS)':
 C_PATH='@t6g_mb_lib.t6g(sch_1):page274_i326@pure_quanta.q_res(chips)';

PART_NAME
 R3626 'Q_RES_0402LF-10K,1%,1/16W,CHIP,TMP_QCS31002FB26':;

SECTION_NUMBER 1
 '@T6G_MB_LIB.T6G(SCH_1):PAGE274_I327@PURE_QUANTA.Q_RES(CHIPS)':
 C_PATH='@t6g_mb_lib.t6g(sch_1):page274_i327@pure_quanta.q_res(chips)';

PART_NAME
 R3625 'Q_RES_0402LF-10K,1%,1/16W,CHIP,TMP_QCS31002FB26':;

SECTION_NUMBER 1
 '@T6G_MB_LIB.T6G(SCH_1):PAGE274_I324@PURE_QUANTA.Q_RES(CHIPS)':
 C_PATH='@t6g_mb_lib.t6g(sch_1):page274_i324@pure_quanta.q_res(chips)';

PART_NAME
 R3624 'Q_RES_0402LF-10K,1%,1/16W,CHIP,TMP_QCS31002FB26':;

SECTION_NUMBER 1
 '@T6G_MB_LIB.T6G(SCH_1):PAGE274_I325@PURE_QUANTA.Q_RES(CHIPS)':
 C_PATH='@t6g_mb_lib.t6g(sch_1):page274_i325@pure_quanta.q_res(chips)';

PART_NAME
 R2703 'Q_RES_0402LF-0,5%,1/16W,CHIP,CS00002JB38':;

SECTION_NUMBER 1
 '@T6G_MB_LIB.T6G(SCH_1):PAGE274_I52@PURE_QUANTA.Q_RES(CHIPS)':
 C_PATH='@t6g_mb_lib.t6g(sch_1):page274_i52@pure_quanta.q_res(chips)';

PART_NAME
 R2697 'Q_RES_0402LF-10K,5%,1/16W,CHIP,TMP_QCS31002JB28':;

SECTION_NUMBER 1
 '@T6G_MB_LIB.T6G(SCH_1):PAGE274_I346@PURE_QUANTA.Q_RES(CHIPS)':
 C_PATH='@t6g_mb_lib.t6g(sch_1):page274_i346@pure_quanta.q_res(chips)';

PART_NAME
 R1714 'Q_RES_0402LF-0,5%,1/16W,CHIP,CS00002JB38':;

SECTION_NUMBER 1
 '@T6G_MB_LIB.T6G(SCH_1):PAGE274_I368@PURE_QUANTA.Q_RES(CHIPS)':
 C_PATH='@t6g_mb_lib.t6g(sch_1):page274_i368@pure_quanta.q_res(chips)';

PART_NAME
 R1476 'Q_RES_0402LF-0,5%,1/16W,CHIP,CS00002JB38':;

SECTION_NUMBER 1
 '@T6G_MB_LIB.T6G(SCH_1):PAGE274_I43@PURE_QUANTA.Q_RES(CHIPS)':
 C_PATH='@t6g_mb_lib.t6g(sch_1):page274_i43@pure_quanta.q_res(chips)';

PART_NAME
 R1475 'Q_RES_0402LF-0,5%,1/16W,CHIP,CS00002JB38':;

SECTION_NUMBER 1
 '@T6G_MB_LIB.T6G(SCH_1):PAGE274_I44@PURE_QUANTA.Q_RES(CHIPS)':
 C_PATH='@t6g_mb_lib.t6g(sch_1):page274_i44@pure_quanta.q_res(chips)';

PART_NAME
 R1474 'Q_RES_0402LF-0,5%,1/16W,CHIP,CS00002JB38':;

SECTION_NUMBER 1
 '@T6G_MB_LIB.T6G(SCH_1):PAGE274_I46@PURE_QUANTA.Q_RES(CHIPS)':
 C_PATH='@t6g_mb_lib.t6g(sch_1):page274_i46@pure_quanta.q_res(chips)';

PART_NAME
 R1473 'Q_RES_0402LF-0,5%,1/16W,CHIP,CS00002JB38':;

SECTION_NUMBER 1
 '@T6G_MB_LIB.T6G(SCH_1):PAGE274_I45@PURE_QUANTA.Q_RES(CHIPS)':
 C_PATH='@t6g_mb_lib.t6g(sch_1):page274_i45@pure_quanta.q_res(chips)';

PART_NAME
 R1472 'Q_RES_0402LF-10K,5%,1/16W,CHIP,TMP_QCS31002JB28':;

SECTION_NUMBER 1
 '@T6G_MB_LIB.T6G(SCH_1):PAGE274_I344@PURE_QUANTA.Q_RES(CHIPS)':
 C_PATH='@t6g_mb_lib.t6g(sch_1):page274_i344@pure_quanta.q_res(chips)';

PART_NAME
 R1471 'Q_RES_0402LF-10K,5%,1/16W,CHIP,TMP_QCS31002JB28':;

SECTION_NUMBER 1
 '@T6G_MB_LIB.T6G(SCH_1):PAGE274_I345@PURE_QUANTA.Q_RES(CHIPS)':
 C_PATH='@t6g_mb_lib.t6g(sch_1):page274_i345@pure_quanta.q_res(chips)';

PART_NAME
 R1470 'Q_RES_0402LF-0,5%,1/16W,CHIP,CS00002JB38':;

SECTION_NUMBER 1
 '@T6G_MB_LIB.T6G(SCH_1):PAGE274_I50@PURE_QUANTA.Q_RES(CHIPS)':
 C_PATH='@t6g_mb_lib.t6g(sch_1):page274_i50@pure_quanta.q_res(chips)';

PART_NAME
 R1469 'Q_RES_0402LF-0,5%,1/16W,CHIP,CS00002JB38':;

SECTION_NUMBER 1
 '@T6G_MB_LIB.T6G(SCH_1):PAGE274_I49@PURE_QUANTA.Q_RES(CHIPS)':
 C_PATH='@t6g_mb_lib.t6g(sch_1):page274_i49@pure_quanta.q_res(chips)';

PART_NAME
 R1468 'Q_RES_0402LF-0,5%,1/16W,CHIP,CS00002JB38':;

SECTION_NUMBER 1
 '@T6G_MB_LIB.T6G(SCH_1):PAGE274_I51@PURE_QUANTA.Q_RES(CHIPS)':
 C_PATH='@t6g_mb_lib.t6g(sch_1):page274_i51@pure_quanta.q_res(chips)';

PART_NAME
 R1462 'Q_RES_0402LF-10K,5%,1/16W,CHIP,TMP_QCS31002JB28':;

SECTION_NUMBER 1
 '@T6G_MB_LIB.T6G(SCH_1):PAGE274_I385@PURE_QUANTA.Q_RES(CHIPS)':
 C_PATH='@t6g_mb_lib.t6g(sch_1):page274_i385@pure_quanta.q_res(chips)';

PART_NAME
 R1461 'Q_RES_0402LF-0,5%,1/16W,CHIP,CS00002JB38':;

SECTION_NUMBER 1
 '@T6G_MB_LIB.T6G(SCH_1):PAGE274_I55@PURE_QUANTA.Q_RES(CHIPS)':
 C_PATH='@t6g_mb_lib.t6g(sch_1):page274_i55@pure_quanta.q_res(chips)';

PART_NAME
 R1460 'Q_RES_0402LF-0,5%,1/16W,CHIP,CS00002JB38':;

SECTION_NUMBER 1
 '@T6G_MB_LIB.T6G(SCH_1):PAGE274_I56@PURE_QUANTA.Q_RES(CHIPS)':
 C_PATH='@t6g_mb_lib.t6g(sch_1):page274_i56@pure_quanta.q_res(chips)';

PART_NAME
 R1459 'Q_RES_0402LF-10K,1%,1/16W,CHIP,TMP_QCS31002FB26':;

SECTION_NUMBER 1
 '@T6G_MB_LIB.T6G(SCH_1):PAGE274_I365@PURE_QUANTA.Q_RES(CHIPS)':
 C_PATH='@t6g_mb_lib.t6g(sch_1):page274_i365@pure_quanta.q_res(chips)';

PART_NAME
 R660 'Q_RES_0402LF-0,5%,1/16W,CHIP,CS00002JB38':;

SECTION_NUMBER 1
 '@T6G_MB_LIB.T6G(SCH_1):PAGE274_I57@PURE_QUANTA.Q_RES(CHIPS)':
 C_PATH='@t6g_mb_lib.t6g(sch_1):page274_i57@pure_quanta.q_res(chips)';

PART_NAME
 R659 'Q_RES_0402LF-0,5%,1/16W,CHIP,CS00002JB38':;

SECTION_NUMBER 1
 '@T6G_MB_LIB.T6G(SCH_1):PAGE274_I58@PURE_QUANTA.Q_RES(CHIPS)':
 C_PATH='@t6g_mb_lib.t6g(sch_1):page274_i58@pure_quanta.q_res(chips)';

PART_NAME
 R647 'Q_RES_0402LF-33,5%,1/16W,CHIP,CS03302JB29':;

SECTION_NUMBER 1
 '@T6G_MB_LIB.T6G(SCH_1):PAGE274_I367@PURE_QUANTA.Q_RES(CHIPS)':
 C_PATH='@t6g_mb_lib.t6g(sch_1):page274_i367@pure_quanta.q_res(chips)';

PART_NAME
 R644 'Q_RES_0402LF-1K,1%,1/16W,CHIP,TMP_QCS21002FB24':;

SECTION_NUMBER 1
 '@T6G_MB_LIB.T6G(SCH_1):PAGE274_I379@PURE_QUANTA.Q_RES(CHIPS)':
 C_PATH='@t6g_mb_lib.t6g(sch_1):page274_i379@pure_quanta.q_res(chips)';

PART_NAME
 R643 'Q_RES_0402LF-10K,1%,1/16W,EMPTY,TMP_QCS31002FB26':;

SECTION_NUMBER 1
 '@T6G_MB_LIB.T6G(SCH_1):PAGE274_I377@PURE_QUANTA.Q_RES(CHIPS)':
 C_PATH='@t6g_mb_lib.t6g(sch_1):page274_i377@pure_quanta.q_res(chips)';

PART_NAME
 R642 'Q_RES_0402LF-1K,1%,1/16W,EMPTY,TMP_QCS21002FB24':;

SECTION_NUMBER 1
 '@T6G_MB_LIB.T6G(SCH_1):PAGE274_I380@PURE_QUANTA.Q_RES(CHIPS)':
 C_PATH='@t6g_mb_lib.t6g(sch_1):page274_i380@pure_quanta.q_res(chips)';

PART_NAME
 R641 'Q_RES_0402LF-10K,1%,1/16W,CHIP,TMP_QCS31002FB26':;

SECTION_NUMBER 1
 '@T6G_MB_LIB.T6G(SCH_1):PAGE274_I378@PURE_QUANTA.Q_RES(CHIPS)':
 C_PATH='@t6g_mb_lib.t6g(sch_1):page274_i378@pure_quanta.q_res(chips)';

PART_NAME
 JP31 'CONN3_210HP1030BR1-CONN3_210-HP1-030BR1,THLF,IO,DFHD03MS213':;

SECTION_NUMBER 1
 '@T6G_MB_LIB.T6G(SCH_1):PAGE274_I372@PURE_QUANTA.CONN3_210HP1030BR1(CHIPS)':
 C_PATH='@t6g_mb_lib.t6g(sch_1):page274_i372@pure_quanta.conn3_210hp1030br1(chip~
s)';

PART_NAME
 C1075 'Q_CAP_0402-0.1UF,25V,10%,X7R,CH4104K1B00':;

SECTION_NUMBER 1
 '@T6G_MB_LIB.T6G(SCH_1):PAGE274_I363@PURE_QUANTA.Q_CAP(CHIPS)':
 C_PATH='@t6g_mb_lib.t6g(sch_1):page274_i363@pure_quanta.q_cap(chips)';

PART_NAME
 U143 'GTL2014PW-GTL2014PW,SMLF,IC,AL002014K01':;

SECTION_NUMBER 1
 '@T6G_MB_LIB.T6G(SCH_1):PAGE237_I116@PURE_QUANTA.GTL2014PW(CHIPS)':
 C_PATH='@t6g_mb_lib.t6g(sch_1):page237_i116@pure_quanta.gtl2014pw(chips)';

PART_NAME
 U142 'GTL2014PW-GTL2014PW,SMLF,IC,AL002014K01':;

SECTION_NUMBER 1
 '@T6G_MB_LIB.T6G(SCH_1):PAGE237_I115@PURE_QUANTA.GTL2014PW(CHIPS)':
 C_PATH='@t6g_mb_lib.t6g(sch_1):page237_i115@pure_quanta.gtl2014pw(chips)';

PART_NAME
 U127 'TS3A24157RSER-TS3A24157RSER,SMLF,IC,AL024157000':;

SECTION_NUMBER 1
 '@T6G_MB_LIB.T6G(SCH_1):PAGE237_I100@PURE_QUANTA.TS3A24157RSER(CHIPS)':
 C_PATH='@t6g_mb_lib.t6g(sch_1):page237_i100@pure_quanta.ts3a24157rser(chips)';

PART_NAME
 U126 'TS3A24157RSER-TS3A24157RSER,SMLF,IC,AL024157000':;

SECTION_NUMBER 1
 '@T6G_MB_LIB.T6G(SCH_1):PAGE237_I35@PURE_QUANTA.TS3A24157RSER(CHIPS)':
 C_PATH='@t6g_mb_lib.t6g(sch_1):page237_i35@pure_quanta.ts3a24157rser(chips)';

PART_NAME
 R1832 'Q_RES_0402LF-0,5%,1/16W,EMPTY,CS00002JB38':;

SECTION_NUMBER 1
 '@T6G_MB_LIB.T6G(SCH_1):PAGE237_I56@PURE_QUANTA.Q_RES(CHIPS)':
 C_PATH='@t6g_mb_lib.t6g(sch_1):page237_i56@pure_quanta.q_res(chips)';

PART_NAME
 R1831 'Q_RES_0402LF-0,5%,1/16W,EMPTY,CS00002JB38':;

SECTION_NUMBER 1
 '@T6G_MB_LIB.T6G(SCH_1):PAGE237_I64@PURE_QUANTA.Q_RES(CHIPS)':
 C_PATH='@t6g_mb_lib.t6g(sch_1):page237_i64@pure_quanta.q_res(chips)';

PART_NAME
 R1814 'Q_RES_0402LF-1K,1%,1/16W,CHIP,TMP_QCS21002FB24':;

SECTION_NUMBER 1
 '@T6G_MB_LIB.T6G(SCH_1):PAGE237_I110@PURE_QUANTA.Q_RES(CHIPS)':
 C_PATH='@t6g_mb_lib.t6g(sch_1):page237_i110@pure_quanta.q_res(chips)';

PART_NAME
 R1813 'Q_RES_0402LF-10K,1%,1/16W,EMPTY,TMP_QCS31002FB26':;

SECTION_NUMBER 1
 '@T6G_MB_LIB.T6G(SCH_1):PAGE237_I109@PURE_QUANTA.Q_RES(CHIPS)':
 C_PATH='@t6g_mb_lib.t6g(sch_1):page237_i109@pure_quanta.q_res(chips)';

PART_NAME
 R1449 'Q_RES_0402LF-1K,1%,1/16W,CHIP,TMP_QCS21002FB24':;

SECTION_NUMBER 1
 '@T6G_MB_LIB.T6G(SCH_1):PAGE237_I52@PURE_QUANTA.Q_RES(CHIPS)':
 C_PATH='@t6g_mb_lib.t6g(sch_1):page237_i52@pure_quanta.q_res(chips)';

PART_NAME
 R1448 'Q_RES_0402LF-1K,1%,1/16W,CHIP,TMP_QCS21002FB24':;

SECTION_NUMBER 1
 '@T6G_MB_LIB.T6G(SCH_1):PAGE237_I65@PURE_QUANTA.Q_RES(CHIPS)':
 C_PATH='@t6g_mb_lib.t6g(sch_1):page237_i65@pure_quanta.q_res(chips)';

PART_NAME
 R1447 'Q_RES_0402LF-0,5%,1/16W,CHIP,CS00002JB38':;

SECTION_NUMBER 1
 '@T6G_MB_LIB.T6G(SCH_1):PAGE237_I55@PURE_QUANTA.Q_RES(CHIPS)':
 C_PATH='@t6g_mb_lib.t6g(sch_1):page237_i55@pure_quanta.q_res(chips)';

PART_NAME
 R1446 'Q_RES_0402LF-0,5%,1/16W,CHIP,CS00002JB38':;

SECTION_NUMBER 1
 '@T6G_MB_LIB.T6G(SCH_1):PAGE237_I54@PURE_QUANTA.Q_RES(CHIPS)':
 C_PATH='@t6g_mb_lib.t6g(sch_1):page237_i54@pure_quanta.q_res(chips)';

PART_NAME
 R1444 'Q_RES_0402LF-0,5%,1/16W,CHIP,CS00002JB38':;

SECTION_NUMBER 1
 '@T6G_MB_LIB.T6G(SCH_1):PAGE237_I67@PURE_QUANTA.Q_RES(CHIPS)':
 C_PATH='@t6g_mb_lib.t6g(sch_1):page237_i67@pure_quanta.q_res(chips)';

PART_NAME
 R1443 'Q_RES_0402LF-0,5%,1/16W,CHIP,CS00002JB38':;

SECTION_NUMBER 1
 '@T6G_MB_LIB.T6G(SCH_1):PAGE237_I84@PURE_QUANTA.Q_RES(CHIPS)':
 C_PATH='@t6g_mb_lib.t6g(sch_1):page237_i84@pure_quanta.q_res(chips)';

PART_NAME
 R1383 'Q_RES_0402LF-1K,1%,1/16W,CHIP,TMP_QCS21002FB24':;

SECTION_NUMBER 1
 '@T6G_MB_LIB.T6G(SCH_1):PAGE237_I43@PURE_QUANTA.Q_RES(CHIPS)':
 C_PATH='@t6g_mb_lib.t6g(sch_1):page237_i43@pure_quanta.q_res(chips)';

PART_NAME
 R1382 'Q_RES_0402LF-1K,1%,1/16W,CHIP,TMP_QCS21002FB24':;

SECTION_NUMBER 1
 '@T6G_MB_LIB.T6G(SCH_1):PAGE237_I59@PURE_QUANTA.Q_RES(CHIPS)':
 C_PATH='@t6g_mb_lib.t6g(sch_1):page237_i59@pure_quanta.q_res(chips)';

PART_NAME
 R1381 'Q_RES_0402LF-1K,1%,1/16W,CHIP,TMP_QCS21002FB24':;

SECTION_NUMBER 1
 '@T6G_MB_LIB.T6G(SCH_1):PAGE237_I45@PURE_QUANTA.Q_RES(CHIPS)':
 C_PATH='@t6g_mb_lib.t6g(sch_1):page237_i45@pure_quanta.q_res(chips)';

PART_NAME
 R1380 'Q_RES_0402LF-1K,1%,1/16W,CHIP,TMP_QCS21002FB24':;

SECTION_NUMBER 1
 '@T6G_MB_LIB.T6G(SCH_1):PAGE237_I62@PURE_QUANTA.Q_RES(CHIPS)':
 C_PATH='@t6g_mb_lib.t6g(sch_1):page237_i62@pure_quanta.q_res(chips)';

PART_NAME
 R1379 'Q_RES_0402LF-33,5%,1/16W,CHIP,CS03302JB29':;

SECTION_NUMBER 1
 '@T6G_MB_LIB.T6G(SCH_1):PAGE237_I57@PURE_QUANTA.Q_RES(CHIPS)':
 C_PATH='@t6g_mb_lib.t6g(sch_1):page237_i57@pure_quanta.q_res(chips)';

PART_NAME
 R1378 'Q_RES_0402LF-33,5%,1/16W,CHIP,CS03302JB29':;

SECTION_NUMBER 1
 '@T6G_MB_LIB.T6G(SCH_1):PAGE237_I68@PURE_QUANTA.Q_RES(CHIPS)':
 C_PATH='@t6g_mb_lib.t6g(sch_1):page237_i68@pure_quanta.q_res(chips)';

PART_NAME
 R1377 'Q_RES_0402LF-1K,1%,1/16W,CHIP,TMP_QCS21002FB24':;

SECTION_NUMBER 1
 '@T6G_MB_LIB.T6G(SCH_1):PAGE237_I53@PURE_QUANTA.Q_RES(CHIPS)':
 C_PATH='@t6g_mb_lib.t6g(sch_1):page237_i53@pure_quanta.q_res(chips)';

PART_NAME
 R1376 'Q_RES_0402LF-1K,1%,1/16W,CHIP,TMP_QCS21002FB24':;

SECTION_NUMBER 1
 '@T6G_MB_LIB.T6G(SCH_1):PAGE237_I66@PURE_QUANTA.Q_RES(CHIPS)':
 C_PATH='@t6g_mb_lib.t6g(sch_1):page237_i66@pure_quanta.q_res(chips)';

PART_NAME
 R1369 'Q_RES_0402LF-1K,1%,1/16W,CHIP,TMP_QCS21002FB24':;

SECTION_NUMBER 1
 '@T6G_MB_LIB.T6G(SCH_1):PAGE237_I89@PURE_QUANTA.Q_RES(CHIPS)':
 C_PATH='@t6g_mb_lib.t6g(sch_1):page237_i89@pure_quanta.q_res(chips)';

PART_NAME
 R1368 'Q_RES_0402LF-1K,1%,1/16W,CHIP,TMP_QCS21002FB24':;

SECTION_NUMBER 1
 '@T6G_MB_LIB.T6G(SCH_1):PAGE237_I90@PURE_QUANTA.Q_RES(CHIPS)':
 C_PATH='@t6g_mb_lib.t6g(sch_1):page237_i90@pure_quanta.q_res(chips)';

PART_NAME
 R1367 'Q_RES_0402LF-100,1%,1/16W,CHIP,CS11002FB07':;

SECTION_NUMBER 1
 '@T6G_MB_LIB.T6G(SCH_1):PAGE237_I92@PURE_QUANTA.Q_RES(CHIPS)':
 C_PATH='@t6g_mb_lib.t6g(sch_1):page237_i92@pure_quanta.q_res(chips)';

PART_NAME
 R1366 'Q_RES_0402LF-100,1%,1/16W,CHIP,CS11002FB07':;

SECTION_NUMBER 1
 '@T6G_MB_LIB.T6G(SCH_1):PAGE237_I91@PURE_QUANTA.Q_RES(CHIPS)':
 C_PATH='@t6g_mb_lib.t6g(sch_1):page237_i91@pure_quanta.q_res(chips)';

PART_NAME
 R481 'Q_RES_0402LF-0,5%,1/16W,CHIP,CS00002JB38':;

SECTION_NUMBER 1
 '@T6G_MB_LIB.T6G(SCH_1):PAGE237_I83@PURE_QUANTA.Q_RES(CHIPS)':
 C_PATH='@t6g_mb_lib.t6g(sch_1):page237_i83@pure_quanta.q_res(chips)';

PART_NAME
 R480 'Q_RES_0402LF-0,5%,1/16W,CHIP,CS00002JB38':;

SECTION_NUMBER 1
 '@T6G_MB_LIB.T6G(SCH_1):PAGE237_I82@PURE_QUANTA.Q_RES(CHIPS)':
 C_PATH='@t6g_mb_lib.t6g(sch_1):page237_i82@pure_quanta.q_res(chips)';

PART_NAME
 C1291 'Q_CAP_C0402-1UF,25V,10%,X6S,CH5104KEB02':;

SECTION_NUMBER 1
 '@T6G_MB_LIB.T6G(SCH_1):PAGE237_I70@PURE_QUANTA.Q_CAP(CHIPS)':
 C_PATH='@t6g_mb_lib.t6g(sch_1):page237_i70@pure_quanta.q_cap(chips)';

PART_NAME
 C1074 'Q_CAP_0402-0.1UF,25V,10%,X7R,CH4104K1B00':;

SECTION_NUMBER 1
 '@T6G_MB_LIB.T6G(SCH_1):PAGE237_I40@PURE_QUANTA.Q_CAP(CHIPS)':
 C_PATH='@t6g_mb_lib.t6g(sch_1):page237_i40@pure_quanta.q_cap(chips)';

PART_NAME
 C1070 'Q_CAP_C0402-1UF,25V,10%,X6S,CH5104KEB02':;

SECTION_NUMBER 1
 '@T6G_MB_LIB.T6G(SCH_1):PAGE237_I76@PURE_QUANTA.Q_CAP(CHIPS)':
 C_PATH='@t6g_mb_lib.t6g(sch_1):page237_i76@pure_quanta.q_cap(chips)';

PART_NAME
 C1063 'Q_CAP_0402-0.1UF,25V,10%,X7R,CH4104K1B00':;

SECTION_NUMBER 1
 '@T6G_MB_LIB.T6G(SCH_1):PAGE237_I81@PURE_QUANTA.Q_CAP(CHIPS)':
 C_PATH='@t6g_mb_lib.t6g(sch_1):page237_i81@pure_quanta.q_cap(chips)';

PART_NAME
 U125 '74CBTLV3126PW-74CBTLV3126PW,SMLF,IC,AL003126K08':;

SECTION_NUMBER 1
 '@T6G_MB_LIB.T6G(SCH_1):PAGE236_I1@PURE_QUANTA.74CBTLV3126PW(CHIPS)':
 C_PATH='@t6g_mb_lib.t6g(sch_1):page236_i1@pure_quanta.\74cbtlv3126pw\(chips)';

PART_NAME
 U123 'MOSFET_N_SMLF-BSS138K,BSS138K,IC,BAM138K0000':;

SECTION_NUMBER 1
 '@T6G_MB_LIB.T6G(SCH_1):PAGE236_I13@PURE_QUANTA.MOSFET_N(CHIPS)':
 C_PATH='@t6g_mb_lib.t6g(sch_1):page236_i13@pure_quanta.mosfet_n(chips)';

PART_NAME
 U122 'NC7SB3157_SMLF-NC7SB3157P6X,NC7SB3157P6X,IC,ALSB3157000':;

SECTION_NUMBER 1
 '@T6G_MB_LIB.T6G(SCH_1):PAGE236_I28@PURE_QUANTA.NC7SB3157(CHIPS)':
 C_PATH='@t6g_mb_lib.t6g(sch_1):page236_i28@pure_quanta.nc7sb3157(chips)';

PART_NAME
 R1442 'Q_RES_0402LF-0,5%,1/16W,CHIP,CS00002JB38':;

SECTION_NUMBER 1
 '@T6G_MB_LIB.T6G(SCH_1):PAGE236_I5@PURE_QUANTA.Q_RES(CHIPS)':
 C_PATH='@t6g_mb_lib.t6g(sch_1):page236_i5@pure_quanta.q_res(chips)';

PART_NAME
 R1441 'Q_RES_0402LF-0,5%,1/16W,CHIP,CS00002JB38':;

SECTION_NUMBER 1
 '@T6G_MB_LIB.T6G(SCH_1):PAGE236_I4@PURE_QUANTA.Q_RES(CHIPS)':
 C_PATH='@t6g_mb_lib.t6g(sch_1):page236_i4@pure_quanta.q_res(chips)';

PART_NAME
 R1375 'Q_RES_0402LF-10K,1%,1/16W,CHIP,TMP_QCS31002FB26':;

SECTION_NUMBER 1
 '@T6G_MB_LIB.T6G(SCH_1):PAGE236_I12@PURE_QUANTA.Q_RES(CHIPS)':
 C_PATH='@t6g_mb_lib.t6g(sch_1):page236_i12@pure_quanta.q_res(chips)';

PART_NAME
 R1374 'Q_RES_0402LF-1K,1%,1/16W,CHIP,TMP_QCS21002FB24':;

SECTION_NUMBER 1
 '@T6G_MB_LIB.T6G(SCH_1):PAGE236_I17@PURE_QUANTA.Q_RES(CHIPS)':
 C_PATH='@t6g_mb_lib.t6g(sch_1):page236_i17@pure_quanta.q_res(chips)';

PART_NAME
 R1373 'Q_RES_0402LF-1K,1%,1/16W,CHIP,TMP_QCS21002FB24':;

SECTION_NUMBER 1
 '@T6G_MB_LIB.T6G(SCH_1):PAGE236_I18@PURE_QUANTA.Q_RES(CHIPS)':
 C_PATH='@t6g_mb_lib.t6g(sch_1):page236_i18@pure_quanta.q_res(chips)';

PART_NAME
 R1372 'Q_RES_0402LF-1K,1%,1/16W,EMPTY,TMP_QCS21002FB24':;

SECTION_NUMBER 1
 '@T6G_MB_LIB.T6G(SCH_1):PAGE236_I38@PURE_QUANTA.Q_RES(CHIPS)':
 C_PATH='@t6g_mb_lib.t6g(sch_1):page236_i38@pure_quanta.q_res(chips)';

PART_NAME
 R1371 'Q_RES_0402LF-1K,1%,1/16W,CHIP,TMP_QCS21002FB24':;

SECTION_NUMBER 1
 '@T6G_MB_LIB.T6G(SCH_1):PAGE236_I23@PURE_QUANTA.Q_RES(CHIPS)':
 C_PATH='@t6g_mb_lib.t6g(sch_1):page236_i23@pure_quanta.q_res(chips)';

PART_NAME
 R1370 'Q_RES_0402LF-100,1%,1/16W,CHIP,TMP_QCS11002FB22':;

SECTION_NUMBER 1
 '@T6G_MB_LIB.T6G(SCH_1):PAGE236_I36@PURE_QUANTA.Q_RES(CHIPS)':
 C_PATH='@t6g_mb_lib.t6g(sch_1):page236_i36@pure_quanta.q_res(chips)';

PART_NAME
 R1365 'Q_RES_0402LF-1K,1%,1/16W,CHIP,TMP_QCS21002FB24':;

SECTION_NUMBER 1
 '@T6G_MB_LIB.T6G(SCH_1):PAGE236_I30@PURE_QUANTA.Q_RES(CHIPS)':
 C_PATH='@t6g_mb_lib.t6g(sch_1):page236_i30@pure_quanta.q_res(chips)';

PART_NAME
 C1293 'Q_CAP_C0402-1UF,25V,10%,X6S,CH5104KEB02':;

SECTION_NUMBER 1
 '@T6G_MB_LIB.T6G(SCH_1):PAGE236_I11@PURE_QUANTA.Q_CAP(CHIPS)':
 C_PATH='@t6g_mb_lib.t6g(sch_1):page236_i11@pure_quanta.q_cap(chips)';

PART_NAME
 C1292 'Q_CAP_0402-0.1UF,25V,10%,X7R,CH4104K1B00':;

SECTION_NUMBER 1
 '@T6G_MB_LIB.T6G(SCH_1):PAGE236_I7@PURE_QUANTA.Q_CAP(CHIPS)':
 C_PATH='@t6g_mb_lib.t6g(sch_1):page236_i7@pure_quanta.q_cap(chips)';

PART_NAME
 C1062 'Q_CAP_C0402-1UF,25V,10%,X6S,CH5104KEB02':;

SECTION_NUMBER 1
 '@T6G_MB_LIB.T6G(SCH_1):PAGE236_I25@PURE_QUANTA.Q_CAP(CHIPS)':
 C_PATH='@t6g_mb_lib.t6g(sch_1):page236_i25@pure_quanta.q_cap(chips)';

PART_NAME
 C1061 'Q_CAP_0402-0.1UF,25V,10%,X7R,CH4104K1B00':;

SECTION_NUMBER 1
 '@T6G_MB_LIB.T6G(SCH_1):PAGE236_I27@PURE_QUANTA.Q_CAP(CHIPS)':
 C_PATH='@t6g_mb_lib.t6g(sch_1):page236_i27@pure_quanta.q_cap(chips)';

PART_NAME
 U133 'IDTQS3VH257QG_SMLF-IDTQS3VH257QG,IC,AL000257W24':;

SECTION_NUMBER 1
 '@T6G_MB_LIB.T6G(SCH_1):PAGE224_I86@PURE_QUANTA.IDTQS3VH257QG(CHIPS)':
 C_PATH='@t6g_mb_lib.t6g(sch_1):page224_i86@pure_quanta.idtqs3vh257qg(chips)';

PART_NAME
 R1440 'Q_RES_0402LF-0,5%,1/16W,CHIP,CS00002JB38':;

SECTION_NUMBER 1
 '@T6G_MB_LIB.T6G(SCH_1):PAGE224_I66@PURE_QUANTA.Q_RES(CHIPS)':
 C_PATH='@t6g_mb_lib.t6g(sch_1):page224_i66@pure_quanta.q_res(chips)';

PART_NAME
 R1439 'Q_RES_0402LF-0,5%,1/16W,EMPTY,CS00002JB38':;

SECTION_NUMBER 1
 '@T6G_MB_LIB.T6G(SCH_1):PAGE224_I74@PURE_QUANTA.Q_RES(CHIPS)':
 C_PATH='@t6g_mb_lib.t6g(sch_1):page224_i74@pure_quanta.q_res(chips)';

PART_NAME
 R1438 'Q_RES_0402LF-0,5%,1/16W,EMPTY,CS00002JB38':;

SECTION_NUMBER 1
 '@T6G_MB_LIB.T6G(SCH_1):PAGE224_I73@PURE_QUANTA.Q_RES(CHIPS)':
 C_PATH='@t6g_mb_lib.t6g(sch_1):page224_i73@pure_quanta.q_res(chips)';

PART_NAME
 R1437 'Q_RES_0402LF-0,5%,1/16W,EMPTY,CS00002JB38':;

SECTION_NUMBER 1
 '@T6G_MB_LIB.T6G(SCH_1):PAGE224_I71@PURE_QUANTA.Q_RES(CHIPS)':
 C_PATH='@t6g_mb_lib.t6g(sch_1):page224_i71@pure_quanta.q_res(chips)';

PART_NAME
 R676 'Q_RES_0402LF-0,5%,1/16W,CHIP,CS00002JB38':;

SECTION_NUMBER 1
 '@T6G_MB_LIB.T6G(SCH_1):PAGE224_I65@PURE_QUANTA.Q_RES(CHIPS)':
 C_PATH='@t6g_mb_lib.t6g(sch_1):page224_i65@pure_quanta.q_res(chips)';

PART_NAME
 R675 'Q_RES_0402LF-0,5%,1/16W,CHIP,CS00002JB38':;

SECTION_NUMBER 1
 '@T6G_MB_LIB.T6G(SCH_1):PAGE224_I64@PURE_QUANTA.Q_RES(CHIPS)':
 C_PATH='@t6g_mb_lib.t6g(sch_1):page224_i64@pure_quanta.q_res(chips)';

PART_NAME
 R674 'Q_RES_0402LF-0,5%,1/16W,CHIP,CS00002JB38':;

SECTION_NUMBER 1
 '@T6G_MB_LIB.T6G(SCH_1):PAGE224_I63@PURE_QUANTA.Q_RES(CHIPS)':
 C_PATH='@t6g_mb_lib.t6g(sch_1):page224_i63@pure_quanta.q_res(chips)';

PART_NAME
 R673 'Q_RES_0402LF-0,5%,1/16W,CHIP,CS00002JB38':;

SECTION_NUMBER 1
 '@T6G_MB_LIB.T6G(SCH_1):PAGE224_I94@PURE_QUANTA.Q_RES(CHIPS)':
 C_PATH='@t6g_mb_lib.t6g(sch_1):page224_i94@pure_quanta.q_res(chips)';

PART_NAME
 R672 'Q_RES_0402LF-0,5%,1/16W,CHIP,CS00002JB38':;

SECTION_NUMBER 1
 '@T6G_MB_LIB.T6G(SCH_1):PAGE224_I93@PURE_QUANTA.Q_RES(CHIPS)':
 C_PATH='@t6g_mb_lib.t6g(sch_1):page224_i93@pure_quanta.q_res(chips)';

PART_NAME
 R671 'Q_RES_0402LF-0,5%,1/16W,CHIP,CS00002JB38':;

SECTION_NUMBER 1
 '@T6G_MB_LIB.T6G(SCH_1):PAGE224_I92@PURE_QUANTA.Q_RES(CHIPS)':
 C_PATH='@t6g_mb_lib.t6g(sch_1):page224_i92@pure_quanta.q_res(chips)';

PART_NAME
 R670 'Q_RES_0402LF-0,5%,1/16W,CHIP,CS00002JB38':;

SECTION_NUMBER 1
 '@T6G_MB_LIB.T6G(SCH_1):PAGE224_I91@PURE_QUANTA.Q_RES(CHIPS)':
 C_PATH='@t6g_mb_lib.t6g(sch_1):page224_i91@pure_quanta.q_res(chips)';

PART_NAME
 R669 'Q_RES_0402LF-240,1%,1/16W,CHIP,CS12402FB03':;

SECTION_NUMBER 1
 '@T6G_MB_LIB.T6G(SCH_1):PAGE224_I95@PURE_QUANTA.Q_RES(CHIPS)':
 C_PATH='@t6g_mb_lib.t6g(sch_1):page224_i95@pure_quanta.q_res(chips)';

PART_NAME
 R666 'Q_RES_0402LF-0,5%,1/16W,EMPTY,CS00002JB38':;

SECTION_NUMBER 1
 '@T6G_MB_LIB.T6G(SCH_1):PAGE224_I72@PURE_QUANTA.Q_RES(CHIPS)':
 C_PATH='@t6g_mb_lib.t6g(sch_1):page224_i72@pure_quanta.q_res(chips)';

PART_NAME
 R664 'Q_RES_0402LF-240,1%,1/16W,CHIP,CS12402FB03':;

SECTION_NUMBER 1
 '@T6G_MB_LIB.T6G(SCH_1):PAGE224_I96@PURE_QUANTA.Q_RES(CHIPS)':
 C_PATH='@t6g_mb_lib.t6g(sch_1):page224_i96@pure_quanta.q_res(chips)';

PART_NAME
 R663 'Q_RES_0402LF-240,1%,1/16W,CHIP,CS12402FB03':;

SECTION_NUMBER 1
 '@T6G_MB_LIB.T6G(SCH_1):PAGE224_I98@PURE_QUANTA.Q_RES(CHIPS)':
 C_PATH='@t6g_mb_lib.t6g(sch_1):page224_i98@pure_quanta.q_res(chips)';

PART_NAME
 R662 'Q_RES_0402LF-240,1%,1/16W,CHIP,CS12402FB03':;

SECTION_NUMBER 1
 '@T6G_MB_LIB.T6G(SCH_1):PAGE224_I99@PURE_QUANTA.Q_RES(CHIPS)':
 C_PATH='@t6g_mb_lib.t6g(sch_1):page224_i99@pure_quanta.q_res(chips)';

PART_NAME
 R661 'Q_RES_0402LF-1K,1%,1/16W,CHIP,TMP_QCS21002FB24':;

SECTION_NUMBER 1
 '@T6G_MB_LIB.T6G(SCH_1):PAGE224_I82@PURE_QUANTA.Q_RES(CHIPS)':
 C_PATH='@t6g_mb_lib.t6g(sch_1):page224_i82@pure_quanta.q_res(chips)';

PART_NAME
 C1060 'Q_CAP_0402-0.1UF,25V,10%,X7R,CH4104K1B00':;

SECTION_NUMBER 1
 '@T6G_MB_LIB.T6G(SCH_1):PAGE224_I69@PURE_QUANTA.Q_CAP(CHIPS)':
 C_PATH='@t6g_mb_lib.t6g(sch_1):page224_i69@pure_quanta.q_cap(chips)';

PART_NAME
 U132 'IDTQS3VH257QG_SMLF-IDTQS3VH257QG,IC,AL000257W24':;

SECTION_NUMBER 1
 '@T6G_MB_LIB.T6G(SCH_1):PAGE222_I106@PURE_QUANTA.IDTQS3VH257QG(CHIPS)':
 C_PATH='@t6g_mb_lib.t6g(sch_1):page222_i106@pure_quanta.idtqs3vh257qg(chips)';

PART_NAME
 R1821 'Q_RES_0402LF-0,5%,1/16W,EMPTY,CS00002JB38':;

SECTION_NUMBER 1
 '@T6G_MB_LIB.T6G(SCH_1):PAGE222_I103@PURE_QUANTA.Q_RES(CHIPS)':
 C_PATH='@t6g_mb_lib.t6g(sch_1):page222_i103@pure_quanta.q_res(chips)';

PART_NAME
 R1436 'Q_RES_0402LF-0,5%,1/16W,CHIP,CS00002JB38':;

SECTION_NUMBER 1
 '@T6G_MB_LIB.T6G(SCH_1):PAGE222_I83@PURE_QUANTA.Q_RES(CHIPS)':
 C_PATH='@t6g_mb_lib.t6g(sch_1):page222_i83@pure_quanta.q_res(chips)';

PART_NAME
 R1435 'Q_RES_0402LF-1K,1%,1/16W,CHIP,TMP_QCS21002FB24':;

SECTION_NUMBER 1
 '@T6G_MB_LIB.T6G(SCH_1):PAGE222_I93@PURE_QUANTA.Q_RES(CHIPS)':
 C_PATH='@t6g_mb_lib.t6g(sch_1):page222_i93@pure_quanta.q_res(chips)';

PART_NAME
 R693 'Q_RES_0402LF-0,5%,1/16W,CHIP,CS00002JB38':;

SECTION_NUMBER 1
 '@T6G_MB_LIB.T6G(SCH_1):PAGE222_I82@PURE_QUANTA.Q_RES(CHIPS)':
 C_PATH='@t6g_mb_lib.t6g(sch_1):page222_i82@pure_quanta.q_res(chips)';

PART_NAME
 R692 'Q_RES_0402LF-0,5%,1/16W,CHIP,CS00002JB38':;

SECTION_NUMBER 1
 '@T6G_MB_LIB.T6G(SCH_1):PAGE222_I80@PURE_QUANTA.Q_RES(CHIPS)':
 C_PATH='@t6g_mb_lib.t6g(sch_1):page222_i80@pure_quanta.q_res(chips)';

PART_NAME
 R691 'Q_RES_0402LF-0,5%,1/16W,CHIP,CS00002JB38':;

SECTION_NUMBER 1
 '@T6G_MB_LIB.T6G(SCH_1):PAGE222_I81@PURE_QUANTA.Q_RES(CHIPS)':
 C_PATH='@t6g_mb_lib.t6g(sch_1):page222_i81@pure_quanta.q_res(chips)';

PART_NAME
 R690 'Q_RES_0402LF-33,5%,1/16W,CHIP,CS03302JB29':;

SECTION_NUMBER 1
 '@T6G_MB_LIB.T6G(SCH_1):PAGE222_I120@PURE_QUANTA.Q_RES(CHIPS)':
 C_PATH='@t6g_mb_lib.t6g(sch_1):page222_i120@pure_quanta.q_res(chips)';

PART_NAME
 R689 'Q_RES_0402LF-0,5%,1/16W,CHIP,CS00002JB38':;

SECTION_NUMBER 1
 '@T6G_MB_LIB.T6G(SCH_1):PAGE222_I121@PURE_QUANTA.Q_RES(CHIPS)':
 C_PATH='@t6g_mb_lib.t6g(sch_1):page222_i121@pure_quanta.q_res(chips)';

PART_NAME
 R688 'Q_RES_0402LF-33,5%,1/16W,CHIP,CS03302JB29':;

SECTION_NUMBER 1
 '@T6G_MB_LIB.T6G(SCH_1):PAGE222_I112@PURE_QUANTA.Q_RES(CHIPS)':
 C_PATH='@t6g_mb_lib.t6g(sch_1):page222_i112@pure_quanta.q_res(chips)';

PART_NAME
 R687 'Q_RES_0402LF-0,5%,1/16W,CHIP,CS00002JB38':;

SECTION_NUMBER 1
 '@T6G_MB_LIB.T6G(SCH_1):PAGE222_I111@PURE_QUANTA.Q_RES(CHIPS)':
 C_PATH='@t6g_mb_lib.t6g(sch_1):page222_i111@pure_quanta.q_res(chips)';

PART_NAME
 R686 'Q_RES_0402LF-240,1%,1/16W,CHIP,CS12402FB03':;

SECTION_NUMBER 1
 '@T6G_MB_LIB.T6G(SCH_1):PAGE222_I113@PURE_QUANTA.Q_RES(CHIPS)':
 C_PATH='@t6g_mb_lib.t6g(sch_1):page222_i113@pure_quanta.q_res(chips)';

PART_NAME
 R685 'Q_RES_0402LF-0,5%,1/16W,EMPTY,CS00002JB38':;

SECTION_NUMBER 1
 '@T6G_MB_LIB.T6G(SCH_1):PAGE222_I92@PURE_QUANTA.Q_RES(CHIPS)':
 C_PATH='@t6g_mb_lib.t6g(sch_1):page222_i92@pure_quanta.q_res(chips)';

PART_NAME
 R684 'Q_RES_0402LF-0,5%,1/16W,EMPTY,CS00002JB38':;

SECTION_NUMBER 1
 '@T6G_MB_LIB.T6G(SCH_1):PAGE222_I91@PURE_QUANTA.Q_RES(CHIPS)':
 C_PATH='@t6g_mb_lib.t6g(sch_1):page222_i91@pure_quanta.q_res(chips)';

PART_NAME
 R683 'Q_RES_0402LF-0,5%,1/16W,EMPTY,CS00002JB38':;

SECTION_NUMBER 1
 '@T6G_MB_LIB.T6G(SCH_1):PAGE222_I90@PURE_QUANTA.Q_RES(CHIPS)':
 C_PATH='@t6g_mb_lib.t6g(sch_1):page222_i90@pure_quanta.q_res(chips)';

PART_NAME
 R682 'Q_RES_0402LF-0,5%,1/16W,EMPTY,CS00002JB38':;

SECTION_NUMBER 1
 '@T6G_MB_LIB.T6G(SCH_1):PAGE222_I89@PURE_QUANTA.Q_RES(CHIPS)':
 C_PATH='@t6g_mb_lib.t6g(sch_1):page222_i89@pure_quanta.q_res(chips)';

PART_NAME
 R681 'Q_RES_0402LF-240,1%,1/16W,CHIP,CS12402FB03':;

SECTION_NUMBER 1
 '@T6G_MB_LIB.T6G(SCH_1):PAGE222_I114@PURE_QUANTA.Q_RES(CHIPS)':
 C_PATH='@t6g_mb_lib.t6g(sch_1):page222_i114@pure_quanta.q_res(chips)';

PART_NAME
 R680 'Q_RES_0402LF-240,1%,1/16W,CHIP,CS12402FB03':;

SECTION_NUMBER 1
 '@T6G_MB_LIB.T6G(SCH_1):PAGE222_I116@PURE_QUANTA.Q_RES(CHIPS)':
 C_PATH='@t6g_mb_lib.t6g(sch_1):page222_i116@pure_quanta.q_res(chips)';

PART_NAME
 R679 'Q_RES_0402LF-240,1%,1/16W,CHIP,CS12402FB03':;

SECTION_NUMBER 1
 '@T6G_MB_LIB.T6G(SCH_1):PAGE222_I117@PURE_QUANTA.Q_RES(CHIPS)':
 C_PATH='@t6g_mb_lib.t6g(sch_1):page222_i117@pure_quanta.q_res(chips)';

PART_NAME
 R318 'Q_RES_0402LF-10K,1%,1/16W,CHIP,TMP_QCS31002FB26':;

SECTION_NUMBER 1
 '@T6G_MB_LIB.T6G(SCH_1):PAGE222_I78@PURE_QUANTA.Q_RES(CHIPS)':
 C_PATH='@t6g_mb_lib.t6g(sch_1):page222_i78@pure_quanta.q_res(chips)';

PART_NAME
 R87 'Q_RES_0402LF-1K,5%,1/16W,EMPTY,TMP_QCS21002JB34':;

SECTION_NUMBER 1
 '@T6G_MB_LIB.T6G(SCH_1):PAGE222_I77@PURE_QUANTA.Q_RES(CHIPS)':
 C_PATH='@t6g_mb_lib.t6g(sch_1):page222_i77@pure_quanta.q_res(chips)';

PART_NAME
 C1059 'Q_CAP_0402-0.1UF,25V,10%,X7R,CH4104K1B00':;

SECTION_NUMBER 1
 '@T6G_MB_LIB.T6G(SCH_1):PAGE222_I85@PURE_QUANTA.Q_CAP(CHIPS)':
 C_PATH='@t6g_mb_lib.t6g(sch_1):page222_i85@pure_quanta.q_cap(chips)';

PART_NAME
 Y2 'Q_XTAL_4P_13_SMLF-25MHZ,IC,BG625000142':;

SECTION_NUMBER 1
 '@T6G_MB_LIB.T6G(SCH_1):PAGE205_I402@PURE_QUANTA.Q_XTAL_4P_13(CHIPS)':
 C_PATH='@t6g_mb_lib.t6g(sch_1):page205_i402@pure_quanta.q_xtal_4p_13(chips)';

PART_NAME
 U23 '9SQ440NQQI8-9SQ440NQQI8,SMLF,IC,AJ004400000':;

SECTION_NUMBER 1
 '@T6G_MB_LIB.T6G(SCH_1):PAGE205_I467@PURE_QUANTA.9SQ440NQQI8(CHIPS)':
 C_PATH='@t6g_mb_lib.t6g(sch_1):page205_i467@pure_quanta.\9sq440nqqi8\(chips)';

SECTION_NUMBER 2
 '@T6G_MB_LIB.T6G(SCH_1):PAGE205_I443@PURE_QUANTA.9SQ440NQQI8(CHIPS)':
 C_PATH='@t6g_mb_lib.t6g(sch_1):page205_i443@pure_quanta.\9sq440nqqi8\(chips)';

PART_NAME
 R3795 'Q_RES_0402LF-0,5%,1/16W,CHIP,CS00002JB38':;

SECTION_NUMBER 1
 '@T6G_MB_LIB.T6G(SCH_1):PAGE205_I471@PURE_QUANTA.Q_RES(CHIPS)':
 C_PATH='@t6g_mb_lib.t6g(sch_1):page205_i471@pure_quanta.q_res(chips)';

PART_NAME
 R3794 'Q_RES_0402LF-0,5%,1/16W,CHIP,CS00002JB38':;

SECTION_NUMBER 1
 '@T6G_MB_LIB.T6G(SCH_1):PAGE205_I470@PURE_QUANTA.Q_RES(CHIPS)':
 C_PATH='@t6g_mb_lib.t6g(sch_1):page205_i470@pure_quanta.q_res(chips)';

PART_NAME
 R3165 'Q_RES_0402LF-49.9,1%,1/16W,CHIP,CS04992FB07':
;

SECTION_NUMBER 1
 '@T6G_MB_LIB.T6G(SCH_1):PAGE205_I411@PURE_QUANTA.Q_RES(CHIPS)':
 C_PATH='@t6g_mb_lib.t6g(sch_1):page205_i411@pure_quanta.q_res(chips)';

PART_NAME
 R3164 'Q_RES_0402LF-0,5%,1/16W,CHIP,CS00002JB13':
;

SECTION_NUMBER 1
 '@T6G_MB_LIB.T6G(SCH_1):PAGE205_I403@PURE_QUANTA.Q_RES(CHIPS)':
 C_PATH='@t6g_mb_lib.t6g(sch_1):page205_i403@pure_quanta.q_res(chips)';

PART_NAME
 R1502 'Q_RES_0402LF-4.7K,5%,1/16W,CHIP,TMP_QCS24702JB38':;

SECTION_NUMBER 1
 '@T6G_MB_LIB.T6G(SCH_1):PAGE205_I396@PURE_QUANTA.Q_RES(CHIPS)':
 C_PATH='@t6g_mb_lib.t6g(sch_1):page205_i396@pure_quanta.q_res(chips)';

PART_NAME
 R1500 'Q_RES_0402LF-4.7K,5%,1/16W,CHIP,TMP_QCS24702JB38':;

SECTION_NUMBER 1
 '@T6G_MB_LIB.T6G(SCH_1):PAGE205_I395@PURE_QUANTA.Q_RES(CHIPS)':
 C_PATH='@t6g_mb_lib.t6g(sch_1):page205_i395@pure_quanta.q_res(chips)';

PART_NAME
 R1484 'Q_RES_0402LF-1K,1%,1/16W,EMPTY,TMP_QCS21002FB24':;

SECTION_NUMBER 1
 '@T6G_MB_LIB.T6G(SCH_1):PAGE205_I425@PURE_QUANTA.Q_RES(CHIPS)':
 C_PATH='@t6g_mb_lib.t6g(sch_1):page205_i425@pure_quanta.q_res(chips)';

PART_NAME
 R1483 'Q_RES_0402LF-10K,1%,1/16W,EMPTY,TMP_QCS31002FB26':;

SECTION_NUMBER 1
 '@T6G_MB_LIB.T6G(SCH_1):PAGE205_I426@PURE_QUANTA.Q_RES(CHIPS)':
 C_PATH='@t6g_mb_lib.t6g(sch_1):page205_i426@pure_quanta.q_res(chips)';

PART_NAME
 R1390 'Q_RES_0402LF-1K,1%,1/16W,EMPTY,TMP_QCS21002FB24':;

SECTION_NUMBER 1
 '@T6G_MB_LIB.T6G(SCH_1):PAGE205_I393@PURE_QUANTA.Q_RES(CHIPS)':
 C_PATH='@t6g_mb_lib.t6g(sch_1):page205_i393@pure_quanta.q_res(chips)';

PART_NAME
 R1267 'Q_RES_0402LF-1K,1%,1/16W,CHIP,TMP_QCS21002FB24':;

SECTION_NUMBER 1
 '@T6G_MB_LIB.T6G(SCH_1):PAGE205_I388@PURE_QUANTA.Q_RES(CHIPS)':
 C_PATH='@t6g_mb_lib.t6g(sch_1):page205_i388@pure_quanta.q_res(chips)';

PART_NAME
 R1204 'Q_RES_0402LF-10K,1%,1/16W,EMPTY,TMP_QCS31002FB26':;

SECTION_NUMBER 1
 '@T6G_MB_LIB.T6G(SCH_1):PAGE205_I392@PURE_QUANTA.Q_RES(CHIPS)':
 C_PATH='@t6g_mb_lib.t6g(sch_1):page205_i392@pure_quanta.q_res(chips)';

PART_NAME
 R1196 'Q_RES_0402LF-4.7K,5%,1/16W,CHIP,TMP_QCS24702JB38':;

SECTION_NUMBER 1
 '@T6G_MB_LIB.T6G(SCH_1):PAGE205_I387@PURE_QUANTA.Q_RES(CHIPS)':
 C_PATH='@t6g_mb_lib.t6g(sch_1):page205_i387@pure_quanta.q_res(chips)';

PART_NAME
 R1194 'Q_RES_0402LF-4.7K,5%,1/16W,EMPTY,TMP_QCS24702JB38':;

SECTION_NUMBER 1
 '@T6G_MB_LIB.T6G(SCH_1):PAGE205_I391@PURE_QUANTA.Q_RES(CHIPS)':
 C_PATH='@t6g_mb_lib.t6g(sch_1):page205_i391@pure_quanta.q_res(chips)';

PART_NAME
 R953 'Q_RES_0402LF-4.7K,5%,1/16W,CHIP,TMP_QCS24702JB38':;

SECTION_NUMBER 1
 '@T6G_MB_LIB.T6G(SCH_1):PAGE205_I386@PURE_QUANTA.Q_RES(CHIPS)':
 C_PATH='@t6g_mb_lib.t6g(sch_1):page205_i386@pure_quanta.q_res(chips)';

PART_NAME
 R912 'Q_RES_0402LF-4.7K,5%,1/16W,EMPTY,TMP_QCS24702JB38':;

SECTION_NUMBER 1
 '@T6G_MB_LIB.T6G(SCH_1):PAGE205_I390@PURE_QUANTA.Q_RES(CHIPS)':
 C_PATH='@t6g_mb_lib.t6g(sch_1):page205_i390@pure_quanta.q_res(chips)';

PART_NAME
 R562 'Q_RES_0402LF-4.7K,5%,1/16W,EMPTY,TMP_QCS24702JB38':;

SECTION_NUMBER 1
 '@T6G_MB_LIB.T6G(SCH_1):PAGE205_I389@PURE_QUANTA.Q_RES(CHIPS)':
 C_PATH='@t6g_mb_lib.t6g(sch_1):page205_i389@pure_quanta.q_res(chips)';

PART_NAME
 R456 'Q_RES_0402LF-0,5%,1/16W,CHIP,CS00002JB13':;

SECTION_NUMBER 1
 '@T6G_MB_LIB.T6G(SCH_1):PAGE205_I445@PURE_QUANTA.Q_RES(CHIPS)':
 C_PATH='@t6g_mb_lib.t6g(sch_1):page205_i445@pure_quanta.q_res(chips)';

PART_NAME
 R454 'Q_RES_0402LF-0,5%,1/16W,CHIP,CS00002JB13':
;

SECTION_NUMBER 1
 '@T6G_MB_LIB.T6G(SCH_1):PAGE205_I407@PURE_QUANTA.Q_RES(CHIPS)':
 C_PATH='@t6g_mb_lib.t6g(sch_1):page205_i407@pure_quanta.q_res(chips)';

PART_NAME
 R448 'Q_RES_0402LF-0,5%,1/16W,CHIP,CS00002JB13':;

SECTION_NUMBER 1
 '@T6G_MB_LIB.T6G(SCH_1):PAGE205_I446@PURE_QUANTA.Q_RES(CHIPS)':
 C_PATH='@t6g_mb_lib.t6g(sch_1):page205_i446@pure_quanta.q_res(chips)';

PART_NAME
 R388 'Q_RES_0402LF-1K,1%,1/16W,CHIP,TMP_QCS21002FB24':;

SECTION_NUMBER 1
 '@T6G_MB_LIB.T6G(SCH_1):PAGE205_I424@PURE_QUANTA.Q_RES(CHIPS)':
 C_PATH='@t6g_mb_lib.t6g(sch_1):page205_i424@pure_quanta.q_res(chips)';

PART_NAME
 R387 'Q_RES_0402LF-4.7K,5%,1/16W,CHIP,TMP_QCS24702JB38':;

SECTION_NUMBER 1
 '@T6G_MB_LIB.T6G(SCH_1):PAGE205_I398@PURE_QUANTA.Q_RES(CHIPS)':
 C_PATH='@t6g_mb_lib.t6g(sch_1):page205_i398@pure_quanta.q_res(chips)';

PART_NAME
 R386 'Q_RES_0402LF-1K,1%,1/16W,CHIP,TMP_QCS21002FB24':;

SECTION_NUMBER 1
 '@T6G_MB_LIB.T6G(SCH_1):PAGE205_I394@PURE_QUANTA.Q_RES(CHIPS)':
 C_PATH='@t6g_mb_lib.t6g(sch_1):page205_i394@pure_quanta.q_res(chips)';

PART_NAME
 R385 'Q_RES_0402LF-10K,1%,1/16W,EMPTY,TMP_QCS31002FB26':;

SECTION_NUMBER 1
 '@T6G_MB_LIB.T6G(SCH_1):PAGE205_I397@PURE_QUANTA.Q_RES(CHIPS)':
 C_PATH='@t6g_mb_lib.t6g(sch_1):page205_i397@pure_quanta.q_res(chips)';

PART_NAME
 R384 'Q_RES_0402LF-4.7K,5%,1/16W,CHIP,TMP_QCS24702JB38':;

SECTION_NUMBER 1
 '@T6G_MB_LIB.T6G(SCH_1):PAGE205_I385@PURE_QUANTA.Q_RES(CHIPS)':
 C_PATH='@t6g_mb_lib.t6g(sch_1):page205_i385@pure_quanta.q_res(chips)';

PART_NAME
 C2249 'Q_CAP_0402-0.1UF,25V,10%,EMPTY,CH4104K1B00':
;

SECTION_NUMBER 1
 '@T6G_MB_LIB.T6G(SCH_1):PAGE205_I409@PURE_QUANTA.Q_CAP(CHIPS)':
 C_PATH='@t6g_mb_lib.t6g(sch_1):page205_i409@pure_quanta.q_cap(chips)';

PART_NAME
 C1058 'Q_CAP_0402-15PF,50V,5%,C0G,CH01506JB06':;

SECTION_NUMBER 1
 '@T6G_MB_LIB.T6G(SCH_1):PAGE205_I406@PURE_QUANTA.Q_CAP(CHIPS)':
 C_PATH='@t6g_mb_lib.t6g(sch_1):page205_i406@pure_quanta.q_cap(chips)';

PART_NAME
 C1057 'Q_CAP_0402-15PF,50V,5%,C0G,CH01506JB06':;

SECTION_NUMBER 1
 '@T6G_MB_LIB.T6G(SCH_1):PAGE205_I401@PURE_QUANTA.Q_CAP(CHIPS)':
 C_PATH='@t6g_mb_lib.t6g(sch_1):page205_i401@pure_quanta.q_cap(chips)';

PART_NAME
 U119 'PCA9617ADP-PCA9617ADP,SMLF,IC,AL009617K02':;

SECTION_NUMBER 1
 '@T6G_MB_LIB.T6G(SCH_1):PAGE234_I97@PURE_QUANTA.PCA9617ADP(CHIPS)':
 C_PATH='@t6g_mb_lib.t6g(sch_1):page234_i97@pure_quanta.pca9617adp(chips)';

PART_NAME
 U117 'PCA9617ADP-PCA9617ADP,SMLF,IC,AL009617K02':;

SECTION_NUMBER 1
 '@T6G_MB_LIB.T6G(SCH_1):PAGE234_I96@PURE_QUANTA.PCA9617ADP(CHIPS)':
 C_PATH='@t6g_mb_lib.t6g(sch_1):page234_i96@pure_quanta.pca9617adp(chips)';

PART_NAME
 R2650 'Q_RES_0402LF-499,1%,1/16W,CHIP,CS14992FB24':;

SECTION_NUMBER 1
 '@T6G_MB_LIB.T6G(SCH_1):PAGE234_I100@PURE_QUANTA.Q_RES(CHIPS)':
 C_PATH='@t6g_mb_lib.t6g(sch_1):page234_i100@pure_quanta.q_res(chips)';

PART_NAME
 R2649 'Q_RES_0402LF-499,1%,1/16W,CHIP,CS14992FB24':;

SECTION_NUMBER 1
 '@T6G_MB_LIB.T6G(SCH_1):PAGE234_I98@PURE_QUANTA.Q_RES(CHIPS)':
 C_PATH='@t6g_mb_lib.t6g(sch_1):page234_i98@pure_quanta.q_res(chips)';

PART_NAME
 R2648 'Q_RES_0402LF-499,1%,1/16W,CHIP,CS14992FB24':;

SECTION_NUMBER 1
 '@T6G_MB_LIB.T6G(SCH_1):PAGE234_I101@PURE_QUANTA.Q_RES(CHIPS)':
 C_PATH='@t6g_mb_lib.t6g(sch_1):page234_i101@pure_quanta.q_res(chips)';

PART_NAME
 R2646 'Q_RES_0402LF-499,1%,1/16W,CHIP,CS14992FB24':;

SECTION_NUMBER 1
 '@T6G_MB_LIB.T6G(SCH_1):PAGE234_I99@PURE_QUANTA.Q_RES(CHIPS)':
 C_PATH='@t6g_mb_lib.t6g(sch_1):page234_i99@pure_quanta.q_res(chips)';

PART_NAME
 R1830 'Q_RES_0402LF-0,5%,1/16W,EMPTY,CS00002JB38':;

SECTION_NUMBER 1
 '@T6G_MB_LIB.T6G(SCH_1):PAGE234_I61@PURE_QUANTA.Q_RES(CHIPS)':
 C_PATH='@t6g_mb_lib.t6g(sch_1):page234_i61@pure_quanta.q_res(chips)';

PART_NAME
 R1829 'Q_RES_0402LF-0,5%,1/16W,EMPTY,CS00002JB38':;

SECTION_NUMBER 1
 '@T6G_MB_LIB.T6G(SCH_1):PAGE234_I62@PURE_QUANTA.Q_RES(CHIPS)':
 C_PATH='@t6g_mb_lib.t6g(sch_1):page234_i62@pure_quanta.q_res(chips)';

PART_NAME
 R1760 'Q_RES_0402LF-0,5%,1/16W,EMPTY,CS00002JB38':;

SECTION_NUMBER 1
 '@T6G_MB_LIB.T6G(SCH_1):PAGE234_I53@PURE_QUANTA.Q_RES(CHIPS)':
 C_PATH='@t6g_mb_lib.t6g(sch_1):page234_i53@pure_quanta.q_res(chips)';

PART_NAME
 R1759 'Q_RES_0402LF-0,5%,1/16W,EMPTY,CS00002JB38':;

SECTION_NUMBER 1
 '@T6G_MB_LIB.T6G(SCH_1):PAGE234_I54@PURE_QUANTA.Q_RES(CHIPS)':
 C_PATH='@t6g_mb_lib.t6g(sch_1):page234_i54@pure_quanta.q_res(chips)';

PART_NAME
 R1648 'Q_RES_0402LF-0,5%,1/16W,EMPTY,CS00002JB38':;

SECTION_NUMBER 1
 '@T6G_MB_LIB.T6G(SCH_1):PAGE234_I45@PURE_QUANTA.Q_RES(CHIPS)':
 C_PATH='@t6g_mb_lib.t6g(sch_1):page234_i45@pure_quanta.q_res(chips)';

PART_NAME
 R1356 'Q_RES_0402LF-0,5%,1/16W,EMPTY,CS00002JB38':;

SECTION_NUMBER 1
 '@T6G_MB_LIB.T6G(SCH_1):PAGE234_I55@PURE_QUANTA.Q_RES(CHIPS)':
 C_PATH='@t6g_mb_lib.t6g(sch_1):page234_i55@pure_quanta.q_res(chips)';

PART_NAME
 R1351 'Q_RES_0402LF-33,5%,1/16W,CHIP,CS03302JB29':;

SECTION_NUMBER 1
 '@T6G_MB_LIB.T6G(SCH_1):PAGE234_I81@PURE_QUANTA.Q_RES(CHIPS)':
 C_PATH='@t6g_mb_lib.t6g(sch_1):page234_i81@pure_quanta.q_res(chips)';

PART_NAME
 R1350 'Q_RES_0402LF-0,5%,1/16W,CHIP,CS00002JB38':;

SECTION_NUMBER 1
 '@T6G_MB_LIB.T6G(SCH_1):PAGE234_I80@PURE_QUANTA.Q_RES(CHIPS)':
 C_PATH='@t6g_mb_lib.t6g(sch_1):page234_i80@pure_quanta.q_res(chips)';

PART_NAME
 R1349 'Q_RES_0402LF-0,5%,1/16W,CHIP,CS00002JB38':;

SECTION_NUMBER 1
 '@T6G_MB_LIB.T6G(SCH_1):PAGE234_I71@PURE_QUANTA.Q_RES(CHIPS)':
 C_PATH='@t6g_mb_lib.t6g(sch_1):page234_i71@pure_quanta.q_res(chips)';

PART_NAME
 R1348 'Q_RES_0402LF-0,5%,1/16W,CHIP,CS00002JB38':;

SECTION_NUMBER 1
 '@T6G_MB_LIB.T6G(SCH_1):PAGE234_I69@PURE_QUANTA.Q_RES(CHIPS)':
 C_PATH='@t6g_mb_lib.t6g(sch_1):page234_i69@pure_quanta.q_res(chips)';

PART_NAME
 R1347 'Q_RES_0402LF-240,1%,1/16W,CHIP,CS12402FB03':;

SECTION_NUMBER 1
 '@T6G_MB_LIB.T6G(SCH_1):PAGE234_I90@PURE_QUANTA.Q_RES(CHIPS)':
 C_PATH='@t6g_mb_lib.t6g(sch_1):page234_i90@pure_quanta.q_res(chips)';

PART_NAME
 R1346 'Q_RES_0402LF-240,1%,1/16W,CHIP,CS12402FB03':;

SECTION_NUMBER 1
 '@T6G_MB_LIB.T6G(SCH_1):PAGE234_I83@PURE_QUANTA.Q_RES(CHIPS)':
 C_PATH='@t6g_mb_lib.t6g(sch_1):page234_i83@pure_quanta.q_res(chips)';

PART_NAME
 R1345 'Q_RES_0402LF-240,1%,1/16W,CHIP,CS12402FB03':;

SECTION_NUMBER 1
 '@T6G_MB_LIB.T6G(SCH_1):PAGE234_I91@PURE_QUANTA.Q_RES(CHIPS)':
 C_PATH='@t6g_mb_lib.t6g(sch_1):page234_i91@pure_quanta.q_res(chips)';

PART_NAME
 R1343 'Q_RES_0402LF-240,1%,1/16W,CHIP,CS12402FB03':;

SECTION_NUMBER 1
 '@T6G_MB_LIB.T6G(SCH_1):PAGE234_I84@PURE_QUANTA.Q_RES(CHIPS)':
 C_PATH='@t6g_mb_lib.t6g(sch_1):page234_i84@pure_quanta.q_res(chips)';

PART_NAME
 R1342 'Q_RES_0402LF-10,1%,1/16W,CHIP,TMP_QCS01002FB21':;

SECTION_NUMBER 1
 '@T6G_MB_LIB.T6G(SCH_1):PAGE234_I93@PURE_QUANTA.Q_RES(CHIPS)':
 C_PATH='@t6g_mb_lib.t6g(sch_1):page234_i93@pure_quanta.q_res(chips)';

PART_NAME
 R1341 'Q_RES_0402LF-10,1%,1/16W,CHIP,TMP_QCS01002FB21':;

SECTION_NUMBER 1
 '@T6G_MB_LIB.T6G(SCH_1):PAGE234_I92@PURE_QUANTA.Q_RES(CHIPS)':
 C_PATH='@t6g_mb_lib.t6g(sch_1):page234_i92@pure_quanta.q_res(chips)';

PART_NAME
 R1340 'Q_RES_0402LF-10,1%,1/16W,CHIP,TMP_QCS01002FB21':;

SECTION_NUMBER 1
 '@T6G_MB_LIB.T6G(SCH_1):PAGE234_I86@PURE_QUANTA.Q_RES(CHIPS)':
 C_PATH='@t6g_mb_lib.t6g(sch_1):page234_i86@pure_quanta.q_res(chips)';

PART_NAME
 R1339 'Q_RES_0402LF-10,1%,1/16W,CHIP,TMP_QCS01002FB21':;

SECTION_NUMBER 1
 '@T6G_MB_LIB.T6G(SCH_1):PAGE234_I85@PURE_QUANTA.Q_RES(CHIPS)':
 C_PATH='@t6g_mb_lib.t6g(sch_1):page234_i85@pure_quanta.q_res(chips)';

PART_NAME
 C2530 'Q_CAP_0402-0.1UF,25V,10%,X7R,CH4104K1B00':;

SECTION_NUMBER 1
 '@T6G_MB_LIB.T6G(SCH_1):PAGE234_I67@PURE_QUANTA.Q_CAP(CHIPS)':
 C_PATH='@t6g_mb_lib.t6g(sch_1):page234_i67@pure_quanta.q_cap(chips)';

PART_NAME
 C1048 'Q_CAP_0402-0.1UF,25V,10%,X7R,CH4104K1B00':;

SECTION_NUMBER 1
 '@T6G_MB_LIB.T6G(SCH_1):PAGE234_I74@PURE_QUANTA.Q_CAP(CHIPS)':
 C_PATH='@t6g_mb_lib.t6g(sch_1):page234_i74@pure_quanta.q_cap(chips)';

PART_NAME
 C1047 'Q_CAP_0402-0.1UF,25V,10%,X7R,CH4104K1B00':;

SECTION_NUMBER 1
 '@T6G_MB_LIB.T6G(SCH_1):PAGE234_I64@PURE_QUANTA.Q_CAP(CHIPS)':
 C_PATH='@t6g_mb_lib.t6g(sch_1):page234_i64@pure_quanta.q_cap(chips)';

PART_NAME
 C1046 'Q_CAP_0402-0.1UF,25V,10%,X7R,CH4104K1B00':;

SECTION_NUMBER 1
 '@T6G_MB_LIB.T6G(SCH_1):PAGE234_I76@PURE_QUANTA.Q_CAP(CHIPS)':
 C_PATH='@t6g_mb_lib.t6g(sch_1):page234_i76@pure_quanta.q_cap(chips)';

PART_NAME
 U84 'SN74LVC1G17DCKR-SN74LVC1G17DCKR,SMLF,IC,AL1G0017003':;

SECTION_NUMBER 1
 '@T6G_MB_LIB.T6G(SCH_1):PAGE148_I47@PURE_QUANTA.SN74LVC1G17DCKR(CHIPS)':
 C_PATH='@t6g_mb_lib.t6g(sch_1):page148_i47@pure_quanta.sn74lvc1g17dckr(chips)';

PART_NAME
 U82 'SN74LVC2G07DCKR_SMLF-SN74LVC2G07DCKR,IC,AL002G07006':;

SECTION_NUMBER 1
 '@T6G_MB_LIB.T6G(SCH_1):PAGE148_I49@PURE_QUANTA.SN74LVC2G07DCKR(CHIPS)':
 C_PATH='@t6g_mb_lib.t6g(sch_1):page148_i49@pure_quanta.sn74lvc2g07dckr(chips)';

PART_NAME
 U4 'TPS3808G18DBVR-TPS3808G18DBVR,SMLF,IC,AL003808003':;

SECTION_NUMBER 1
 '@T6G_MB_LIB.T6G(SCH_1):PAGE148_I88@PURE_QUANTA.TPS3808G18DBVR(CHIPS)':
 C_PATH='@t6g_mb_lib.t6g(sch_1):page148_i88@pure_quanta.tps3808g18dbvr(chips)';

PART_NAME
 R3792 'Q_RES_0402LF-0,5%,1/16W,CHIP,CS00002JB38':;

SECTION_NUMBER 1
 '@T6G_MB_LIB.T6G(SCH_1):PAGE148_I134@PURE_QUANTA.Q_RES(CHIPS)':
 C_PATH='@t6g_mb_lib.t6g(sch_1):page148_i134@pure_quanta.q_res(chips)';

PART_NAME
 R3791 'Q_RES_0402LF-0,5%,1/16W,EMPTY,CS00002JB38':;

SECTION_NUMBER 1
 '@T6G_MB_LIB.T6G(SCH_1):PAGE148_I135@PURE_QUANTA.Q_RES(CHIPS)':
 C_PATH='@t6g_mb_lib.t6g(sch_1):page148_i135@pure_quanta.q_res(chips)';

PART_NAME
 R2750 'Q_RES_0402LF-10K,1%,1/16W,CHIP,TMP_QCS31002FB26':;

SECTION_NUMBER 1
 '@T6G_MB_LIB.T6G(SCH_1):PAGE148_I126@PURE_QUANTA.Q_RES(CHIPS)':
 C_PATH='@t6g_mb_lib.t6g(sch_1):page148_i126@pure_quanta.q_res(chips)';

PART_NAME
 R2749 'Q_RES_0402LF-10K,1%,1/16W,CHIP,TMP_QCS31002FB26':;

SECTION_NUMBER 1
 '@T6G_MB_LIB.T6G(SCH_1):PAGE148_I124@PURE_QUANTA.Q_RES(CHIPS)':
 C_PATH='@t6g_mb_lib.t6g(sch_1):page148_i124@pure_quanta.q_res(chips)';

PART_NAME
 R2748 'Q_RES_0402LF-10K,1%,1/16W,CHIP,TMP_QCS31002FB26':;

SECTION_NUMBER 1
 '@T6G_MB_LIB.T6G(SCH_1):PAGE148_I128@PURE_QUANTA.Q_RES(CHIPS)':
 C_PATH='@t6g_mb_lib.t6g(sch_1):page148_i128@pure_quanta.q_res(chips)';

PART_NAME
 R2747 'Q_RES_0402LF-10K,1%,1/16W,CHIP,TMP_QCS31002FB26':;

SECTION_NUMBER 1
 '@T6G_MB_LIB.T6G(SCH_1):PAGE148_I125@PURE_QUANTA.Q_RES(CHIPS)':
 C_PATH='@t6g_mb_lib.t6g(sch_1):page148_i125@pure_quanta.q_res(chips)';

PART_NAME
 R1136 'Q_RES_0402LF-25.5K,1%,1/16W,CHIP,CS32552FB11':;

SECTION_NUMBER 1
 '@T6G_MB_LIB.T6G(SCH_1):PAGE148_I82@PURE_QUANTA.Q_RES(CHIPS)':
 C_PATH='@t6g_mb_lib.t6g(sch_1):page148_i82@pure_quanta.q_res(chips)';

PART_NAME
 R1132 'Q_RES_0402LF-10K,5%,1/16W,CHIP,TMP_QCS31002JB28':;

SECTION_NUMBER 1
 '@T6G_MB_LIB.T6G(SCH_1):PAGE148_I98@PURE_QUANTA.Q_RES(CHIPS)':
 C_PATH='@t6g_mb_lib.t6g(sch_1):page148_i98@pure_quanta.q_res(chips)';

PART_NAME
 R1131 'Q_RES_0402LF-10K,5%,1/16W,CHIP,TMP_QCS31002JB28':;

SECTION_NUMBER 1
 '@T6G_MB_LIB.T6G(SCH_1):PAGE148_I90@PURE_QUANTA.Q_RES(CHIPS)':
 C_PATH='@t6g_mb_lib.t6g(sch_1):page148_i90@pure_quanta.q_res(chips)';

PART_NAME
 R1129 'Q_RES_0402LF-10K,5%,1/16W,CHIP,TMP_QCS31002JB28':;

SECTION_NUMBER 1
 '@T6G_MB_LIB.T6G(SCH_1):PAGE148_I23@PURE_QUANTA.Q_RES(CHIPS)':
 C_PATH='@t6g_mb_lib.t6g(sch_1):page148_i23@pure_quanta.q_res(chips)';

PART_NAME
 R1128 'Q_RES_0402LF-267K,1%,1/16W,CHIP,CS42672FB16':;

SECTION_NUMBER 1
 '@T6G_MB_LIB.T6G(SCH_1):PAGE148_I16@PURE_QUANTA.Q_RES(CHIPS)':
 C_PATH='@t6g_mb_lib.t6g(sch_1):page148_i16@pure_quanta.q_res(chips)';

PART_NAME
 R1127 'Q_RES_0402LF-4.7K,5%,1/16W,CHIP,TMP_QCS24702JB38':;

SECTION_NUMBER 1
 '@T6G_MB_LIB.T6G(SCH_1):PAGE148_I57@PURE_QUANTA.Q_RES(CHIPS)':
 C_PATH='@t6g_mb_lib.t6g(sch_1):page148_i57@pure_quanta.q_res(chips)';

PART_NAME
 R1126 'Q_RES_0402LF-10K,5%,1/16W,CHIP,TMP_QCS31002JB28':;

SECTION_NUMBER 1
 '@T6G_MB_LIB.T6G(SCH_1):PAGE148_I42@PURE_QUANTA.Q_RES(CHIPS)':
 C_PATH='@t6g_mb_lib.t6g(sch_1):page148_i42@pure_quanta.q_res(chips)';

PART_NAME
 R1125 'Q_RES_0402LF-10K,5%,1/16W,CHIP,TMP_QCS31002JB28':;

SECTION_NUMBER 1
 '@T6G_MB_LIB.T6G(SCH_1):PAGE148_I39@PURE_QUANTA.Q_RES(CHIPS)':
 C_PATH='@t6g_mb_lib.t6g(sch_1):page148_i39@pure_quanta.q_res(chips)';

PART_NAME
 R1124 'Q_RES_0402LF-10K,5%,1/16W,EMPTY,TMP_QCS31002JB28':;

SECTION_NUMBER 1
 '@T6G_MB_LIB.T6G(SCH_1):PAGE148_I26@PURE_QUANTA.Q_RES(CHIPS)':
 C_PATH='@t6g_mb_lib.t6g(sch_1):page148_i26@pure_quanta.q_res(chips)';

PART_NAME
 R1123 'Q_RES_0402LF-0,5%,1/16W,CHIP,CS00002JB38':;

SECTION_NUMBER 1
 '@T6G_MB_LIB.T6G(SCH_1):PAGE148_I55@PURE_QUANTA.Q_RES(CHIPS)':
 C_PATH='@t6g_mb_lib.t6g(sch_1):page148_i55@pure_quanta.q_res(chips)';

PART_NAME
 R1122 'Q_RES_0402LF-0,5%,1/16W,CHIP,CS00002JB38':;

SECTION_NUMBER 1
 '@T6G_MB_LIB.T6G(SCH_1):PAGE148_I56@PURE_QUANTA.Q_RES(CHIPS)':
 C_PATH='@t6g_mb_lib.t6g(sch_1):page148_i56@pure_quanta.q_res(chips)';

PART_NAME
 R1121 'Q_RES_0402LF-0,5%,1/16W,CHIP,CS00002JB38':;

SECTION_NUMBER 1
 '@T6G_MB_LIB.T6G(SCH_1):PAGE148_I59@PURE_QUANTA.Q_RES(CHIPS)':
 C_PATH='@t6g_mb_lib.t6g(sch_1):page148_i59@pure_quanta.q_res(chips)';

PART_NAME
 R1120 'Q_RES_0402LF-0,5%,1/16W,CHIP,CS00002JB38':;

SECTION_NUMBER 1
 '@T6G_MB_LIB.T6G(SCH_1):PAGE148_I60@PURE_QUANTA.Q_RES(CHIPS)':
 C_PATH='@t6g_mb_lib.t6g(sch_1):page148_i60@pure_quanta.q_res(chips)';

PART_NAME
 R1119 'Q_RES_0402LF-10K,5%,1/16W,CHIP,TMP_QCS31002JB28':;

SECTION_NUMBER 1
 '@T6G_MB_LIB.T6G(SCH_1):PAGE148_I97@PURE_QUANTA.Q_RES(CHIPS)':
 C_PATH='@t6g_mb_lib.t6g(sch_1):page148_i97@pure_quanta.q_res(chips)';

PART_NAME
 R1118 'Q_RES_0402LF-100,5%,1/16W,CHIP,TMP_QCS11002JB32':;

SECTION_NUMBER 1
 '@T6G_MB_LIB.T6G(SCH_1):PAGE148_I100@PURE_QUANTA.Q_RES(CHIPS)':
 C_PATH='@t6g_mb_lib.t6g(sch_1):page148_i100@pure_quanta.q_res(chips)';

PART_NAME
 R1117 'Q_RES_0402LF-10K,5%,1/16W,CHIP,TMP_QCS31002JB28':;

SECTION_NUMBER 1
 '@T6G_MB_LIB.T6G(SCH_1):PAGE148_I29@PURE_QUANTA.Q_RES(CHIPS)':
 C_PATH='@t6g_mb_lib.t6g(sch_1):page148_i29@pure_quanta.q_res(chips)';

PART_NAME
 R1116 'Q_RES_0402LF-4.53K,1%,1/16W,CHIP,TMP_QCS24532FB08':;

SECTION_NUMBER 1
 '@T6G_MB_LIB.T6G(SCH_1):PAGE148_I81@PURE_QUANTA.Q_RES(CHIPS)':
 C_PATH='@t6g_mb_lib.t6g(sch_1):page148_i81@pure_quanta.q_res(chips)';

PART_NAME
 R1115 'Q_RES_0402LF-0,5%,1/16W,CHIP,CS00002JB38':;

SECTION_NUMBER 1
 '@T6G_MB_LIB.T6G(SCH_1):PAGE148_I61@PURE_QUANTA.Q_RES(CHIPS)':
 C_PATH='@t6g_mb_lib.t6g(sch_1):page148_i61@pure_quanta.q_res(chips)';

PART_NAME
 R1114 'Q_RES_0402LF-10K,5%,1/16W,CHIP,TMP_QCS31002JB28':;

SECTION_NUMBER 1
 '@T6G_MB_LIB.T6G(SCH_1):PAGE148_I69@PURE_QUANTA.Q_RES(CHIPS)':
 C_PATH='@t6g_mb_lib.t6g(sch_1):page148_i69@pure_quanta.q_res(chips)';

PART_NAME
 R1113 'Q_RES_0402LF-0,5%,1/16W,CHIP,CS00002JB38':;

SECTION_NUMBER 1
 '@T6G_MB_LIB.T6G(SCH_1):PAGE148_I62@PURE_QUANTA.Q_RES(CHIPS)':
 C_PATH='@t6g_mb_lib.t6g(sch_1):page148_i62@pure_quanta.q_res(chips)';

PART_NAME
 R1112 'Q_RES_0402LF-0,5%,1/16W,CHIP,CS00002JB38':;

SECTION_NUMBER 1
 '@T6G_MB_LIB.T6G(SCH_1):PAGE148_I63@PURE_QUANTA.Q_RES(CHIPS)':
 C_PATH='@t6g_mb_lib.t6g(sch_1):page148_i63@pure_quanta.q_res(chips)';

PART_NAME
 R106 'Q_RES_0402LF-0,5%,1/16W,CHIP,CS00002JB38':;

SECTION_NUMBER 1
 '@T6G_MB_LIB.T6G(SCH_1):PAGE148_I64@PURE_QUANTA.Q_RES(CHIPS)':
 C_PATH='@t6g_mb_lib.t6g(sch_1):page148_i64@pure_quanta.q_res(chips)';

PART_NAME
 Q32 'MOSFET_NCH_DUAL-2N7002KDW,SMLF,IC,BAM70020047':;

SECTION_NUMBER 1
 '@T6G_MB_LIB.T6G(SCH_1):PAGE148_I37@PURE_QUANTA.MOSFET_NCH_DUAL(CHIPS)':
 C_PATH='@t6g_mb_lib.t6g(sch_1):page148_i37@pure_quanta.mosfet_nch_dual(chips)';

SECTION_NUMBER 2
 '@T6G_MB_LIB.T6G(SCH_1):PAGE148_I36@PURE_QUANTA.MOSFET_NCH_DUAL(CHIPS)':
 C_PATH='@t6g_mb_lib.t6g(sch_1):page148_i36@pure_quanta.mosfet_nch_dual(chips)';

PART_NAME
 Q31 'MOSFET_NCH_DUAL-2N7002KDW,SMLF,IC,BAM70020047':;

SECTION_NUMBER 1
 '@T6G_MB_LIB.T6G(SCH_1):PAGE148_I92@PURE_QUANTA.MOSFET_NCH_DUAL(CHIPS)':
 C_PATH='@t6g_mb_lib.t6g(sch_1):page148_i92@pure_quanta.mosfet_nch_dual(chips)';

SECTION_NUMBER 2
 '@T6G_MB_LIB.T6G(SCH_1):PAGE148_I94@PURE_QUANTA.MOSFET_NCH_DUAL(CHIPS)':
 C_PATH='@t6g_mb_lib.t6g(sch_1):page148_i94@pure_quanta.mosfet_nch_dual(chips)';

PART_NAME
 Q30 'MOSFET_NCH_DUAL-2N7002KDW,SMLF,IC,BAM70020047':;

SECTION_NUMBER 1
 '@T6G_MB_LIB.T6G(SCH_1):PAGE148_I52@PURE_QUANTA.MOSFET_NCH_DUAL(CHIPS)':
 C_PATH='@t6g_mb_lib.t6g(sch_1):page148_i52@pure_quanta.mosfet_nch_dual(chips)';

SECTION_NUMBER 2
 '@T6G_MB_LIB.T6G(SCH_1):PAGE148_I33@PURE_QUANTA.MOSFET_NCH_DUAL(CHIPS)':
 C_PATH='@t6g_mb_lib.t6g(sch_1):page148_i33@pure_quanta.mosfet_nch_dual(chips)';

PART_NAME
 D34 'Q_DIODE_SMLF-SDMK0340L-7-F,IC,BC000340033':;

SECTION_NUMBER 1
 '@T6G_MB_LIB.T6G(SCH_1):PAGE148_I22@PURE_QUANTA.Q_DIODE(CHIPS)':
 C_PATH='@t6g_mb_lib.t6g(sch_1):page148_i22@pure_quanta.q_diode(chips)';

PART_NAME
 D33 'Q_DIODE_SMLF-SDMK0340L-7-F,IC,BC000340033':;

SECTION_NUMBER 1
 '@T6G_MB_LIB.T6G(SCH_1):PAGE148_I21@PURE_QUANTA.Q_DIODE(CHIPS)':
 C_PATH='@t6g_mb_lib.t6g(sch_1):page148_i21@pure_quanta.q_diode(chips)';

PART_NAME
 D32 'Q_DIODE_SMLF-SDMK0340L-7-F,IC,BC000340033':;

SECTION_NUMBER 1
 '@T6G_MB_LIB.T6G(SCH_1):PAGE148_I28@PURE_QUANTA.Q_DIODE(CHIPS)':
 C_PATH='@t6g_mb_lib.t6g(sch_1):page148_i28@pure_quanta.q_diode(chips)';

PART_NAME
 D31 'Q_DIODE_SMLF-SDMK0340L-7-F,IC,BC000340033':;

SECTION_NUMBER 1
 '@T6G_MB_LIB.T6G(SCH_1):PAGE148_I27@PURE_QUANTA.Q_DIODE(CHIPS)':
 C_PATH='@t6g_mb_lib.t6g(sch_1):page148_i27@pure_quanta.q_diode(chips)';

PART_NAME
 D29 'Q_DIODE_SMLF-SDMK0340L-7-F,IC,BC000340033':;

SECTION_NUMBER 1
 '@T6G_MB_LIB.T6G(SCH_1):PAGE148_I19@PURE_QUANTA.Q_DIODE(CHIPS)':
 C_PATH='@t6g_mb_lib.t6g(sch_1):page148_i19@pure_quanta.q_diode(chips)';

PART_NAME
 C897 'Q_CAP_0402-0.1UF,25V,10%,X7R,CH4104K1B00':;

SECTION_NUMBER 1
 '@T6G_MB_LIB.T6G(SCH_1):PAGE148_I51@PURE_QUANTA.Q_CAP(CHIPS)':
 C_PATH='@t6g_mb_lib.t6g(sch_1):page148_i51@pure_quanta.q_cap(chips)';

PART_NAME
 C896 'Q_CAP_0402-2200PF,50V,10%,X7R,TMP_QCH22206KB16':;

SECTION_NUMBER 1
 '@T6G_MB_LIB.T6G(SCH_1):PAGE148_I80@PURE_QUANTA.Q_CAP(CHIPS)':
 C_PATH='@t6g_mb_lib.t6g(sch_1):page148_i80@pure_quanta.q_cap(chips)';

PART_NAME
 C891 'Q_CAP_0402-2200PF,50V,10%,X7R,TMP_QCH22206KB16':;

SECTION_NUMBER 1
 '@T6G_MB_LIB.T6G(SCH_1):PAGE148_I78@PURE_QUANTA.Q_CAP(CHIPS)':
 C_PATH='@t6g_mb_lib.t6g(sch_1):page148_i78@pure_quanta.q_cap(chips)';

PART_NAME
 C890 'Q_CAP_0402-0.1UF,25V,10%,X7R,CH4104K1B00':;

SECTION_NUMBER 1
 '@T6G_MB_LIB.T6G(SCH_1):PAGE148_I86@PURE_QUANTA.Q_CAP(CHIPS)':
 C_PATH='@t6g_mb_lib.t6g(sch_1):page148_i86@pure_quanta.q_cap(chips)';

PART_NAME
 C889 'Q_CAP_0402-1000PF,50V,5%,X7R,TMP_QCH21006JB10':;

SECTION_NUMBER 1
 '@T6G_MB_LIB.T6G(SCH_1):PAGE148_I83@PURE_QUANTA.Q_CAP(CHIPS)':
 C_PATH='@t6g_mb_lib.t6g(sch_1):page148_i83@pure_quanta.q_cap(chips)';

PART_NAME
 C888 'Q_CAP_0402-0.1UF,25V,10%,X7R,CH4104K1B00':;

SECTION_NUMBER 1
 '@T6G_MB_LIB.T6G(SCH_1):PAGE148_I45@PURE_QUANTA.Q_CAP(CHIPS)':
 C_PATH='@t6g_mb_lib.t6g(sch_1):page148_i45@pure_quanta.q_cap(chips)';

PART_NAME
 C887 'Q_CAP_C0603-4.7UF,25V,10%,X6S,CH5474KE906':;

SECTION_NUMBER 1
 '@T6G_MB_LIB.T6G(SCH_1):PAGE148_I18@PURE_QUANTA.Q_CAP(CHIPS)':
 C_PATH='@t6g_mb_lib.t6g(sch_1):page148_i18@pure_quanta.q_cap(chips)';

PART_NAME
 U13 '74LVC1G02GW_SMLF-74LVC1G02GW,IC,ALVC1G02000':;

SECTION_NUMBER 1
 '@T6G_MB_LIB.T6G(SCH_1):PAGE280_I247@PURE_QUANTA.74LVC1G02GW(CHIPS)':
 C_PATH='@t6g_mb_lib.t6g(sch_1):page280_i247@pure_quanta.\74lvc1g02gw\(chips)';

PART_NAME
 R3547 'Q_RES_0805LF-820,1%,1/4W,CHIP,TMP_QCS18206FA00':;

SECTION_NUMBER 1
 '@T6G_MB_LIB.T6G(SCH_1):PAGE280_I231@PURE_QUANTA.Q_RES(CHIPS)':
 C_PATH='@t6g_mb_lib.t6g(sch_1):page280_i231@pure_quanta.q_res(chips)';

PART_NAME
 R3546 'Q_RES_0805LF-820,1%,1/4W,CHIP,TMP_QCS18206FA00':;

SECTION_NUMBER 1
 '@T6G_MB_LIB.T6G(SCH_1):PAGE280_I229@PURE_QUANTA.Q_RES(CHIPS)':
 C_PATH='@t6g_mb_lib.t6g(sch_1):page280_i229@pure_quanta.q_res(chips)';

PART_NAME
 R3494 'Q_RES_0402LF-4.7K,5%,1/16W,CHIP,TMP_QCS24702JB38':;

SECTION_NUMBER 1
 '@T6G_MB_LIB.T6G(SCH_1):PAGE280_I211@PURE_QUANTA.Q_RES(CHIPS)':
 C_PATH='@t6g_mb_lib.t6g(sch_1):page280_i211@pure_quanta.q_res(chips)';

PART_NAME
 R3493 'Q_RES_0402LF-2K,5%,1/16W,CHIP,TMP_QCS22002JB29':;

SECTION_NUMBER 1
 '@T6G_MB_LIB.T6G(SCH_1):PAGE280_I208@PURE_QUANTA.Q_RES(CHIPS)':
 C_PATH='@t6g_mb_lib.t6g(sch_1):page280_i208@pure_quanta.q_res(chips)';

PART_NAME
 R2848 'Q_RES_0402LF-0,5%,1/16W,CHIP,CS00002JB38':;

SECTION_NUMBER 1
 '@T6G_MB_LIB.T6G(SCH_1):PAGE280_I170@PURE_QUANTA.Q_RES(CHIPS)':
 C_PATH='@t6g_mb_lib.t6g(sch_1):page280_i170@pure_quanta.q_res(chips)';

PART_NAME
 R2847 'Q_RES_0402LF-33,5%,1/16W,CHIP,CS03302JB29':;

SECTION_NUMBER 1
 '@T6G_MB_LIB.T6G(SCH_1):PAGE280_I166@PURE_QUANTA.Q_RES(CHIPS)':
 C_PATH='@t6g_mb_lib.t6g(sch_1):page280_i166@pure_quanta.q_res(chips)';

PART_NAME
 R1538 'Q_RES_0402LF-0,5%,1/16W,CHIP,CS00002JB38':;

SECTION_NUMBER 1
 '@T6G_MB_LIB.T6G(SCH_1):PAGE280_I172@PURE_QUANTA.Q_RES(CHIPS)':
 C_PATH='@t6g_mb_lib.t6g(sch_1):page280_i172@pure_quanta.q_res(chips)';

PART_NAME
 R1537 'Q_RES_0402LF-33,5%,1/16W,CHIP,CS03302JB29':;

SECTION_NUMBER 1
 '@T6G_MB_LIB.T6G(SCH_1):PAGE280_I171@PURE_QUANTA.Q_RES(CHIPS)':
 C_PATH='@t6g_mb_lib.t6g(sch_1):page280_i171@pure_quanta.q_res(chips)';

PART_NAME
 R631 'Q_RES_0402LF-33,5%,1/16W,CHIP,CS03302JB29':;

SECTION_NUMBER 1
 '@T6G_MB_LIB.T6G(SCH_1):PAGE280_I241@PURE_QUANTA.Q_RES(CHIPS)':
 C_PATH='@t6g_mb_lib.t6g(sch_1):page280_i241@pure_quanta.q_res(chips)';

PART_NAME
 R605 'Q_RES_0402LF-0,5%,1/16W,CHIP,CS00002JB13':;

SECTION_NUMBER 1
 '@T6G_MB_LIB.T6G(SCH_1):PAGE280_I233@PURE_QUANTA.Q_RES(CHIPS)':
 C_PATH='@t6g_mb_lib.t6g(sch_1):page280_i233@pure_quanta.q_res(chips)';

PART_NAME
 R575 'Q_RES_0402LF-10K,1%,1/16W,CHIP,CS31002FB08':;

SECTION_NUMBER 1
 '@T6G_MB_LIB.T6G(SCH_1):PAGE280_I235@PURE_QUANTA.Q_RES(CHIPS)':
 C_PATH='@t6g_mb_lib.t6g(sch_1):page280_i235@pure_quanta.q_res(chips)';

PART_NAME
 R573 'Q_RES_0402LF-33,5%,1/16W,CHIP,CS03302JB29':;

SECTION_NUMBER 1
 '@T6G_MB_LIB.T6G(SCH_1):PAGE280_I253@PURE_QUANTA.Q_RES(CHIPS)':
 C_PATH='@t6g_mb_lib.t6g(sch_1):page280_i253@pure_quanta.q_res(chips)';

PART_NAME
 R566 'Q_RES_0402LF-33,5%,1/16W,CHIP,CS03302JB29':;

SECTION_NUMBER 1
 '@T6G_MB_LIB.T6G(SCH_1):PAGE280_I255@PURE_QUANTA.Q_RES(CHIPS)':
 C_PATH='@t6g_mb_lib.t6g(sch_1):page280_i255@pure_quanta.q_res(chips)';

PART_NAME
 R542 'Q_RES_0402LF-10K,1%,1/16W,EMPTY,CS31002FB08':;

SECTION_NUMBER 1
 '@T6G_MB_LIB.T6G(SCH_1):PAGE280_I314@PURE_QUANTA.Q_RES(CHIPS)':
 C_PATH='@t6g_mb_lib.t6g(sch_1):page280_i314@pure_quanta.q_res(chips)';

PART_NAME
 R535 'Q_RES_0402LF-10K,1%,1/16W,CHIP,CS31002FB08':;

SECTION_NUMBER 1
 '@T6G_MB_LIB.T6G(SCH_1):PAGE280_I324@PURE_QUANTA.Q_RES(CHIPS)':
 C_PATH='@t6g_mb_lib.t6g(sch_1):page280_i324@pure_quanta.q_res(chips)';

PART_NAME
 R534 'Q_RES_0402LF-10K,1%,1/16W,EMPTY,CS31002FB08':;

SECTION_NUMBER 1
 '@T6G_MB_LIB.T6G(SCH_1):PAGE280_I315@PURE_QUANTA.Q_RES(CHIPS)':
 C_PATH='@t6g_mb_lib.t6g(sch_1):page280_i315@pure_quanta.q_res(chips)';

PART_NAME
 R533 'Q_RES_0402LF-10K,1%,1/16W,CHIP,CS31002FB08':;

SECTION_NUMBER 1
 '@T6G_MB_LIB.T6G(SCH_1):PAGE280_I325@PURE_QUANTA.Q_RES(CHIPS)':
 C_PATH='@t6g_mb_lib.t6g(sch_1):page280_i325@pure_quanta.q_res(chips)';

PART_NAME
 R522 'Q_RES_0402LF-2.2K ,5%,1/16W,EMPTY,CS22202JB18':;

SECTION_NUMBER 1
 '@T6G_MB_LIB.T6G(SCH_1):PAGE280_I174@PURE_QUANTA.Q_RES(CHIPS)':
 C_PATH='@t6g_mb_lib.t6g(sch_1):page280_i174@pure_quanta.q_res(chips)';

PART_NAME
 R521 'Q_RES_0402LF-2.2K ,5%,1/16W,EMPTY,CS22202JB18':;

SECTION_NUMBER 1
 '@T6G_MB_LIB.T6G(SCH_1):PAGE280_I173@PURE_QUANTA.Q_RES(CHIPS)':
 C_PATH='@t6g_mb_lib.t6g(sch_1):page280_i173@pure_quanta.q_res(chips)';

PART_NAME
 Q183 'MOSFET_NCH_DUAL-2N7002KDW,SMLF,IC,BAM70020047':;

SECTION_NUMBER 1
 '@T6G_MB_LIB.T6G(SCH_1):PAGE280_I236@PURE_QUANTA.MOSFET_NCH_DUAL(CHIPS)':
 C_PATH='@t6g_mb_lib.t6g(sch_1):page280_i236@pure_quanta.mosfet_nch_dual(chips)';

SECTION_NUMBER 2
 '@T6G_MB_LIB.T6G(SCH_1):PAGE280_I239@PURE_QUANTA.MOSFET_NCH_DUAL(CHIPS)':
 C_PATH='@t6g_mb_lib.t6g(sch_1):page280_i239@pure_quanta.mosfet_nch_dual(chips)';

PART_NAME
 Q93 'MOSFET_NCH_DUAL-2N7002KDW,SMLF,IC,BAM70020047':;

SECTION_NUMBER 1
 '@T6G_MB_LIB.T6G(SCH_1):PAGE280_I227@PURE_QUANTA.MOSFET_NCH_DUAL(CHIPS)':
 C_PATH='@t6g_mb_lib.t6g(sch_1):page280_i227@pure_quanta.mosfet_nch_dual(chips)';

SECTION_NUMBER 2
 '@T6G_MB_LIB.T6G(SCH_1):PAGE280_I209@PURE_QUANTA.MOSFET_NCH_DUAL(CHIPS)':
 C_PATH='@t6g_mb_lib.t6g(sch_1):page280_i209@pure_quanta.mosfet_nch_dual(chips)';

PART_NAME
 Q85 'MOSFET_NCH_DUAL-2N7002KDW,SMLF,IC,BAM70020047':;

SECTION_NUMBER 1
 '@T6G_MB_LIB.T6G(SCH_1):PAGE280_I177@PURE_QUANTA.MOSFET_NCH_DUAL(CHIPS)':
 C_PATH='@t6g_mb_lib.t6g(sch_1):page280_i177@pure_quanta.mosfet_nch_dual(chips)';

SECTION_NUMBER 2
 '@T6G_MB_LIB.T6G(SCH_1):PAGE280_I176@PURE_QUANTA.MOSFET_NCH_DUAL(CHIPS)':
 C_PATH='@t6g_mb_lib.t6g(sch_1):page280_i176@pure_quanta.mosfet_nch_dual(chips)';

PART_NAME
 C812 'Q_CAP_0603-1UF,16V,10%,X7R,TMP_QCH5103K1900':
;

SECTION_NUMBER 1
 '@T6G_MB_LIB.T6G(SCH_1):PAGE280_I248@PURE_QUANTA.Q_CAP(CHIPS)':
 C_PATH='@t6g_mb_lib.t6g(sch_1):page280_i248@pure_quanta.q_cap(chips)';

PART_NAME
 C811 'Q_CAP_0603-1UF,16V,10%,X7R,TMP_QCH5103K1900':
;

SECTION_NUMBER 1
 '@T6G_MB_LIB.T6G(SCH_1):PAGE280_I254@PURE_QUANTA.Q_CAP(CHIPS)':
 C_PATH='@t6g_mb_lib.t6g(sch_1):page280_i254@pure_quanta.q_cap(chips)';

PART_NAME
 U201 'TUSB211IRWBR-TUSB211IRWBR,SMLF,IC,AL000211007':;

SECTION_NUMBER 1
 '@T6G_MB_LIB.T6G(SCH_1):PAGE264_I63@PURE_QUANTA.TUSB211IRWBR(CHIPS)':
 C_PATH='@t6g_mb_lib.t6g(sch_1):page264_i63@pure_quanta.tusb211irwbr(chips)';

PART_NAME
 U91 'IP4220CZ6-IP4220CZ6,SMLF,IC,BC004220Z00':;

SECTION_NUMBER 1
 '@T6G_MB_LIB.T6G(SCH_1):PAGE264_I25@PURE_QUANTA.IP4220CZ6(CHIPS)':
 C_PATH='@t6g_mb_lib.t6g(sch_1):page264_i25@pure_quanta.ip4220cz6(chips)';

PART_NAME
 U83 'TUSB211IRWBR-TUSB211IRWBR,SMLF,IC,AL000211007':;

SECTION_NUMBER 1
 '@T6G_MB_LIB.T6G(SCH_1):PAGE264_I67@PURE_QUANTA.TUSB211IRWBR(CHIPS)':
 C_PATH='@t6g_mb_lib.t6g(sch_1):page264_i67@pure_quanta.tusb211irwbr(chips)';

PART_NAME
 R2393 'Q_RES_0402LF-3.9K,1%,1/16W,CHIP,CS23902FB14':;

SECTION_NUMBER 1
 '@T6G_MB_LIB.T6G(SCH_1):PAGE264_I62@PURE_QUANTA.Q_RES(CHIPS)':
 C_PATH='@t6g_mb_lib.t6g(sch_1):page264_i62@pure_quanta.q_res(chips)';

PART_NAME
 R1161 'Q_RES_0402LF-0,5%,1/16W,CHIP,CS00002JB38':;

SECTION_NUMBER 1
 '@T6G_MB_LIB.T6G(SCH_1):PAGE264_I27@PURE_QUANTA.Q_RES(CHIPS)':
 C_PATH='@t6g_mb_lib.t6g(sch_1):page264_i27@pure_quanta.q_res(chips)';

PART_NAME
 R1160 'Q_RES_0402LF-0,5%,1/16W,CHIP,CS00002JB38':;

SECTION_NUMBER 1
 '@T6G_MB_LIB.T6G(SCH_1):PAGE264_I22@PURE_QUANTA.Q_RES(CHIPS)':
 C_PATH='@t6g_mb_lib.t6g(sch_1):page264_i22@pure_quanta.q_res(chips)';

PART_NAME
 R1159 'Q_RES_0402LF-0,5%,1/16W,CHIP,CS00002JB38':;

SECTION_NUMBER 1
 '@T6G_MB_LIB.T6G(SCH_1):PAGE264_I30@PURE_QUANTA.Q_RES(CHIPS)':
 C_PATH='@t6g_mb_lib.t6g(sch_1):page264_i30@pure_quanta.q_res(chips)';

PART_NAME
 R1158 'Q_RES_0402LF-0,5%,1/16W,CHIP,CS00002JB38':;

SECTION_NUMBER 1
 '@T6G_MB_LIB.T6G(SCH_1):PAGE264_I33@PURE_QUANTA.Q_RES(CHIPS)':
 C_PATH='@t6g_mb_lib.t6g(sch_1):page264_i33@pure_quanta.q_res(chips)';

PART_NAME
 R979 'Q_RES_0402LF-3.9K,1%,1/16W,CHIP,CS23902FB14':;

SECTION_NUMBER 1
 '@T6G_MB_LIB.T6G(SCH_1):PAGE264_I66@PURE_QUANTA.Q_RES(CHIPS)':
 C_PATH='@t6g_mb_lib.t6g(sch_1):page264_i66@pure_quanta.q_res(chips)';

PART_NAME
 L82 'Q_INDUCTOR4P_12-67/320MA,320MA,SMLF,EMPTY,CX21SN67000':;

SECTION_NUMBER 1
 '@T6G_MB_LIB.T6G(SCH_1):PAGE264_I34@PURE_QUANTA.Q_INDUCTOR4P_12(CHIPS)':
 C_PATH='@t6g_mb_lib.t6g(sch_1):page264_i34@pure_quanta.q_inductor4p_12(chips)';

PART_NAME
 L81 'Q_INDUCTOR4P_12-67/320MA,320MA,SMLF,EMPTY,CX21SN67000':;

SECTION_NUMBER 1
 '@T6G_MB_LIB.T6G(SCH_1):PAGE264_I18@PURE_QUANTA.Q_INDUCTOR4P_12(CHIPS)':
 C_PATH='@t6g_mb_lib.t6g(sch_1):page264_i18@pure_quanta.q_inductor4p_12(chips)';

PART_NAME
 C2402 'Q_CAP_C0402-1UF,25V,10%,X7R,CH-104K6B00':;

SECTION_NUMBER 1
 '@T6G_MB_LIB.T6G(SCH_1):PAGE264_I75@PURE_QUANTA.Q_CAP(CHIPS)':
 C_PATH='@t6g_mb_lib.t6g(sch_1):page264_i75@pure_quanta.q_cap(chips)';

PART_NAME
 C2401 'Q_CAP_0402-0.1UF,25V,10%,X7R,CH4104K1B00':;

SECTION_NUMBER 1
 '@T6G_MB_LIB.T6G(SCH_1):PAGE264_I72@PURE_QUANTA.Q_CAP(CHIPS)':
 C_PATH='@t6g_mb_lib.t6g(sch_1):page264_i72@pure_quanta.q_cap(chips)';

PART_NAME
 C2399 'Q_CAP_0402-0.1UF,25V,10%,X7R,CH4104K1B00':;

SECTION_NUMBER 1
 '@T6G_MB_LIB.T6G(SCH_1):PAGE264_I74@PURE_QUANTA.Q_CAP(CHIPS)':
 C_PATH='@t6g_mb_lib.t6g(sch_1):page264_i74@pure_quanta.q_cap(chips)';

PART_NAME
 C2396 'Q_CAP_0402-0.1UF,25V,10%,X7R,CH4104K1B00':;

SECTION_NUMBER 1
 '@T6G_MB_LIB.T6G(SCH_1):PAGE264_I60@PURE_QUANTA.Q_CAP(CHIPS)':
 C_PATH='@t6g_mb_lib.t6g(sch_1):page264_i60@pure_quanta.q_cap(chips)';

PART_NAME
 C933 'Q_CAP_C0402-0.1UF,16V,10%,X7R,CH4103K1B08':;

SECTION_NUMBER 1
 '@T6G_MB_LIB.T6G(SCH_1):PAGE264_I24@PURE_QUANTA.Q_CAP(CHIPS)':
 C_PATH='@t6g_mb_lib.t6g(sch_1):page264_i24@pure_quanta.q_cap(chips)';

PART_NAME
 C810 'Q_CAP_C0402-1UF,25V,10%,X7R,CH-104K6B00':;

SECTION_NUMBER 1
 '@T6G_MB_LIB.T6G(SCH_1):PAGE264_I85@PURE_QUANTA.Q_CAP(CHIPS)':
 C_PATH='@t6g_mb_lib.t6g(sch_1):page264_i85@pure_quanta.q_cap(chips)';

PART_NAME
 C809 'Q_CAP_0402-0.1UF,25V,10%,X7R,CH4104K1B00':;

SECTION_NUMBER 1
 '@T6G_MB_LIB.T6G(SCH_1):PAGE264_I81@PURE_QUANTA.Q_CAP(CHIPS)':
 C_PATH='@t6g_mb_lib.t6g(sch_1):page264_i81@pure_quanta.q_cap(chips)';

PART_NAME
 C808 'Q_CAP_0402-0.1UF,25V,10%,X7R,CH4104K1B00':;

SECTION_NUMBER 1
 '@T6G_MB_LIB.T6G(SCH_1):PAGE264_I84@PURE_QUANTA.Q_CAP(CHIPS)':
 C_PATH='@t6g_mb_lib.t6g(sch_1):page264_i84@pure_quanta.q_cap(chips)';

PART_NAME
 C807 'Q_CAP_0402-0.1UF,25V,10%,X7R,CH4104K1B00':;

SECTION_NUMBER 1
 '@T6G_MB_LIB.T6G(SCH_1):PAGE264_I64@PURE_QUANTA.Q_CAP(CHIPS)':
 C_PATH='@t6g_mb_lib.t6g(sch_1):page264_i64@pure_quanta.q_cap(chips)';

PART_NAME
 R4581 'Q_RES_0402LF-10K,5%,1/16W,CHIP,TMP_QCS31002JB28':;

SECTION_NUMBER 1
 '@T6G_MB_LIB.T6G(SCH_1):PAGE202_I583@PURE_QUANTA.Q_RES(CHIPS)':
 C_PATH='@t6g_mb_lib.t6g(sch_1):page202_i583@pure_quanta.q_res(chips)';

PART_NAME
 R4580 'Q_RES_0402LF-10K,5%,1/16W,CHIP,TMP_QCS31002JB28':;

SECTION_NUMBER 1
 '@T6G_MB_LIB.T6G(SCH_1):PAGE202_I587@PURE_QUANTA.Q_RES(CHIPS)':
 C_PATH='@t6g_mb_lib.t6g(sch_1):page202_i587@pure_quanta.q_res(chips)';

PART_NAME
 R3837 'Q_RES_0402LF-0,5%,1/16W,CHIP,CS00002JB38':;

SECTION_NUMBER 1
 '@T6G_MB_LIB.T6G(SCH_1):PAGE202_I599@PURE_QUANTA.Q_RES(CHIPS)':
 C_PATH='@t6g_mb_lib.t6g(sch_1):page202_i599@pure_quanta.q_res(chips)';

PART_NAME
 R3836 'Q_RES_0402LF-0,5%,1/16W,CHIP,CS00002JB38':;

SECTION_NUMBER 1
 '@T6G_MB_LIB.T6G(SCH_1):PAGE202_I600@PURE_QUANTA.Q_RES(CHIPS)':
 C_PATH='@t6g_mb_lib.t6g(sch_1):page202_i600@pure_quanta.q_res(chips)';

PART_NAME
 R3835 'Q_RES_0402LF-0,5%,1/16W,CHIP,CS00002JB38':;

SECTION_NUMBER 1
 '@T6G_MB_LIB.T6G(SCH_1):PAGE202_I598@PURE_QUANTA.Q_RES(CHIPS)':
 C_PATH='@t6g_mb_lib.t6g(sch_1):page202_i598@pure_quanta.q_res(chips)';

PART_NAME
 R2705 'Q_RES_0402LF-4.7K,5%,1/16W,CHIP,TMP_QCS24702JB38':;

SECTION_NUMBER 1
 '@T6G_MB_LIB.T6G(SCH_1):PAGE202_I501@PURE_QUANTA.Q_RES(CHIPS)':
 C_PATH='@t6g_mb_lib.t6g(sch_1):page202_i501@pure_quanta.q_res(chips)';

PART_NAME
 R1718 'Q_RES_0402LF-4.7K,5%,1/16W,CHIP,TMP_QCS24702JB38':;

SECTION_NUMBER 1
 '@T6G_MB_LIB.T6G(SCH_1):PAGE202_I517@PURE_QUANTA.Q_RES(CHIPS)':
 C_PATH='@t6g_mb_lib.t6g(sch_1):page202_i517@pure_quanta.q_res(chips)';

PART_NAME
 R1709 'Q_RES_0402LF-0,5%,1/16W,CHIP,CS00002JB38':;

SECTION_NUMBER 1
 '@T6G_MB_LIB.T6G(SCH_1):PAGE202_I542@PURE_QUANTA.Q_RES(CHIPS)':
 C_PATH='@t6g_mb_lib.t6g(sch_1):page202_i542@pure_quanta.q_res(chips)';

PART_NAME
 R1708 'Q_RES_0402LF-33,5%,1/16W,CHIP,CS03302JB29':;

SECTION_NUMBER 1
 '@T6G_MB_LIB.T6G(SCH_1):PAGE202_I549@PURE_QUANTA.Q_RES(CHIPS)':
 C_PATH='@t6g_mb_lib.t6g(sch_1):page202_i549@pure_quanta.q_res(chips)';

PART_NAME
 R1707 'Q_RES_0402LF-33,5%,1/16W,CHIP,CS03302JB29':;

SECTION_NUMBER 1
 '@T6G_MB_LIB.T6G(SCH_1):PAGE202_I550@PURE_QUANTA.Q_RES(CHIPS)':
 C_PATH='@t6g_mb_lib.t6g(sch_1):page202_i550@pure_quanta.q_res(chips)';

PART_NAME
 R1706 'Q_RES_0402LF-100,1%,1/16W,CHIP,TMP_QCS11002FB22':;

SECTION_NUMBER 1
 '@T6G_MB_LIB.T6G(SCH_1):PAGE202_I551@PURE_QUANTA.Q_RES(CHIPS)':
 C_PATH='@t6g_mb_lib.t6g(sch_1):page202_i551@pure_quanta.q_res(chips)';

PART_NAME
 R1699 'Q_RES_0402LF-4.7K,5%,1/16W,CHIP,TMP_QCS24702JB38':;

SECTION_NUMBER 1
 '@T6G_MB_LIB.T6G(SCH_1):PAGE202_I508@PURE_QUANTA.Q_RES(CHIPS)':
 C_PATH='@t6g_mb_lib.t6g(sch_1):page202_i508@pure_quanta.q_res(chips)';

PART_NAME
 R869 'Q_RES_0402LF-33,5%,1/16W,CHIP,CS03302JB29':;

SECTION_NUMBER 1
 '@T6G_MB_LIB.T6G(SCH_1):PAGE202_I568@PURE_QUANTA.Q_RES(CHIPS)':
 C_PATH='@t6g_mb_lib.t6g(sch_1):page202_i568@pure_quanta.q_res(chips)';

PART_NAME
 R769 'Q_RES_0402LF-100,1%,1/16W,CHIP,TMP_QCS11002FB22':;

SECTION_NUMBER 1
 '@T6G_MB_LIB.T6G(SCH_1):PAGE202_I570@PURE_QUANTA.Q_RES(CHIPS)':
 C_PATH='@t6g_mb_lib.t6g(sch_1):page202_i570@pure_quanta.q_res(chips)';

PART_NAME
 R694 'Q_RES_0402LF-0,5%,1/16W,CHIP,CS00002JB38':;

SECTION_NUMBER 1
 '@T6G_MB_LIB.T6G(SCH_1):PAGE202_I567@PURE_QUANTA.Q_RES(CHIPS)':
 C_PATH='@t6g_mb_lib.t6g(sch_1):page202_i567@pure_quanta.q_res(chips)';

PART_NAME
 R503 'Q_RES_0402LF-33,5%,1/16W,CHIP,CS03302JB29':;

SECTION_NUMBER 1
 '@T6G_MB_LIB.T6G(SCH_1):PAGE202_I569@PURE_QUANTA.Q_RES(CHIPS)':
 C_PATH='@t6g_mb_lib.t6g(sch_1):page202_i569@pure_quanta.q_res(chips)';

PART_NAME
 R487 'Q_RES_0402LF-100,5%,1/16W,EMPTY,TMP_QCS11002JB32':;

SECTION_NUMBER 1
 '@T6G_MB_LIB.T6G(SCH_1):PAGE202_I563@PURE_QUANTA.Q_RES(CHIPS)':
 C_PATH='@t6g_mb_lib.t6g(sch_1):page202_i563@pure_quanta.q_res(chips)';

PART_NAME
 R486 'Q_RES_0402LF-4.7K,5%,1/16W,CHIP,TMP_QCS24702JB38':;

SECTION_NUMBER 1
 '@T6G_MB_LIB.T6G(SCH_1):PAGE202_I554@PURE_QUANTA.Q_RES(CHIPS)':
 C_PATH='@t6g_mb_lib.t6g(sch_1):page202_i554@pure_quanta.q_res(chips)';

PART_NAME
 R485 'Q_RES_0402LF-100,5%,1/16W,EMPTY,TMP_QCS11002JB32':;

SECTION_NUMBER 1
 '@T6G_MB_LIB.T6G(SCH_1):PAGE202_I544@PURE_QUANTA.Q_RES(CHIPS)':
 C_PATH='@t6g_mb_lib.t6g(sch_1):page202_i544@pure_quanta.q_res(chips)';

PART_NAME
 R484 'Q_RES_0402LF-4.7K,5%,1/16W,CHIP,TMP_QCS24702JB38':;

SECTION_NUMBER 1
 '@T6G_MB_LIB.T6G(SCH_1):PAGE202_I546@PURE_QUANTA.Q_RES(CHIPS)':
 C_PATH='@t6g_mb_lib.t6g(sch_1):page202_i546@pure_quanta.q_res(chips)';

PART_NAME
 R483 'Q_RES_0402LF-0,5%,1/16W,CHIP,CS00002JB38':;

SECTION_NUMBER 1
 '@T6G_MB_LIB.T6G(SCH_1):PAGE202_I553@PURE_QUANTA.Q_RES(CHIPS)':
 C_PATH='@t6g_mb_lib.t6g(sch_1):page202_i553@pure_quanta.q_res(chips)';

PART_NAME
 R482 'Q_RES_0402LF-0,5%,1/16W,CHIP,CS00002JB38':;

SECTION_NUMBER 1
 '@T6G_MB_LIB.T6G(SCH_1):PAGE202_I545@PURE_QUANTA.Q_RES(CHIPS)':
 C_PATH='@t6g_mb_lib.t6g(sch_1):page202_i545@pure_quanta.q_res(chips)';

PART_NAME
 J66 'SCONN75K_517650752C012-SCONN75K_51765-0752C-012,SMLF,IO,DFHS75FS004':;

SECTION_NUMBER 1
 '@T6G_MB_LIB.T6G(SCH_1):PAGE202_I520@PURE_QUANTA.SCONN75K_517650752C012(CHIPS)':
 C_PATH='@t6g_mb_lib.t6g(sch_1):page202_i520@pure_quanta.sconn75k_517650752c012(~
chips)';

PART_NAME
 J65 'SCONN75K_517650752C012-SCONN75K_51765-0752C-012,SMLF,IO,DFHS75FS004':;

SECTION_NUMBER 1
 '@T6G_MB_LIB.T6G(SCH_1):PAGE202_I581@PURE_QUANTA.SCONN75K_517650752C012(CHIPS)':
 C_PATH='@t6g_mb_lib.t6g(sch_1):page202_i581@pure_quanta.sconn75k_517650752c012(~
chips)';

PART_NAME
 D103 'Q_DIODE_SMLF-SDMK0340L-7-F,IC,BC000340033':;

SECTION_NUMBER 1
 '@T6G_MB_LIB.T6G(SCH_1):PAGE202_I589@PURE_QUANTA.Q_DIODE(CHIPS)':
 C_PATH='@t6g_mb_lib.t6g(sch_1):page202_i589@pure_quanta.q_diode(chips)';

PART_NAME
 D102 'Q_DIODE_SMLF-SDMK0340L-7-F,IC,BC000340033':;

SECTION_NUMBER 1
 '@T6G_MB_LIB.T6G(SCH_1):PAGE202_I588@PURE_QUANTA.Q_DIODE(CHIPS)':
 C_PATH='@t6g_mb_lib.t6g(sch_1):page202_i588@pure_quanta.q_diode(chips)';

PART_NAME
 C2529 'Q_CAP_0402-0.1UF,25V,10%,X7R,CH4104K1B00':;

SECTION_NUMBER 1
 '@T6G_MB_LIB.T6G(SCH_1):PAGE202_I580@PURE_QUANTA.Q_CAP(CHIPS)':
 C_PATH='@t6g_mb_lib.t6g(sch_1):page202_i580@pure_quanta.q_cap(chips)';

PART_NAME
 C2528 'Q_CAP_0402-0.1UF,25V,10%,X7R,CH4104K1B00':;

SECTION_NUMBER 1
 '@T6G_MB_LIB.T6G(SCH_1):PAGE202_I578@PURE_QUANTA.Q_CAP(CHIPS)':
 C_PATH='@t6g_mb_lib.t6g(sch_1):page202_i578@pure_quanta.q_cap(chips)';

PART_NAME
 C2527 'Q_CAP_C0603-10UF,16V,20%,X6S,CH6103ME902':;

SECTION_NUMBER 1
 '@T6G_MB_LIB.T6G(SCH_1):PAGE202_I577@PURE_QUANTA.Q_CAP(CHIPS)':
 C_PATH='@t6g_mb_lib.t6g(sch_1):page202_i577@pure_quanta.q_cap(chips)';

PART_NAME
 C1175 'Q_CAP_0402-0.1UF,25V,10%,X7R,CH4104K1B00':;

SECTION_NUMBER 1
 '@T6G_MB_LIB.T6G(SCH_1):PAGE202_I565@PURE_QUANTA.Q_CAP(CHIPS)':
 C_PATH='@t6g_mb_lib.t6g(sch_1):page202_i565@pure_quanta.q_cap(chips)';

PART_NAME
 C1174 'Q_CAP_0402-0.1UF,25V,10%,X7R,CH4104K1B00':;

SECTION_NUMBER 1
 '@T6G_MB_LIB.T6G(SCH_1):PAGE202_I562@PURE_QUANTA.Q_CAP(CHIPS)':
 C_PATH='@t6g_mb_lib.t6g(sch_1):page202_i562@pure_quanta.q_cap(chips)';

PART_NAME
 C1173 'Q_CAP_C0603-10UF,16V,20%,X6S,CH6103ME902':;

SECTION_NUMBER 1
 '@T6G_MB_LIB.T6G(SCH_1):PAGE202_I560@PURE_QUANTA.Q_CAP(CHIPS)':
 C_PATH='@t6g_mb_lib.t6g(sch_1):page202_i560@pure_quanta.q_cap(chips)';

PART_NAME
 C733 'Q_CAP_C0402-0.1UF,16V,10%,X7R,CH4103K1B08':;

SECTION_NUMBER 1
 '@T6G_MB_LIB.T6G(SCH_1):PAGE202_I513@PURE_QUANTA.Q_CAP(CHIPS)':
 C_PATH='@t6g_mb_lib.t6g(sch_1):page202_i513@pure_quanta.q_cap(chips)';

PART_NAME
 C732 'Q_CAP_C0402-0.1UF,16V,10%,X7R,CH4103K1B08':;

SECTION_NUMBER 1
 '@T6G_MB_LIB.T6G(SCH_1):PAGE202_I512@PURE_QUANTA.Q_CAP(CHIPS)':
 C_PATH='@t6g_mb_lib.t6g(sch_1):page202_i512@pure_quanta.q_cap(chips)';

PART_NAME
 C731 'Q_CAP_C0402-0.1UF,16V,10%,X7R,CH4103K1B08':;

SECTION_NUMBER 1
 '@T6G_MB_LIB.T6G(SCH_1):PAGE202_I514@PURE_QUANTA.Q_CAP(CHIPS)':
 C_PATH='@t6g_mb_lib.t6g(sch_1):page202_i514@pure_quanta.q_cap(chips)';

PART_NAME
 C730 'Q_CAP_C0402-0.1UF,16V,10%,X7R,CH4103K1B08':;

SECTION_NUMBER 1
 '@T6G_MB_LIB.T6G(SCH_1):PAGE202_I515@PURE_QUANTA.Q_CAP(CHIPS)':
 C_PATH='@t6g_mb_lib.t6g(sch_1):page202_i515@pure_quanta.q_cap(chips)';

PART_NAME
 C729 'Q_CAP_C0402-0.1UF,16V,10%,X7R,CH4103K1B08':;

SECTION_NUMBER 1
 '@T6G_MB_LIB.T6G(SCH_1):PAGE202_I535@PURE_QUANTA.Q_CAP(CHIPS)':
 C_PATH='@t6g_mb_lib.t6g(sch_1):page202_i535@pure_quanta.q_cap(chips)';

PART_NAME
 C728 'Q_CAP_C0402-0.1UF,16V,10%,X7R,CH4103K1B08':;

SECTION_NUMBER 1
 '@T6G_MB_LIB.T6G(SCH_1):PAGE202_I536@PURE_QUANTA.Q_CAP(CHIPS)':
 C_PATH='@t6g_mb_lib.t6g(sch_1):page202_i536@pure_quanta.q_cap(chips)';

PART_NAME
 C727 'Q_CAP_C0402-0.1UF,16V,10%,X7R,CH4103K1B08':;

SECTION_NUMBER 1
 '@T6G_MB_LIB.T6G(SCH_1):PAGE202_I538@PURE_QUANTA.Q_CAP(CHIPS)':
 C_PATH='@t6g_mb_lib.t6g(sch_1):page202_i538@pure_quanta.q_cap(chips)';

PART_NAME
 C726 'Q_CAP_C0402-0.1UF,16V,10%,X7R,CH4103K1B08':;

SECTION_NUMBER 1
 '@T6G_MB_LIB.T6G(SCH_1):PAGE202_I537@PURE_QUANTA.Q_CAP(CHIPS)':
 C_PATH='@t6g_mb_lib.t6g(sch_1):page202_i537@pure_quanta.q_cap(chips)';

PART_NAME
 PU9 'NCP3284MNTXG-NCP3284MNTXG,SMLF,IC,AL003284001':;

SECTION_NUMBER 1
 '@T6G_MB_LIB.T6G(SCH_1):PAGE252_I130@PURE_QUANTA.NCP3284MNTXG(CHIPS)':
 C_PATH='@t6g_mb_lib.t6g(sch_1):page252_i130@pure_quanta.ncp3284mntxg(chips)';

PART_NAME
 PR836 'Q_RES_0402LF-1K,1%,1/16W,CHIP,TMP_QCS21002FB24':;

SECTION_NUMBER 1
 '@T6G_MB_LIB.T6G(SCH_1):PAGE252_I141@PURE_QUANTA.Q_RES(CHIPS)':
 C_PATH='@t6g_mb_lib.t6g(sch_1):page252_i141@pure_quanta.q_res(chips)';

PART_NAME
 PR835 'Q_RES_0402LF-0,5%,1/16W,CHIP,CS00002JB38':;

SECTION_NUMBER 1
 '@T6G_MB_LIB.T6G(SCH_1):PAGE252_I104@PURE_QUANTA.Q_RES(CHIPS)':
 C_PATH='@t6g_mb_lib.t6g(sch_1):page252_i104@pure_quanta.q_res(chips)';

PART_NAME
 PR834 'Q_RES_0402LF-21.5K,1%,1/16W,CHIP,TMP_QCS32152FB17':;

SECTION_NUMBER 1
 '@T6G_MB_LIB.T6G(SCH_1):PAGE252_I119@PURE_QUANTA.Q_RES(CHIPS)':
 C_PATH='@t6g_mb_lib.t6g(sch_1):page252_i119@pure_quanta.q_res(chips)';

PART_NAME
 PR833 'Q_RES_0402LF-1.5K,1%,1/16W,EMPTY,CS21502FB14':;

SECTION_NUMBER 1
 '@T6G_MB_LIB.T6G(SCH_1):PAGE252_I121@PURE_QUANTA.Q_RES(CHIPS)':
 C_PATH='@t6g_mb_lib.t6g(sch_1):page252_i121@pure_quanta.q_res(chips)';

PART_NAME
 PR832 'Q_RES_0402LF-7.5K,1%,1/16W,CHIP,TMP_QCS27502FB11':;

SECTION_NUMBER 1
 '@T6G_MB_LIB.T6G(SCH_1):PAGE252_I123@PURE_QUANTA.Q_RES(CHIPS)':
 C_PATH='@t6g_mb_lib.t6g(sch_1):page252_i123@pure_quanta.q_res(chips)';

PART_NAME
 PR831 'Q_RES_0402LF-100K,1%,1/16W,CHIP,TMP_QCS41002FB28':;

SECTION_NUMBER 1
 '@T6G_MB_LIB.T6G(SCH_1):PAGE252_I98@PURE_QUANTA.Q_RES(CHIPS)':
 C_PATH='@t6g_mb_lib.t6g(sch_1):page252_i98@pure_quanta.q_res(chips)';

PART_NAME
 PR830 'Q_RES_0402LF-31.6K,1%,1/16W,CHIP,TMP_QCS33162FB14':;

SECTION_NUMBER 1
 '@T6G_MB_LIB.T6G(SCH_1):PAGE252_I100@PURE_QUANTA.Q_RES(CHIPS)':
 C_PATH='@t6g_mb_lib.t6g(sch_1):page252_i100@pure_quanta.q_res(chips)';

PART_NAME
 PR389 'Q_RES_0402LF-1,1%,1/16W,CHIP,CS-1002FB23':;

SECTION_NUMBER 1
 '@T6G_MB_LIB.T6G(SCH_1):PAGE252_I137@PURE_QUANTA.Q_RES(CHIPS)':
 C_PATH='@t6g_mb_lib.t6g(sch_1):page252_i137@pure_quanta.q_res(chips)';

PART_NAME
 PR73 'Q_RES_0402LF-10K,5%,1/16W,CHIP,TMP_QCS31002JB28':;

SECTION_NUMBER 1
 '@T6G_MB_LIB.T6G(SCH_1):PAGE252_I102@PURE_QUANTA.Q_RES(CHIPS)':
 C_PATH='@t6g_mb_lib.t6g(sch_1):page252_i102@pure_quanta.q_res(chips)';

PART_NAME
 PL66 'Q_INDUCTOR_SMLF-1.5UH/27A,IND,CV-15S0MZ00':;

SECTION_NUMBER 1
 '@T6G_MB_LIB.T6G(SCH_1):PAGE252_I97@PURE_QUANTA.Q_INDUCTOR(CHIPS)':
 C_PATH='@t6g_mb_lib.t6g(sch_1):page252_i97@pure_quanta.q_inductor(chips)';

PART_NAME
 PL45 'Q_INDUCTOR_SMLF-100NH/16A,IND,CV+10G0MZ04':;

SECTION_NUMBER 1
 '@T6G_MB_LIB.T6G(SCH_1):PAGE252_I146@PURE_QUANTA.Q_INDUCTOR(CHIPS)':
 C_PATH='@t6g_mb_lib.t6g(sch_1):page252_i146@pure_quanta.q_inductor(chips)';

PART_NAME
 PC1869 'Q_CAP_0402-0.1UF,25V,10%,X7R,CH4104K1B00':;

SECTION_NUMBER 1
 '@T6G_MB_LIB.T6G(SCH_1):PAGE252_I92@PURE_QUANTA.Q_CAP(CHIPS)':
 C_PATH='@t6g_mb_lib.t6g(sch_1):page252_i92@pure_quanta.q_cap(chips)';

PART_NAME
 PC1868 'Q_CAP_C0805-22UF,10V,20%,X6S,CH6222MEA00':;

SECTION_NUMBER 1
 '@T6G_MB_LIB.T6G(SCH_1):PAGE252_I94@PURE_QUANTA.Q_CAP(CHIPS)':
 C_PATH='@t6g_mb_lib.t6g(sch_1):page252_i94@pure_quanta.q_cap(chips)';

PART_NAME
 PC1867 'Q_CAPP_THLF-560UF,6.3V,20%,OSCON,CC75601MD18':;

SECTION_NUMBER 1
 '@T6G_MB_LIB.T6G(SCH_1):PAGE252_I95@PURE_QUANTA.Q_CAPP(CHIPS)':
 C_PATH='@t6g_mb_lib.t6g(sch_1):page252_i95@pure_quanta.q_capp(chips)';

PART_NAME
 PC1866 'Q_CAPP_THLF-560UF,6.3V,20%,OSCON,CC75601MD18':;

SECTION_NUMBER 1
 '@T6G_MB_LIB.T6G(SCH_1):PAGE252_I96@PURE_QUANTA.Q_CAPP(CHIPS)':
 C_PATH='@t6g_mb_lib.t6g(sch_1):page252_i96@pure_quanta.q_capp(chips)';

PART_NAME
 PC591 'Q_CAP_C0603-2.2UF,16V,10%,X6S,CH5223KE901':;

SECTION_NUMBER 1
 '@T6G_MB_LIB.T6G(SCH_1):PAGE252_I149@PURE_QUANTA.Q_CAP(CHIPS)':
 C_PATH='@t6g_mb_lib.t6g(sch_1):page252_i149@pure_quanta.q_cap(chips)';

PART_NAME
 PC581 'Q_CAP_C0603-4.7UF,16V,10%,X6S,CH5473KE902':;

SECTION_NUMBER 1
 '@T6G_MB_LIB.T6G(SCH_1):PAGE252_I112@PURE_QUANTA.Q_CAP(CHIPS)':
 C_PATH='@t6g_mb_lib.t6g(sch_1):page252_i112@pure_quanta.q_cap(chips)';

PART_NAME
 PC577 'Q_CAP_0402-0.1UF,25V,10%,X7R,CH4104K1B00':;

SECTION_NUMBER 1
 '@T6G_MB_LIB.T6G(SCH_1):PAGE252_I89@PURE_QUANTA.Q_CAP(CHIPS)':
 C_PATH='@t6g_mb_lib.t6g(sch_1):page252_i89@pure_quanta.q_cap(chips)';

PART_NAME
 PC576 'Q_CAP_C0805-22UF,16V,20%,X6S,CH6223MEA00':;

SECTION_NUMBER 1
 '@T6G_MB_LIB.T6G(SCH_1):PAGE252_I113@PURE_QUANTA.Q_CAP(CHIPS)':
 C_PATH='@t6g_mb_lib.t6g(sch_1):page252_i113@pure_quanta.q_cap(chips)';

PART_NAME
 PC571 'Q_CAP_C0805-22UF,16V,20%,X6S,CH6223MEA00':;

SECTION_NUMBER 1
 '@T6G_MB_LIB.T6G(SCH_1):PAGE252_I114@PURE_QUANTA.Q_CAP(CHIPS)':
 C_PATH='@t6g_mb_lib.t6g(sch_1):page252_i114@pure_quanta.q_cap(chips)';

PART_NAME
 PC570 'Q_CAP_C0805-22UF,16V,20%,X6S,CH6223MEA00':;

SECTION_NUMBER 1
 '@T6G_MB_LIB.T6G(SCH_1):PAGE252_I115@PURE_QUANTA.Q_CAP(CHIPS)':
 C_PATH='@t6g_mb_lib.t6g(sch_1):page252_i115@pure_quanta.q_cap(chips)';

PART_NAME
 PC569 'Q_CAP_0402-10PF,50V,1%,NPO,TMP_QCH0106F0B00':;

SECTION_NUMBER 1
 '@T6G_MB_LIB.T6G(SCH_1):PAGE252_I99@PURE_QUANTA.Q_CAP(CHIPS)':
 C_PATH='@t6g_mb_lib.t6g(sch_1):page252_i99@pure_quanta.q_cap(chips)';

PART_NAME
 PC568 'Q_CAP_0402-0.22UF,16V,10%,X7R,CH4223K1B00':;

SECTION_NUMBER 1
 '@T6G_MB_LIB.T6G(SCH_1):PAGE252_I107@PURE_QUANTA.Q_CAP(CHIPS)':
 C_PATH='@t6g_mb_lib.t6g(sch_1):page252_i107@pure_quanta.q_cap(chips)';

PART_NAME
 PC567 'Q_CAP_C0805-22UF,16V,20%,X6S,CH6223MEA00':;

SECTION_NUMBER 1
 '@T6G_MB_LIB.T6G(SCH_1):PAGE252_I117@PURE_QUANTA.Q_CAP(CHIPS)':
 C_PATH='@t6g_mb_lib.t6g(sch_1):page252_i117@pure_quanta.q_cap(chips)';

PART_NAME
 PC566 'Q_CAPP_SMLF-100UF,16V,20%,OSCON,CC71003MZ32':
;

SECTION_NUMBER 1
 '@T6G_MB_LIB.T6G(SCH_1):PAGE252_I127@PURE_QUANTA.Q_CAPP(CHIPS)':
 C_PATH='@t6g_mb_lib.t6g(sch_1):page252_i127@pure_quanta.q_capp(chips)';

PART_NAME
 PC71 'Q_CAP_C0805-22UF,16V,20%,X6S,CH6223MEA00':;

SECTION_NUMBER 1
 '@T6G_MB_LIB.T6G(SCH_1):PAGE252_I148@PURE_QUANTA.Q_CAP(CHIPS)':
 C_PATH='@t6g_mb_lib.t6g(sch_1):page252_i148@pure_quanta.q_cap(chips)';

PART_NAME
 C710 'Q_CAP_C0805-22UF,10V,20%,X6S,CH6222MEA00':;

SECTION_NUMBER 1
 '@T6G_MB_LIB.T6G(SCH_1):PAGE252_I144@PURE_QUANTA.Q_CAP(CHIPS)':
 C_PATH='@t6g_mb_lib.t6g(sch_1):page252_i144@pure_quanta.q_cap(chips)';

PART_NAME
 C709 'Q_CAP_C0805-22UF,10V,20%,X6S,CH6222MEA00':;

SECTION_NUMBER 1
 '@T6G_MB_LIB.T6G(SCH_1):PAGE252_I143@PURE_QUANTA.Q_CAP(CHIPS)':
 C_PATH='@t6g_mb_lib.t6g(sch_1):page252_i143@pure_quanta.q_cap(chips)';

PART_NAME
 U37 'SN65LVPE502ARGER-SN65LVPE502ARGER,SMLF,IC,AL000502005':;

SECTION_NUMBER 1
 '@T6G_MB_LIB.T6G(SCH_1):PAGE269_I73@PURE_QUANTA.SN65LVPE502ARGER(CHIPS)':
 C_PATH='@t6g_mb_lib.t6g(sch_1):page269_i73@pure_quanta.sn65lvpe502arger(chips)';

PART_NAME
 U36 'SN65LVPE502ARGER-SN65LVPE502ARGER,SMLF,IC,AL000502005':;

SECTION_NUMBER 1
 '@T6G_MB_LIB.T6G(SCH_1):PAGE269_I86@PURE_QUANTA.SN65LVPE502ARGER(CHIPS)':
 C_PATH='@t6g_mb_lib.t6g(sch_1):page269_i86@pure_quanta.sn65lvpe502arger(chips)';

PART_NAME
 R1066 'Q_RES_0402LF-10K,5%,1/16W,CHIP,TMP_QCS31002JB28':;

SECTION_NUMBER 1
 '@T6G_MB_LIB.T6G(SCH_1):PAGE269_I71@PURE_QUANTA.Q_RES(CHIPS)':
 C_PATH='@t6g_mb_lib.t6g(sch_1):page269_i71@pure_quanta.q_res(chips)';

PART_NAME
 R1065 'Q_RES_0402LF-10K,5%,1/16W,CHIP,TMP_QCS31002JB28':;

SECTION_NUMBER 1
 '@T6G_MB_LIB.T6G(SCH_1):PAGE269_I83@PURE_QUANTA.Q_RES(CHIPS)':
 C_PATH='@t6g_mb_lib.t6g(sch_1):page269_i83@pure_quanta.q_res(chips)';

PART_NAME
 R1064 'Q_RES_0402LF-4.7K,5%,1/16W,EMPTY,TMP_QCS24702JB38':;

SECTION_NUMBER 1
 '@T6G_MB_LIB.T6G(SCH_1):PAGE269_I25@PURE_QUANTA.Q_RES(CHIPS)':
 C_PATH='@t6g_mb_lib.t6g(sch_1):page269_i25@pure_quanta.q_res(chips)';

PART_NAME
 R1063 'Q_RES_0402LF-4.7K,5%,1/16W,EMPTY,TMP_QCS24702JB38':;

SECTION_NUMBER 1
 '@T6G_MB_LIB.T6G(SCH_1):PAGE269_I28@PURE_QUANTA.Q_RES(CHIPS)':
 C_PATH='@t6g_mb_lib.t6g(sch_1):page269_i28@pure_quanta.q_res(chips)';

PART_NAME
 R1062 'Q_RES_0402LF-4.7K,5%,1/16W,EMPTY,TMP_QCS24702JB38':;

SECTION_NUMBER 1
 '@T6G_MB_LIB.T6G(SCH_1):PAGE269_I45@PURE_QUANTA.Q_RES(CHIPS)':
 C_PATH='@t6g_mb_lib.t6g(sch_1):page269_i45@pure_quanta.q_res(chips)';

PART_NAME
 R1061 'Q_RES_0402LF-4.7K,5%,1/16W,EMPTY,TMP_QCS24702JB38':;

SECTION_NUMBER 1
 '@T6G_MB_LIB.T6G(SCH_1):PAGE269_I48@PURE_QUANTA.Q_RES(CHIPS)':
 C_PATH='@t6g_mb_lib.t6g(sch_1):page269_i48@pure_quanta.q_res(chips)';

PART_NAME
 R1060 'Q_RES_0402LF-4.7K,5%,1/16W,EMPTY,TMP_QCS24702JB38':;

SECTION_NUMBER 1
 '@T6G_MB_LIB.T6G(SCH_1):PAGE269_I24@PURE_QUANTA.Q_RES(CHIPS)':
 C_PATH='@t6g_mb_lib.t6g(sch_1):page269_i24@pure_quanta.q_res(chips)';

PART_NAME
 R1059 'Q_RES_0402LF-4.7K,5%,1/16W,EMPTY,TMP_QCS24702JB38':;

SECTION_NUMBER 1
 '@T6G_MB_LIB.T6G(SCH_1):PAGE269_I27@PURE_QUANTA.Q_RES(CHIPS)':
 C_PATH='@t6g_mb_lib.t6g(sch_1):page269_i27@pure_quanta.q_res(chips)';

PART_NAME
 R1058 'Q_RES_0402LF-4.7K,5%,1/16W,EMPTY,TMP_QCS24702JB38':;

SECTION_NUMBER 1
 '@T6G_MB_LIB.T6G(SCH_1):PAGE269_I44@PURE_QUANTA.Q_RES(CHIPS)':
 C_PATH='@t6g_mb_lib.t6g(sch_1):page269_i44@pure_quanta.q_res(chips)';

PART_NAME
 R1057 'Q_RES_0402LF-4.7K,5%,1/16W,EMPTY,TMP_QCS24702JB38':;

SECTION_NUMBER 1
 '@T6G_MB_LIB.T6G(SCH_1):PAGE269_I47@PURE_QUANTA.Q_RES(CHIPS)':
 C_PATH='@t6g_mb_lib.t6g(sch_1):page269_i47@pure_quanta.q_res(chips)';

PART_NAME
 R1056 'Q_RES_0402LF-4.7K,5%,1/16W,EMPTY,TMP_QCS24702JB38':;

SECTION_NUMBER 1
 '@T6G_MB_LIB.T6G(SCH_1):PAGE269_I23@PURE_QUANTA.Q_RES(CHIPS)':
 C_PATH='@t6g_mb_lib.t6g(sch_1):page269_i23@pure_quanta.q_res(chips)';

PART_NAME
 R1055 'Q_RES_0402LF-4.7K,5%,1/16W,EMPTY,TMP_QCS24702JB38':;

SECTION_NUMBER 1
 '@T6G_MB_LIB.T6G(SCH_1):PAGE269_I26@PURE_QUANTA.Q_RES(CHIPS)':
 C_PATH='@t6g_mb_lib.t6g(sch_1):page269_i26@pure_quanta.q_res(chips)';

PART_NAME
 R1054 'Q_RES_0402LF-4.7K,5%,1/16W,EMPTY,TMP_QCS24702JB38':;

SECTION_NUMBER 1
 '@T6G_MB_LIB.T6G(SCH_1):PAGE269_I43@PURE_QUANTA.Q_RES(CHIPS)':
 C_PATH='@t6g_mb_lib.t6g(sch_1):page269_i43@pure_quanta.q_res(chips)';

PART_NAME
 R1053 'Q_RES_0402LF-4.7K,5%,1/16W,EMPTY,TMP_QCS24702JB38':;

SECTION_NUMBER 1
 '@T6G_MB_LIB.T6G(SCH_1):PAGE269_I46@PURE_QUANTA.Q_RES(CHIPS)':
 C_PATH='@t6g_mb_lib.t6g(sch_1):page269_i46@pure_quanta.q_res(chips)';

PART_NAME
 R1052 'Q_RES_0402LF-4.7K,5%,1/16W,EMPTY,TMP_QCS24702JB38':;

SECTION_NUMBER 1
 '@T6G_MB_LIB.T6G(SCH_1):PAGE269_I18@PURE_QUANTA.Q_RES(CHIPS)':
 C_PATH='@t6g_mb_lib.t6g(sch_1):page269_i18@pure_quanta.q_res(chips)';

PART_NAME
 R1051 'Q_RES_0402LF-4.7K,5%,1/16W,EMPTY,TMP_QCS24702JB38':;

SECTION_NUMBER 1
 '@T6G_MB_LIB.T6G(SCH_1):PAGE269_I22@PURE_QUANTA.Q_RES(CHIPS)':
 C_PATH='@t6g_mb_lib.t6g(sch_1):page269_i22@pure_quanta.q_res(chips)';

PART_NAME
 R1050 'Q_RES_0402LF-4.7K,5%,1/16W,EMPTY,TMP_QCS24702JB38':;

SECTION_NUMBER 1
 '@T6G_MB_LIB.T6G(SCH_1):PAGE269_I38@PURE_QUANTA.Q_RES(CHIPS)':
 C_PATH='@t6g_mb_lib.t6g(sch_1):page269_i38@pure_quanta.q_res(chips)';

PART_NAME
 R1049 'Q_RES_0402LF-4.7K,5%,1/16W,EMPTY,TMP_QCS24702JB38':;

SECTION_NUMBER 1
 '@T6G_MB_LIB.T6G(SCH_1):PAGE269_I41@PURE_QUANTA.Q_RES(CHIPS)':
 C_PATH='@t6g_mb_lib.t6g(sch_1):page269_i41@pure_quanta.q_res(chips)';

PART_NAME
 R1048 'Q_RES_0402LF-4.7K,5%,1/16W,EMPTY,TMP_QCS24702JB38':;

SECTION_NUMBER 1
 '@T6G_MB_LIB.T6G(SCH_1):PAGE269_I17@PURE_QUANTA.Q_RES(CHIPS)':
 C_PATH='@t6g_mb_lib.t6g(sch_1):page269_i17@pure_quanta.q_res(chips)';

PART_NAME
 R1047 'Q_RES_0402LF-4.7K,5%,1/16W,EMPTY,TMP_QCS24702JB38':;

SECTION_NUMBER 1
 '@T6G_MB_LIB.T6G(SCH_1):PAGE269_I21@PURE_QUANTA.Q_RES(CHIPS)':
 C_PATH='@t6g_mb_lib.t6g(sch_1):page269_i21@pure_quanta.q_res(chips)';

PART_NAME
 R1046 'Q_RES_0402LF-4.7K,5%,1/16W,EMPTY,TMP_QCS24702JB38':;

SECTION_NUMBER 1
 '@T6G_MB_LIB.T6G(SCH_1):PAGE269_I37@PURE_QUANTA.Q_RES(CHIPS)':
 C_PATH='@t6g_mb_lib.t6g(sch_1):page269_i37@pure_quanta.q_res(chips)';

PART_NAME
 R1045 'Q_RES_0402LF-4.7K,5%,1/16W,EMPTY,TMP_QCS24702JB38':;

SECTION_NUMBER 1
 '@T6G_MB_LIB.T6G(SCH_1):PAGE269_I40@PURE_QUANTA.Q_RES(CHIPS)':
 C_PATH='@t6g_mb_lib.t6g(sch_1):page269_i40@pure_quanta.q_res(chips)';

PART_NAME
 R1044 'Q_RES_0402LF-4.7K,5%,1/16W,EMPTY,TMP_QCS24702JB38':;

SECTION_NUMBER 1
 '@T6G_MB_LIB.T6G(SCH_1):PAGE269_I16@PURE_QUANTA.Q_RES(CHIPS)':
 C_PATH='@t6g_mb_lib.t6g(sch_1):page269_i16@pure_quanta.q_res(chips)';

PART_NAME
 R1043 'Q_RES_0402LF-4.7K,5%,1/16W,EMPTY,TMP_QCS24702JB38':;

SECTION_NUMBER 1
 '@T6G_MB_LIB.T6G(SCH_1):PAGE269_I19@PURE_QUANTA.Q_RES(CHIPS)':
 C_PATH='@t6g_mb_lib.t6g(sch_1):page269_i19@pure_quanta.q_res(chips)';

PART_NAME
 R1042 'Q_RES_0402LF-4.7K,5%,1/16W,EMPTY,TMP_QCS24702JB38':;

SECTION_NUMBER 1
 '@T6G_MB_LIB.T6G(SCH_1):PAGE269_I36@PURE_QUANTA.Q_RES(CHIPS)':
 C_PATH='@t6g_mb_lib.t6g(sch_1):page269_i36@pure_quanta.q_res(chips)';

PART_NAME
 R1041 'Q_RES_0402LF-4.7K,5%,1/16W,EMPTY,TMP_QCS24702JB38':;

SECTION_NUMBER 1
 '@T6G_MB_LIB.T6G(SCH_1):PAGE269_I39@PURE_QUANTA.Q_RES(CHIPS)':
 C_PATH='@t6g_mb_lib.t6g(sch_1):page269_i39@pure_quanta.q_res(chips)';

PART_NAME
 C2814 'Q_CAP_0402-0.1UF,25V,10%,X7R,CH4104K1B00':;

SECTION_NUMBER 1
 '@T6G_MB_LIB.T6G(SCH_1):PAGE269_I142@PURE_QUANTA.Q_CAP(CHIPS)':
 C_PATH='@t6g_mb_lib.t6g(sch_1):page269_i142@pure_quanta.q_cap(chips)';

PART_NAME
 C2813 'Q_CAP_0402-0.1UF,25V,10%,X7R,CH4104K1B00':;

SECTION_NUMBER 1
 '@T6G_MB_LIB.T6G(SCH_1):PAGE269_I141@PURE_QUANTA.Q_CAP(CHIPS)':
 C_PATH='@t6g_mb_lib.t6g(sch_1):page269_i141@pure_quanta.q_cap(chips)';

PART_NAME
 C2812 'Q_CAP_0402-0.1UF,25V,10%,X7R,CH4104K1B00':;

SECTION_NUMBER 1
 '@T6G_MB_LIB.T6G(SCH_1):PAGE269_I136@PURE_QUANTA.Q_CAP(CHIPS)':
 C_PATH='@t6g_mb_lib.t6g(sch_1):page269_i136@pure_quanta.q_cap(chips)';

PART_NAME
 C2811 'Q_CAP_0402-0.1UF,25V,10%,X7R,CH4104K1B00':;

SECTION_NUMBER 1
 '@T6G_MB_LIB.T6G(SCH_1):PAGE269_I137@PURE_QUANTA.Q_CAP(CHIPS)':
 C_PATH='@t6g_mb_lib.t6g(sch_1):page269_i137@pure_quanta.q_cap(chips)';

PART_NAME
 C714 'Q_CAP_C0402-100NF,50V,10%,X7R,CH4106K1B01':;

SECTION_NUMBER 1
 '@T6G_MB_LIB.T6G(SCH_1):PAGE269_I128@PURE_QUANTA.Q_CAP(CHIPS)':
 C_PATH='@t6g_mb_lib.t6g(sch_1):page269_i128@pure_quanta.q_cap(chips)';

PART_NAME
 C713 'Q_CAP_C0402-100NF,50V,10%,X7R,CH4106K1B01':;

SECTION_NUMBER 1
 '@T6G_MB_LIB.T6G(SCH_1):PAGE269_I129@PURE_QUANTA.Q_CAP(CHIPS)':
 C_PATH='@t6g_mb_lib.t6g(sch_1):page269_i129@pure_quanta.q_cap(chips)';

PART_NAME
 C712 'Q_CAP_C0402-100NF,50V,10%,X7R,CH4106K1B01':;

SECTION_NUMBER 1
 '@T6G_MB_LIB.T6G(SCH_1):PAGE269_I123@PURE_QUANTA.Q_CAP(CHIPS)':
 C_PATH='@t6g_mb_lib.t6g(sch_1):page269_i123@pure_quanta.q_cap(chips)';

PART_NAME
 C711 'Q_CAP_C0402-100NF,50V,10%,X7R,CH4106K1B01':;

SECTION_NUMBER 1
 '@T6G_MB_LIB.T6G(SCH_1):PAGE269_I122@PURE_QUANTA.Q_CAP(CHIPS)':
 C_PATH='@t6g_mb_lib.t6g(sch_1):page269_i122@pure_quanta.q_cap(chips)';

PART_NAME
 C703 'Q_CAP_C0402-100NF,50V,10%,X7R,CH4106K1B01':
;

SECTION_NUMBER 1
 '@T6G_MB_LIB.T6G(SCH_1):PAGE269_I100@PURE_QUANTA.Q_CAP(CHIPS)':
 C_PATH='@t6g_mb_lib.t6g(sch_1):page269_i100@pure_quanta.q_cap(chips)';

PART_NAME
 C702 'Q_CAP_C0402-100NF,50V,10%,X7R,CH4106K1B01':
;

SECTION_NUMBER 1
 '@T6G_MB_LIB.T6G(SCH_1):PAGE269_I109@PURE_QUANTA.Q_CAP(CHIPS)':
 C_PATH='@t6g_mb_lib.t6g(sch_1):page269_i109@pure_quanta.q_cap(chips)';

PART_NAME
 C701 'Q_CAP_C0402-100NF,50V,10%,X7R,CH4106K1B01':
;

SECTION_NUMBER 1
 '@T6G_MB_LIB.T6G(SCH_1):PAGE269_I90@PURE_QUANTA.Q_CAP(CHIPS)':
 C_PATH='@t6g_mb_lib.t6g(sch_1):page269_i90@pure_quanta.q_cap(chips)';

PART_NAME
 C700 'Q_CAP_C0402-100NF,50V,10%,X7R,CH4106K1B01':
;

SECTION_NUMBER 1
 '@T6G_MB_LIB.T6G(SCH_1):PAGE269_I88@PURE_QUANTA.Q_CAP(CHIPS)':
 C_PATH='@t6g_mb_lib.t6g(sch_1):page269_i88@pure_quanta.q_cap(chips)';

PART_NAME
 U185 'SLG55221120010VTR-SLG55221-120010VTR,SMLF,IC,AL055221001':;

SECTION_NUMBER 1
 '@T6G_MB_LIB.T6G(SCH_1):PAGE283_I59@PURE_QUANTA.SLG55221120010VTR(CHIPS)':
 C_PATH='@s6q_mb_lib.s6q(sch_1):page283_i59@pure_quanta.slg55221120010vtr(chips)~
';

PART_NAME
 U184 'RT9818C44GV-RT9818C-44GV,SMLF,IC,AL009818001':;

SECTION_NUMBER 1
 '@T6G_MB_LIB.T6G(SCH_1):PAGE283_I6@PURE_QUANTA.RT9818C44GV(CHIPS)':
 C_PATH='@t6g_mb_lib.t6g(sch_1):page283_i6@pure_quanta.rt9818c44gv(chips)';

PART_NAME
 R2116 'Q_RES_0402LF-20K,5%,1/16W,CHIP,TMP_QCS32002JB12':;

SECTION_NUMBER 1
 '@T6G_MB_LIB.T6G(SCH_1):PAGE283_I42@PURE_QUANTA.Q_RES(CHIPS)':
 C_PATH='@t6g_mb_lib.t6g(sch_1):page283_i42@pure_quanta.q_res(chips)';

PART_NAME
 R2115 'Q_RES_0402LF-10K,5%,1/16W,CHIP,TMP_QCS31002JB28':;

SECTION_NUMBER 1
 '@T6G_MB_LIB.T6G(SCH_1):PAGE283_I45@PURE_QUANTA.Q_RES(CHIPS)':
 C_PATH='@t6g_mb_lib.t6g(sch_1):page283_i45@pure_quanta.q_res(chips)';

PART_NAME
 R1260 'Q_RES_0402LF-10K,5%,1/16W,CHIP,TMP_QCS31002JB28':
;

SECTION_NUMBER 1
 '@T6G_MB_LIB.T6G(SCH_1):PAGE283_I24@PURE_QUANTA.Q_RES(CHIPS)':
 C_PATH='@t6g_mb_lib.t6g(sch_1):page283_i24@pure_quanta.q_res(chips)';

PART_NAME
 R1256 'Q_RES_0402LF-0,5%,1/16W,CHIP,CS00002JB38':;

SECTION_NUMBER 1
 '@T6G_MB_LIB.T6G(SCH_1):PAGE283_I8@PURE_QUANTA.Q_RES(CHIPS)':
 C_PATH='@t6g_mb_lib.t6g(sch_1):page283_i8@pure_quanta.q_res(chips)';

PART_NAME
 R1030 'Q_RES_0402LF-4.7K,5%,1/16W,EMPTY,TMP_QCS24702JB38':;

SECTION_NUMBER 1
 '@T6G_MB_LIB.T6G(SCH_1):PAGE283_I51@PURE_QUANTA.Q_RES(CHIPS)':
 C_PATH='@t6g_mb_lib.t6g(sch_1):page283_i51@pure_quanta.q_res(chips)';

PART_NAME
 R1029 'Q_RES_0402LF-1K,5%,1/16W,CHIP,TMP_QCS21002JB34':
;

SECTION_NUMBER 1
 '@T6G_MB_LIB.T6G(SCH_1):PAGE283_I32@PURE_QUANTA.Q_RES(CHIPS)':
 C_PATH='@t6g_mb_lib.t6g(sch_1):page283_i32@pure_quanta.q_res(chips)';

PART_NAME
 R1028 'Q_RES_0402LF-10K,5%,1/16W,CHIP,TMP_QCS31002JB28':;

SECTION_NUMBER 1
 '@T6G_MB_LIB.T6G(SCH_1):PAGE283_I13@PURE_QUANTA.Q_RES(CHIPS)':
 C_PATH='@t6g_mb_lib.t6g(sch_1):page283_i13@pure_quanta.q_res(chips)';

PART_NAME
 R1027 'Q_RES_0402LF-100K,5%,1/16W,CHIP,CS41002JB20':
;

SECTION_NUMBER 1
 '@T6G_MB_LIB.T6G(SCH_1):PAGE283_I11@PURE_QUANTA.Q_RES(CHIPS)':
 C_PATH='@t6g_mb_lib.t6g(sch_1):page283_i11@pure_quanta.q_res(chips)';

PART_NAME
 R1026 'Q_RES_0402LF-0,5%,1/16W,EMPTY,CS00002JB38':;

SECTION_NUMBER 1
 '@T6G_MB_LIB.T6G(SCH_1):PAGE283_I7@PURE_QUANTA.Q_RES(CHIPS)':
 C_PATH='@t6g_mb_lib.t6g(sch_1):page283_i7@pure_quanta.q_res(chips)';

PART_NAME
 Q54 'MOSFET_NCH_1D3S-PSMNR51-25YLH,SMLF,IC,BAMNR510000':;

SECTION_NUMBER 1
 '@T6G_MB_LIB.T6G(SCH_1):PAGE283_I64@PURE_QUANTA.MOSFET_NCH_1D3S(CHIPS)':
 C_PATH='@t6g_mb_lib.t6g(sch_1):page283_i64@pure_quanta.mosfet_nch_1d3s(chips)';

PART_NAME
 Q53 'MOSFET_NCH_1D3S-PSMNR51-25YLH,SMLF,IC,BAMNR510000':;

SECTION_NUMBER 1
 '@T6G_MB_LIB.T6G(SCH_1):PAGE283_I63@PURE_QUANTA.MOSFET_NCH_1D3S(CHIPS)':
 C_PATH='@t6g_mb_lib.t6g(sch_1):page283_i63@pure_quanta.mosfet_nch_1d3s(chips)';

PART_NAME
 Q29 'MOSFET_NCH_DUAL-2N7002KDW,SMLF,IC,BAM70020047':;

SECTION_NUMBER 1
 '@T6G_MB_LIB.T6G(SCH_1):PAGE283_I10@PURE_QUANTA.MOSFET_NCH_DUAL(CHIPS)':
 C_PATH='@t6g_mb_lib.t6g(sch_1):page283_i10@pure_quanta.mosfet_nch_dual(chips)';

SECTION_NUMBER 2
 '@T6G_MB_LIB.T6G(SCH_1):PAGE259_I3@PURE_QUANTA.MOSFET_NCH_DUAL(CHIPS)':
 C_PATH='@t6g_mb_lib.t6g(sch_1):page259_i3@pure_quanta.mosfet_nch_dual(chips)';

PART_NAME
 Q27 'MOSFET_NCH_DUAL-2N7002KDW,SMLF,IC,BAM70020047':;

SECTION_NUMBER 1
 '@T6G_MB_LIB.T6G(SCH_1):PAGE259_I6@PURE_QUANTA.MOSFET_NCH_DUAL(CHIPS)':
 C_PATH='@t6g_mb_lib.t6g(sch_1):page259_i6@pure_quanta.mosfet_nch_dual(chips)';

SECTION_NUMBER 2
 '@T6G_MB_LIB.T6G(SCH_1):PAGE283_I18@PURE_QUANTA.MOSFET_NCH_DUAL(CHIPS)':
 C_PATH='@t6g_mb_lib.t6g(sch_1):page283_i18@pure_quanta.mosfet_nch_dual(chips)';

PART_NAME
 D5 'BAT547F-BAT547F,SMLF,IC,BC0BAT54Z53':;

SECTION_NUMBER 1
 '@T6G_MB_LIB.T6G(SCH_1):PAGE283_I15@PURE_QUANTA.BAT547F(CHIPS)':
 C_PATH='@t6g_mb_lib.t6g(sch_1):page283_i15@pure_quanta.bat547f(chips)';

PART_NAME
 C4027 'Q_CAP_C0402-100NF,50V,10%,X7R,CH4106K1B01':;

SECTION_NUMBER 1
 '@T6G_MB_LIB.T6G(SCH_1):PAGE283_I44@PURE_QUANTA.Q_CAP(CHIPS)':
 C_PATH='@t6g_mb_lib.t6g(sch_1):page283_i44@pure_quanta.q_cap(chips)';

PART_NAME
 C2542 'Q_CAP_C0805-10UF,16V,10%,X6S,CH6103KEA00':;

SECTION_NUMBER 1
 '@T6G_MB_LIB.T6G(SCH_1):PAGE283_I56@PURE_QUANTA.Q_CAP(CHIPS)':
 C_PATH='@t6g_mb_lib.t6g(sch_1):page283_i56@pure_quanta.q_cap(chips)';

PART_NAME
 C2541 'Q_CAP_C0402-100NF,50V,10%,X7R,CH4106K1B01':;

SECTION_NUMBER 1
 '@T6G_MB_LIB.T6G(SCH_1):PAGE283_I55@PURE_QUANTA.Q_CAP(CHIPS)':
 C_PATH='@t6g_mb_lib.t6g(sch_1):page283_i55@pure_quanta.q_cap(chips)';

PART_NAME
 C2540 'Q_CAP_C0805-10UF,16V,10%,X6S,CH6103KEA00':
;

SECTION_NUMBER 1
 '@T6G_MB_LIB.T6G(SCH_1):PAGE283_I37@PURE_QUANTA.Q_CAP(CHIPS)':
 C_PATH='@t6g_mb_lib.t6g(sch_1):page283_i37@pure_quanta.q_cap(chips)';

PART_NAME
 C2539 'Q_CAP_0402-0.22UF,16V,10%,X7R,CH4223K1B00':;

SECTION_NUMBER 1
 '@T6G_MB_LIB.T6G(SCH_1):PAGE283_I61@PURE_QUANTA.Q_CAP(CHIPS)':
 C_PATH='@t6g_mb_lib.t6g(sch_1):page283_i61@pure_quanta.q_cap(chips)';

PART_NAME
 C2538 'Q_CAP_C0805-10UF,16V,10%,X6S,CH6103KEA00':
;

SECTION_NUMBER 1
 '@T6G_MB_LIB.T6G(SCH_1):PAGE283_I28@PURE_QUANTA.Q_CAP(CHIPS)':
 C_PATH='@t6g_mb_lib.t6g(sch_1):page283_i28@pure_quanta.q_cap(chips)';

PART_NAME
 C1887 'Q_CAP_C0402-100NF,50V,10%,X7R,CH4106K1B01':;

SECTION_NUMBER 1
 '@T6G_MB_LIB.T6G(SCH_1):PAGE283_I4@PURE_QUANTA.Q_CAP(CHIPS)':
 C_PATH='@t6g_mb_lib.t6g(sch_1):page283_i4@pure_quanta.q_cap(chips)';

PART_NAME
 C1886 'Q_CAP_C0402-100NF,50V,10%,X7R,CH4106K1B01':
;

SECTION_NUMBER 1
 '@T6G_MB_LIB.T6G(SCH_1):PAGE283_I22@PURE_QUANTA.Q_CAP(CHIPS)':
 C_PATH='@t6g_mb_lib.t6g(sch_1):page283_i22@pure_quanta.q_cap(chips)';

PART_NAME
 C655 'Q_CAP_C0805-10UF,16V,10%,EMPTY,CH6103KEA00':;

SECTION_NUMBER 1
 '@T6G_MB_LIB.T6G(SCH_1):PAGE283_I48@PURE_QUANTA.Q_CAP(CHIPS)':
 C_PATH='@t6g_mb_lib.t6g(sch_1):page283_i48@pure_quanta.q_cap(chips)';

PART_NAME
 C653 'Q_CAP_C0805-10UF,16V,10%,X6S,CH6103KEA00':;

SECTION_NUMBER 1
 '@T6G_MB_LIB.T6G(SCH_1):PAGE283_I46@PURE_QUANTA.Q_CAP(CHIPS)':
 C_PATH='@t6g_mb_lib.t6g(sch_1):page283_i46@pure_quanta.q_cap(chips)';

PART_NAME
 C652 'Q_CAP_C0402-100NF,50V,10%,X7R,CH4106K1B01':
;

SECTION_NUMBER 1
 '@T6G_MB_LIB.T6G(SCH_1):PAGE283_I36@PURE_QUANTA.Q_CAP(CHIPS)':
 C_PATH='@t6g_mb_lib.t6g(sch_1):page283_i36@pure_quanta.q_cap(chips)';

PART_NAME
 C651 'Q_CAP_C0805-10UF,16V,10%,EMPTY,CH6103KEA00':
;

SECTION_NUMBER 1
 '@T6G_MB_LIB.T6G(SCH_1):PAGE283_I30@PURE_QUANTA.Q_CAP(CHIPS)':
 C_PATH='@t6g_mb_lib.t6g(sch_1):page283_i30@pure_quanta.q_cap(chips)';

PART_NAME
 C650 'Q_CAP_C0402-100NF,50V,10%,X7R,CH4106K1B01':
;

SECTION_NUMBER 1
 '@T6G_MB_LIB.T6G(SCH_1):PAGE283_I27@PURE_QUANTA.Q_CAP(CHIPS)':
 C_PATH='@t6g_mb_lib.t6g(sch_1):page283_i27@pure_quanta.q_cap(chips)';

PART_NAME
 U79 'MOSFET_NCH_GDS_ESD_PROTECTED-2N7002K,SMLF,EMPTY,BAM70020002':;

SECTION_NUMBER 1
 '@T6G_MB_LIB.T6G(SCH_1):PAGE258_I88@PURE_QUANTA.MOSFET_NCH_GDS_ESD_PROTECTED(CHIPS)':
 C_PATH='@t6g_mb_lib.t6g(sch_1):page258_i88@pure_quanta.mosfet_nch_gds_esd_prote~
cted(chips)';

PART_NAME
 R2672 'Q_RES_0402LF-1K,5%,1/16W,CHIP,TMP_QCS21002JB34':;

SECTION_NUMBER 1
 '@T6G_MB_LIB.T6G(SCH_1):PAGE258_I89@PURE_QUANTA.Q_RES(CHIPS)':
 C_PATH='@t6g_mb_lib.t6g(sch_1):page258_i89@pure_quanta.q_res(chips)';

PART_NAME
 R2392 'Q_RES_0402LF-0,5%,1/16W,CHIP,CS00002JB38':;

SECTION_NUMBER 1
 '@T6G_MB_LIB.T6G(SCH_1):PAGE258_I86@PURE_QUANTA.Q_RES(CHIPS)':
 C_PATH='@t6g_mb_lib.t6g(sch_1):page258_i86@pure_quanta.q_res(chips)';

PART_NAME
 R1301 'Q_RES_0402LF-0,5%,1/16W,EMPTY,CS00002JB38':;

SECTION_NUMBER 1
 '@T6G_MB_LIB.T6G(SCH_1):PAGE258_I85@PURE_QUANTA.Q_RES(CHIPS)':
 C_PATH='@t6g_mb_lib.t6g(sch_1):page258_i85@pure_quanta.q_res(chips)';

PART_NAME
 R1297 'Q_RES_0402LF-0,5%,1/16W,CHIP,CS00002JB38':;

SECTION_NUMBER 1
 '@T6G_MB_LIB.T6G(SCH_1):PAGE258_I70@PURE_QUANTA.Q_RES(CHIPS)':
 C_PATH='@t6g_mb_lib.t6g(sch_1):page258_i70@pure_quanta.q_res(chips)';

PART_NAME
 R1022 'Q_RES_0402LF-47K,5%,1/16W,CHIP,TMP_QCS34702JB21':;

SECTION_NUMBER 1
 '@T6G_MB_LIB.T6G(SCH_1):PAGE258_I97@PURE_QUANTA.Q_RES(CHIPS)':
 C_PATH='@t6g_mb_lib.t6g(sch_1):page258_i97@pure_quanta.q_res(chips)';

PART_NAME
 R1021 'Q_RES_0402LF-1K,5%,1/16W,EMPTY,TMP_QCS21002JB34':;

SECTION_NUMBER 1
 '@T6G_MB_LIB.T6G(SCH_1):PAGE258_I81@PURE_QUANTA.Q_RES(CHIPS)':
 C_PATH='@t6g_mb_lib.t6g(sch_1):page258_i81@pure_quanta.q_res(chips)';

PART_NAME
 R1020 'Q_RES_0402LF-100K,5%,1/16W,CHIP,CS41002JB20':;

SECTION_NUMBER 1
 '@T6G_MB_LIB.T6G(SCH_1):PAGE258_I71@PURE_QUANTA.Q_RES(CHIPS)':
 C_PATH='@t6g_mb_lib.t6g(sch_1):page258_i71@pure_quanta.q_res(chips)';

PART_NAME
 R138 'Q_RES_0402LF-47K,5%,1/16W,CHIP,TMP_QCS34702JB21':;

SECTION_NUMBER 1
 '@T6G_MB_LIB.T6G(SCH_1):PAGE258_I93@PURE_QUANTA.Q_RES(CHIPS)':
 C_PATH='@t6g_mb_lib.t6g(sch_1):page258_i93@pure_quanta.q_res(chips)';

PART_NAME
 R137 'Q_RES_0402LF-0,5%,1/16W,CHIP,CS00002JB38':;

SECTION_NUMBER 1
 '@T6G_MB_LIB.T6G(SCH_1):PAGE258_I72@PURE_QUANTA.Q_RES(CHIPS)':
 C_PATH='@t6g_mb_lib.t6g(sch_1):page258_i72@pure_quanta.q_res(chips)';

PART_NAME
 Q84 'MOSFET_PCH_1D3S-AP6681GMT-HF,SMLF,IC,BAM66810004':;

SECTION_NUMBER 1
 '@T6G_MB_LIB.T6G(SCH_1):PAGE258_I96@PURE_QUANTA.MOSFET_PCH_1D3S(CHIPS)':
 C_PATH='@t6g_mb_lib.t6g(sch_1):page258_i96@pure_quanta.mosfet_pch_1d3s(chips)';

PART_NAME
 Q48 'MOSFET_NCH_DUAL-2N7002KDW,SMLF,IC,BAM70020047':;

SECTION_NUMBER 1
 '@T6G_MB_LIB.T6G(SCH_1):PAGE258_I101@PURE_QUANTA.MOSFET_NCH_DUAL(CHIPS)':
 C_PATH='@t6g_mb_lib.t6g(sch_1):page258_i101@pure_quanta.mosfet_nch_dual(chips)';

SECTION_NUMBER 2
 '@T6G_MB_LIB.T6G(SCH_1):PAGE258_I68@PURE_QUANTA.MOSFET_NCH_DUAL(CHIPS)':
 C_PATH='@t6g_mb_lib.t6g(sch_1):page258_i68@pure_quanta.mosfet_nch_dual(chips)';

PART_NAME
 Q26 'MOSFET_PCH_1D3S-AP6681GMT-HF,SMLF,IC,BAM66810004':;

SECTION_NUMBER 1
 '@T6G_MB_LIB.T6G(SCH_1):PAGE258_I74@PURE_QUANTA.MOSFET_PCH_1D3S(CHIPS)':
 C_PATH='@t6g_mb_lib.t6g(sch_1):page258_i74@pure_quanta.mosfet_pch_1d3s(chips)';

PART_NAME
 Q25 'MOSFET_PCH_1D3S-AP6681GMT-HF,SMLF,EMPTY,BAM66810004':;

SECTION_NUMBER 1
 '@T6G_MB_LIB.T6G(SCH_1):PAGE258_I65@PURE_QUANTA.MOSFET_PCH_1D3S(CHIPS)':
 C_PATH='@t6g_mb_lib.t6g(sch_1):page258_i65@pure_quanta.mosfet_pch_1d3s(chips)';

PART_NAME
 D30 'SBR15U30SP513-SBR15U30SP5-13,SMLF,IC,BC15U30SZ00':;

SECTION_NUMBER 1
 '@T6G_MB_LIB.T6G(SCH_1):PAGE258_I78@PURE_QUANTA.SBR15U30SP513(CHIPS)':
 C_PATH='@t6g_mb_lib.t6g(sch_1):page258_i78@pure_quanta.sbr15u30sp513(chips)';

PART_NAME
 D26 'SBR15U30SP513-SBR15U30SP5-13,SMLF,EMPTY,BC15U30SZ00':;

SECTION_NUMBER 1
 '@T6G_MB_LIB.T6G(SCH_1):PAGE258_I75@PURE_QUANTA.SBR15U30SP513(CHIPS)':
 C_PATH='@t6g_mb_lib.t6g(sch_1):page258_i75@pure_quanta.sbr15u30sp513(chips)';

PART_NAME
 D14 'SBR15U30SP513-SBR15U30SP5-13,SMLF,IC,BC15U30SZ00':;

SECTION_NUMBER 1
 '@T6G_MB_LIB.T6G(SCH_1):PAGE258_I76@PURE_QUANTA.SBR15U30SP513(CHIPS)':
 C_PATH='@t6g_mb_lib.t6g(sch_1):page258_i76@pure_quanta.sbr15u30sp513(chips)';

PART_NAME
 C2533 'Q_CAP_0402-100PF,50V,5%,EMPTY,CH11006JB00':;

SECTION_NUMBER 1
 '@T6G_MB_LIB.T6G(SCH_1):PAGE258_I84@PURE_QUANTA.Q_CAP(CHIPS)':
 C_PATH='@t6g_mb_lib.t6g(sch_1):page258_i84@pure_quanta.q_cap(chips)';

PART_NAME
 C2532 'Q_CAP_C0603-10UF,16V,20%,EMPTY,CH6103ME902':;

SECTION_NUMBER 1
 '@T6G_MB_LIB.T6G(SCH_1):PAGE258_I98@PURE_QUANTA.Q_CAP(CHIPS)':
 C_PATH='@t6g_mb_lib.t6g(sch_1):page258_i98@pure_quanta.q_cap(chips)';

PART_NAME
 C2531 'Q_CAP_C0603-10UF,16V,20%,EMPTY,CH6103ME902':;

SECTION_NUMBER 1
 '@T6G_MB_LIB.T6G(SCH_1):PAGE258_I80@PURE_QUANTA.Q_CAP(CHIPS)':
 C_PATH='@t6g_mb_lib.t6g(sch_1):page258_i80@pure_quanta.q_cap(chips)';

PART_NAME
 C649 'Q_CAP_0402-0.1UF,25V,10%,EMPTY,CH4104K1B00':;

SECTION_NUMBER 1
 '@T6G_MB_LIB.T6G(SCH_1):PAGE258_I91@PURE_QUANTA.Q_CAP(CHIPS)':
 C_PATH='@t6g_mb_lib.t6g(sch_1):page258_i91@pure_quanta.q_cap(chips)';

PART_NAME
 R495 'Q_RES_0402LF-100,1%,1/16W,CHIP,CS11002FB07':
;

SECTION_NUMBER 1
 '@T6G_MB_LIB.T6G(SCH_1):PAGE178_I569@PURE_QUANTA.Q_RES(CHIPS)':
 C_PATH='@t6g_mb_lib.t6g(sch_1):page178_i569@pure_quanta.q_res(chips)';

PART_NAME
 C644 'Q_CAP_C0402-0.1UF,16V,10%,X7R,CH4103K1B08':
;

SECTION_NUMBER 1
 '@T6G_MB_LIB.T6G(SCH_1):PAGE178_I702@PURE_QUANTA.Q_CAP(CHIPS)':
 C_PATH='@t6g_mb_lib.t6g(sch_1):page178_i702@pure_quanta.q_cap(chips)';

PART_NAME
 C643 'Q_CAP_C0402-0.1UF,16V,10%,X7R,CH4103K1B08':
;

SECTION_NUMBER 1
 '@T6G_MB_LIB.T6G(SCH_1):PAGE178_I701@PURE_QUANTA.Q_CAP(CHIPS)':
 C_PATH='@t6g_mb_lib.t6g(sch_1):page178_i701@pure_quanta.q_cap(chips)';

PART_NAME
 C640 'Q_CAP_DIFFBUS_C0201-DIFF BUS_0.22UF,6.3V,20%,X6S,SP_CH4221MEE01':;

SECTION_NUMBER 1
 '@T6G_MB_LIB.T6G(SCH_1):PAGE160_I195@PURE_QUANTA.Q_CAP_DIFFBUS(CHIPS)':
 C_PATH='@t6g_mb_lib.t6g(sch_1):page160_i195@pure_quanta.q_cap_diffbus(chips)';

PART_NAME
 C639 'Q_CAP_DIFFBUS_C0201-DIFF BUS_0.22UF,6.3V,20%,X6S,SP_CH4221MEE01':;

SECTION_NUMBER 1
 '@T6G_MB_LIB.T6G(SCH_1):PAGE160_I189@PURE_QUANTA.Q_CAP_DIFFBUS(CHIPS)':
 C_PATH='@t6g_mb_lib.t6g(sch_1):page160_i189@pure_quanta.q_cap_diffbus(chips)';

PART_NAME
 C638 'Q_CAP_DIFFBUS_C0201-DIFF BUS_0.22UF,6.3V,20%,X6S,SP_CH4221MEE01':;

SECTION_NUMBER 1
 '@T6G_MB_LIB.T6G(SCH_1):PAGE160_I188@PURE_QUANTA.Q_CAP_DIFFBUS(CHIPS)':
 C_PATH='@t6g_mb_lib.t6g(sch_1):page160_i188@pure_quanta.q_cap_diffbus(chips)';

PART_NAME
 C637 'Q_CAP_DIFFBUS_C0201-DIFF BUS_0.22UF,6.3V,20%,X6S,SP_CH4221MEE01':;

SECTION_NUMBER 1
 '@T6G_MB_LIB.T6G(SCH_1):PAGE160_I187@PURE_QUANTA.Q_CAP_DIFFBUS(CHIPS)':
 C_PATH='@t6g_mb_lib.t6g(sch_1):page160_i187@pure_quanta.q_cap_diffbus(chips)';

PART_NAME
 C636 'Q_CAP_DIFFBUS_C0201-DIFF BUS_0.22UF,6.3V,20%,X6S,SP_CH4221MEE01':;

SECTION_NUMBER 1
 '@T6G_MB_LIB.T6G(SCH_1):PAGE160_I186@PURE_QUANTA.Q_CAP_DIFFBUS(CHIPS)':
 C_PATH='@t6g_mb_lib.t6g(sch_1):page160_i186@pure_quanta.q_cap_diffbus(chips)';

PART_NAME
 C635 'Q_CAP_DIFFBUS_C0201-DIFF BUS_0.22UF,6.3V,20%,X6S,SP_CH4221MEE01':;

SECTION_NUMBER 1
 '@T6G_MB_LIB.T6G(SCH_1):PAGE160_I185@PURE_QUANTA.Q_CAP_DIFFBUS(CHIPS)':
 C_PATH='@t6g_mb_lib.t6g(sch_1):page160_i185@pure_quanta.q_cap_diffbus(chips)';

PART_NAME
 C634 'Q_CAP_DIFFBUS_C0201-DIFF BUS_0.22UF,6.3V,20%,X6S,SP_CH4221MEE01':;

SECTION_NUMBER 1
 '@T6G_MB_LIB.T6G(SCH_1):PAGE160_I182@PURE_QUANTA.Q_CAP_DIFFBUS(CHIPS)':
 C_PATH='@t6g_mb_lib.t6g(sch_1):page160_i182@pure_quanta.q_cap_diffbus(chips)';

PART_NAME
 C633 'Q_CAP_DIFFBUS_C0201-DIFF BUS_0.22UF,6.3V,20%,X6S,SP_CH4221MEE01':;

SECTION_NUMBER 1
 '@T6G_MB_LIB.T6G(SCH_1):PAGE160_I181@PURE_QUANTA.Q_CAP_DIFFBUS(CHIPS)':
 C_PATH='@t6g_mb_lib.t6g(sch_1):page160_i181@pure_quanta.q_cap_diffbus(chips)';

PART_NAME
 C632 'Q_CAP_DIFFBUS_C0201-DIFF BUS_0.22UF,6.3V,20%,X6S,SP_CH4221MEE01':;

SECTION_NUMBER 1
 '@T6G_MB_LIB.T6G(SCH_1):PAGE160_I196@PURE_QUANTA.Q_CAP_DIFFBUS(CHIPS)':
 C_PATH='@t6g_mb_lib.t6g(sch_1):page160_i196@pure_quanta.q_cap_diffbus(chips)';

PART_NAME
 C631 'Q_CAP_DIFFBUS_C0201-DIFF BUS_0.22UF,6.3V,20%,X6S,SP_CH4221MEE01':;

SECTION_NUMBER 1
 '@T6G_MB_LIB.T6G(SCH_1):PAGE160_I194@PURE_QUANTA.Q_CAP_DIFFBUS(CHIPS)':
 C_PATH='@t6g_mb_lib.t6g(sch_1):page160_i194@pure_quanta.q_cap_diffbus(chips)';

PART_NAME
 C630 'Q_CAP_DIFFBUS_C0201-DIFF BUS_0.22UF,6.3V,20%,X6S,SP_CH4221MEE01':;

SECTION_NUMBER 1
 '@T6G_MB_LIB.T6G(SCH_1):PAGE160_I193@PURE_QUANTA.Q_CAP_DIFFBUS(CHIPS)':
 C_PATH='@t6g_mb_lib.t6g(sch_1):page160_i193@pure_quanta.q_cap_diffbus(chips)';

PART_NAME
 C629 'Q_CAP_DIFFBUS_C0201-DIFF BUS_0.22UF,6.3V,20%,X6S,SP_CH4221MEE01':;

SECTION_NUMBER 1
 '@T6G_MB_LIB.T6G(SCH_1):PAGE160_I192@PURE_QUANTA.Q_CAP_DIFFBUS(CHIPS)':
 C_PATH='@t6g_mb_lib.t6g(sch_1):page160_i192@pure_quanta.q_cap_diffbus(chips)';

PART_NAME
 C628 'Q_CAP_DIFFBUS_C0201-DIFF BUS_0.22UF,6.3V,20%,X6S,SP_CH4221MEE01':;

SECTION_NUMBER 1
 '@T6G_MB_LIB.T6G(SCH_1):PAGE160_I191@PURE_QUANTA.Q_CAP_DIFFBUS(CHIPS)':
 C_PATH='@t6g_mb_lib.t6g(sch_1):page160_i191@pure_quanta.q_cap_diffbus(chips)';

PART_NAME
 C627 'Q_CAP_DIFFBUS_C0201-DIFF BUS_0.22UF,6.3V,20%,X6S,SP_CH4221MEE01':;

SECTION_NUMBER 1
 '@T6G_MB_LIB.T6G(SCH_1):PAGE160_I190@PURE_QUANTA.Q_CAP_DIFFBUS(CHIPS)':
 C_PATH='@t6g_mb_lib.t6g(sch_1):page160_i190@pure_quanta.q_cap_diffbus(chips)';

PART_NAME
 C626 'Q_CAP_DIFFBUS_C0201-DIFF BUS_0.22UF,6.3V,20%,X6S,SP_CH4221MEE01':;

SECTION_NUMBER 1
 '@T6G_MB_LIB.T6G(SCH_1):PAGE160_I184@PURE_QUANTA.Q_CAP_DIFFBUS(CHIPS)':
 C_PATH='@t6g_mb_lib.t6g(sch_1):page160_i184@pure_quanta.q_cap_diffbus(chips)';

PART_NAME
 C625 'Q_CAP_DIFFBUS_C0201-DIFF BUS_0.22UF,6.3V,20%,X6S,SP_CH4221MEE01':;

SECTION_NUMBER 1
 '@T6G_MB_LIB.T6G(SCH_1):PAGE160_I183@PURE_QUANTA.Q_CAP_DIFFBUS(CHIPS)':
 C_PATH='@t6g_mb_lib.t6g(sch_1):page160_i183@pure_quanta.q_cap_diffbus(chips)';

PART_NAME
 C624 'Q_CAP_DIFFBUS_C0201-DIFF BUS_0.22UF,6.3V,20%,X6S,SP_CH4221MEE01':;

SECTION_NUMBER 1
 '@T6G_MB_LIB.T6G(SCH_1):PAGE160_I179@PURE_QUANTA.Q_CAP_DIFFBUS(CHIPS)':
 C_PATH='@t6g_mb_lib.t6g(sch_1):page160_i179@pure_quanta.q_cap_diffbus(chips)';

PART_NAME
 C623 'Q_CAP_DIFFBUS_C0201-DIFF BUS_0.22UF,6.3V,20%,X6S,SP_CH4221MEE01':;

SECTION_NUMBER 1
 '@T6G_MB_LIB.T6G(SCH_1):PAGE160_I177@PURE_QUANTA.Q_CAP_DIFFBUS(CHIPS)':
 C_PATH='@t6g_mb_lib.t6g(sch_1):page160_i177@pure_quanta.q_cap_diffbus(chips)';

PART_NAME
 C622 'Q_CAP_DIFFBUS_C0201-DIFF BUS_0.22UF,6.3V,20%,X6S,SP_CH4221MEE01':;

SECTION_NUMBER 1
 '@T6G_MB_LIB.T6G(SCH_1):PAGE160_I175@PURE_QUANTA.Q_CAP_DIFFBUS(CHIPS)':
 C_PATH='@t6g_mb_lib.t6g(sch_1):page160_i175@pure_quanta.q_cap_diffbus(chips)';

PART_NAME
 C621 'Q_CAP_DIFFBUS_C0201-DIFF BUS_0.22UF,6.3V,20%,X6S,SP_CH4221MEE01':;

SECTION_NUMBER 1
 '@T6G_MB_LIB.T6G(SCH_1):PAGE160_I174@PURE_QUANTA.Q_CAP_DIFFBUS(CHIPS)':
 C_PATH='@t6g_mb_lib.t6g(sch_1):page160_i174@pure_quanta.q_cap_diffbus(chips)';

PART_NAME
 C620 'Q_CAP_DIFFBUS_C0201-DIFF BUS_0.22UF,6.3V,20%,X6S,SP_CH4221MEE01':;

SECTION_NUMBER 1
 '@T6G_MB_LIB.T6G(SCH_1):PAGE160_I171@PURE_QUANTA.Q_CAP_DIFFBUS(CHIPS)':
 C_PATH='@t6g_mb_lib.t6g(sch_1):page160_i171@pure_quanta.q_cap_diffbus(chips)';

PART_NAME
 C619 'Q_CAP_DIFFBUS_C0201-DIFF BUS_0.22UF,6.3V,20%,X6S,SP_CH4221MEE01':;

SECTION_NUMBER 1
 '@T6G_MB_LIB.T6G(SCH_1):PAGE160_I169@PURE_QUANTA.Q_CAP_DIFFBUS(CHIPS)':
 C_PATH='@t6g_mb_lib.t6g(sch_1):page160_i169@pure_quanta.q_cap_diffbus(chips)';

PART_NAME
 C618 'Q_CAP_DIFFBUS_C0201-DIFF BUS_0.22UF,6.3V,20%,X6S,SP_CH4221MEE01':;

SECTION_NUMBER 1
 '@T6G_MB_LIB.T6G(SCH_1):PAGE160_I167@PURE_QUANTA.Q_CAP_DIFFBUS(CHIPS)':
 C_PATH='@t6g_mb_lib.t6g(sch_1):page160_i167@pure_quanta.q_cap_diffbus(chips)';

PART_NAME
 C617 'Q_CAP_DIFFBUS_C0201-DIFF BUS_0.22UF,6.3V,20%,X6S,SP_CH4221MEE01':;

SECTION_NUMBER 1
 '@T6G_MB_LIB.T6G(SCH_1):PAGE160_I166@PURE_QUANTA.Q_CAP_DIFFBUS(CHIPS)':
 C_PATH='@t6g_mb_lib.t6g(sch_1):page160_i166@pure_quanta.q_cap_diffbus(chips)';

PART_NAME
 C616 'Q_CAP_DIFFBUS_C0201-DIFF BUS_0.22UF,6.3V,20%,X6S,SP_CH4221MEE01':;

SECTION_NUMBER 1
 '@T6G_MB_LIB.T6G(SCH_1):PAGE160_I180@PURE_QUANTA.Q_CAP_DIFFBUS(CHIPS)':
 C_PATH='@t6g_mb_lib.t6g(sch_1):page160_i180@pure_quanta.q_cap_diffbus(chips)';

PART_NAME
 C615 'Q_CAP_DIFFBUS_C0201-DIFF BUS_0.22UF,6.3V,20%,X6S,SP_CH4221MEE01':;

SECTION_NUMBER 1
 '@T6G_MB_LIB.T6G(SCH_1):PAGE160_I178@PURE_QUANTA.Q_CAP_DIFFBUS(CHIPS)':
 C_PATH='@t6g_mb_lib.t6g(sch_1):page160_i178@pure_quanta.q_cap_diffbus(chips)';

PART_NAME
 C614 'Q_CAP_DIFFBUS_C0201-DIFF BUS_0.22UF,6.3V,20%,X6S,SP_CH4221MEE01':;

SECTION_NUMBER 1
 '@T6G_MB_LIB.T6G(SCH_1):PAGE160_I176@PURE_QUANTA.Q_CAP_DIFFBUS(CHIPS)':
 C_PATH='@t6g_mb_lib.t6g(sch_1):page160_i176@pure_quanta.q_cap_diffbus(chips)';

PART_NAME
 C613 'Q_CAP_DIFFBUS_C0201-DIFF BUS_0.22UF,6.3V,20%,X6S,SP_CH4221MEE01':;

SECTION_NUMBER 1
 '@T6G_MB_LIB.T6G(SCH_1):PAGE160_I173@PURE_QUANTA.Q_CAP_DIFFBUS(CHIPS)':
 C_PATH='@t6g_mb_lib.t6g(sch_1):page160_i173@pure_quanta.q_cap_diffbus(chips)';

PART_NAME
 C612 'Q_CAP_DIFFBUS_C0201-DIFF BUS_0.22UF,6.3V,20%,X6S,SP_CH4221MEE01':;

SECTION_NUMBER 1
 '@T6G_MB_LIB.T6G(SCH_1):PAGE160_I172@PURE_QUANTA.Q_CAP_DIFFBUS(CHIPS)':
 C_PATH='@t6g_mb_lib.t6g(sch_1):page160_i172@pure_quanta.q_cap_diffbus(chips)';

PART_NAME
 C608 'Q_CAP_DIFFBUS_C0201-DIFF BUS_0.22UF,6.3V,20%,X6S,SP_CH4221MEE01':;

SECTION_NUMBER 1
 '@T6G_MB_LIB.T6G(SCH_1):PAGE160_I170@PURE_QUANTA.Q_CAP_DIFFBUS(CHIPS)':
 C_PATH='@t6g_mb_lib.t6g(sch_1):page160_i170@pure_quanta.q_cap_diffbus(chips)';

PART_NAME
 C607 'Q_CAP_DIFFBUS_C0201-DIFF BUS_0.22UF,6.3V,20%,X6S,SP_CH4221MEE01':;

SECTION_NUMBER 1
 '@T6G_MB_LIB.T6G(SCH_1):PAGE160_I168@PURE_QUANTA.Q_CAP_DIFFBUS(CHIPS)':
 C_PATH='@t6g_mb_lib.t6g(sch_1):page160_i168@pure_quanta.q_cap_diffbus(chips)';

PART_NAME
 C606 'Q_CAP_DIFFBUS_C0201-DIFF BUS_0.22UF,6.3V,20%,X6S,SP_CH4221MEE01':;

SECTION_NUMBER 1
 '@T6G_MB_LIB.T6G(SCH_1):PAGE160_I165@PURE_QUANTA.Q_CAP_DIFFBUS(CHIPS)':
 C_PATH='@t6g_mb_lib.t6g(sch_1):page160_i165@pure_quanta.q_cap_diffbus(chips)';

PART_NAME
 U169 'PI6CV304LE-PI6CV304LE,SMLF,IC,AL000304K01':;

SECTION_NUMBER 1
 '@T6G_MB_LIB.T6G(SCH_1):PAGE142_I17@PURE_QUANTA.PI6CV304LE(CHIPS)':
 C_PATH='@t6g_mb_lib.t6g(sch_1):page142_i17@pure_quanta.pi6cv304le(chips)';

PART_NAME
 U168 '74LVC1G126GW_SMLF-74LVC1G126GW,IC,AL1G0126023':;

SECTION_NUMBER 1
 '@T6G_MB_LIB.T6G(SCH_1):PAGE142_I51@PURE_QUANTA.74LVC1G126GW(CHIPS)':
 C_PATH='@t6g_mb_lib.t6g(sch_1):page142_i51@pure_quanta.\74lvc1g126gw\(chips)';

PART_NAME
 U51 'PCA9555PW_SMLF-PCA9555PW,IC,TMP_QAL009555K04':;

SECTION_NUMBER 1
 '@T6G_MB_LIB.T6G(SCH_1):PAGE142_I75@PURE_QUANTA.PCA9555PW(CHIPS)':
 C_PATH='@t6g_mb_lib.t6g(sch_1):page142_i75@pure_quanta.pca9555pw(chips)';

PART_NAME
 U50 'SN74LVC1G08DBVR_SMLF-SN74LVC1G08DBVR,IC,AL1G0008012':;

SECTION_NUMBER 1
 '@T6G_MB_LIB.T6G(SCH_1):PAGE142_I88@PURE_QUANTA.SN74LVC1G08DBVR(CHIPS)':
 C_PATH='@t6g_mb_lib.t6g(sch_1):page142_i88@pure_quanta.sn74lvc1g08dbvr(chips)';

PART_NAME
 U49 'MOSFET_N_SMLF-BSS138K,BSS138K,IC,BAM138K0000':;

SECTION_NUMBER 1
 '@T6G_MB_LIB.T6G(SCH_1):PAGE142_I97@PURE_QUANTA.MOSFET_N(CHIPS)':
 C_PATH='@t6g_mb_lib.t6g(sch_1):page142_i97@pure_quanta.mosfet_n(chips)';

PART_NAME
 R2745 'Q_RES_0402LF-1K,5%,1/16W,CHIP,TMP_QCS21002JB34':;

SECTION_NUMBER 1
 '@T6G_MB_LIB.T6G(SCH_1):PAGE142_I95@PURE_QUANTA.Q_RES(CHIPS)':
 C_PATH='@t6g_mb_lib.t6g(sch_1):page142_i95@pure_quanta.q_res(chips)';

PART_NAME
 R2645 'Q_RES_0402LF-27.4,1%,1/16W,CHIP,CS02742FB19':;

SECTION_NUMBER 1
 '@T6G_MB_LIB.T6G(SCH_1):PAGE142_I86@PURE_QUANTA.Q_RES(CHIPS)':
 C_PATH='@t6g_mb_lib.t6g(sch_1):page142_i86@pure_quanta.q_res(chips)';

PART_NAME
 R2603 'Q_RES_0402LF-27.4,1%,1/16W,CHIP,CS02742FB19':;

SECTION_NUMBER 1
 '@T6G_MB_LIB.T6G(SCH_1):PAGE142_I87@PURE_QUANTA.Q_RES(CHIPS)':
 C_PATH='@t6g_mb_lib.t6g(sch_1):page142_i87@pure_quanta.q_res(chips)';

PART_NAME
 R2035 'Q_RES_0402LF-33,5%,1/16W,CHIP,CS03302JB29':;

SECTION_NUMBER 1
 '@T6G_MB_LIB.T6G(SCH_1):PAGE142_I56@PURE_QUANTA.Q_RES(CHIPS)':
 C_PATH='@t6g_mb_lib.t6g(sch_1):page142_i56@pure_quanta.q_res(chips)';

PART_NAME
 R2023 'Q_RES_0402LF-33,5%,1/16W,CHIP,CS03302JB29':;

SECTION_NUMBER 1
 '@T6G_MB_LIB.T6G(SCH_1):PAGE142_I55@PURE_QUANTA.Q_RES(CHIPS)':
 C_PATH='@t6g_mb_lib.t6g(sch_1):page142_i55@pure_quanta.q_res(chips)';

PART_NAME
 R2017 'Q_RES_0402LF-0,5%,1/16W,CHIP,CS00002JB38':;

SECTION_NUMBER 1
 '@T6G_MB_LIB.T6G(SCH_1):PAGE142_I74@PURE_QUANTA.Q_RES(CHIPS)':
 C_PATH='@t6g_mb_lib.t6g(sch_1):page142_i74@pure_quanta.q_res(chips)';

PART_NAME
 R2016 'Q_RES_0402LF-1K,5%,1/16W,CHIP,TMP_QCS21002JB34':;

SECTION_NUMBER 1
 '@T6G_MB_LIB.T6G(SCH_1):PAGE142_I67@PURE_QUANTA.Q_RES(CHIPS)':
 C_PATH='@t6g_mb_lib.t6g(sch_1):page142_i67@pure_quanta.q_res(chips)';

PART_NAME
 R2015 'Q_RES_0402LF-1K,5%,1/16W,EMPTY,TMP_QCS21002JB34':;

SECTION_NUMBER 1
 '@T6G_MB_LIB.T6G(SCH_1):PAGE142_I69@PURE_QUANTA.Q_RES(CHIPS)':
 C_PATH='@t6g_mb_lib.t6g(sch_1):page142_i69@pure_quanta.q_res(chips)';

PART_NAME
 R2014 'Q_RES_0402LF-1K,5%,1/16W,CHIP,TMP_QCS21002JB34':;

SECTION_NUMBER 1
 '@T6G_MB_LIB.T6G(SCH_1):PAGE142_I64@PURE_QUANTA.Q_RES(CHIPS)':
 C_PATH='@t6g_mb_lib.t6g(sch_1):page142_i64@pure_quanta.q_res(chips)';

PART_NAME
 R2013 'Q_RES_0402LF-1K,5%,1/16W,EMPTY,TMP_QCS21002JB34':;

SECTION_NUMBER 1
 '@T6G_MB_LIB.T6G(SCH_1):PAGE142_I68@PURE_QUANTA.Q_RES(CHIPS)':
 C_PATH='@t6g_mb_lib.t6g(sch_1):page142_i68@pure_quanta.q_res(chips)';

PART_NAME
 R2012 'Q_RES_0402LF-1K,5%,1/16W,CHIP,TMP_QCS21002JB34':;

SECTION_NUMBER 1
 '@T6G_MB_LIB.T6G(SCH_1):PAGE142_I61@PURE_QUANTA.Q_RES(CHIPS)':
 C_PATH='@t6g_mb_lib.t6g(sch_1):page142_i61@pure_quanta.q_res(chips)';

PART_NAME
 R2011 'Q_RES_0402LF-1K,5%,1/16W,EMPTY,TMP_QCS21002JB34':;

SECTION_NUMBER 1
 '@T6G_MB_LIB.T6G(SCH_1):PAGE142_I62@PURE_QUANTA.Q_RES(CHIPS)':
 C_PATH='@t6g_mb_lib.t6g(sch_1):page142_i62@pure_quanta.q_res(chips)';

PART_NAME
 R1824 'Q_RES_0402LF-10K,1%,1/16W,EMPTY,TMP_QCS31002FB26':;

SECTION_NUMBER 1
 '@T6G_MB_LIB.T6G(SCH_1):PAGE142_I5@PURE_QUANTA.Q_RES(CHIPS)':
 C_PATH='@t6g_mb_lib.t6g(sch_1):page142_i5@pure_quanta.q_res(chips)';

PART_NAME
 R1752 'Q_RES_0402LF-33,5%,1/16W,CHIP,CS03302JB29':;

SECTION_NUMBER 1
 '@T6G_MB_LIB.T6G(SCH_1):PAGE142_I37@PURE_QUANTA.Q_RES(CHIPS)':
 C_PATH='@t6g_mb_lib.t6g(sch_1):page142_i37@pure_quanta.q_res(chips)';

PART_NAME
 R1734 'Q_RES_0402LF-0,5%,1/16W,CHIP,CS00002JB38':;

SECTION_NUMBER 1
 '@T6G_MB_LIB.T6G(SCH_1):PAGE142_I15@PURE_QUANTA.Q_RES(CHIPS)':
 C_PATH='@t6g_mb_lib.t6g(sch_1):page142_i15@pure_quanta.q_res(chips)';

PART_NAME
 R1733 'Q_RES_0402LF-10K,1%,1/16W,CHIP,TMP_QCS31002FB26':;

SECTION_NUMBER 1
 '@T6G_MB_LIB.T6G(SCH_1):PAGE142_I1@PURE_QUANTA.Q_RES(CHIPS)':
 C_PATH='@t6g_mb_lib.t6g(sch_1):page142_i1@pure_quanta.q_res(chips)';

PART_NAME
 R1732 'Q_RES_0402LF-10K,1%,1/16W,CHIP,TMP_QCS31002FB26':;

SECTION_NUMBER 1
 '@T6G_MB_LIB.T6G(SCH_1):PAGE142_I6@PURE_QUANTA.Q_RES(CHIPS)':
 C_PATH='@t6g_mb_lib.t6g(sch_1):page142_i6@pure_quanta.q_res(chips)';

PART_NAME
 OSC3 'OSC4_SIT1602AI2233E50000000D-50MHZ,SMLF,MISC,BF650000037':;

SECTION_NUMBER 1
 '@T6G_MB_LIB.T6G(SCH_1):PAGE142_I12@PURE_QUANTA.OSC4_SIT1602AI2233E50000000D(CHIPS)':
 C_PATH='@t6g_mb_lib.t6g(sch_1):page142_i12@pure_quanta.osc4_sit1602ai2233e50000~
000d(chips)';

PART_NAME
 C2412 'Q_CAP_0402-0.1UF,25V,10%,X7R,CH4104K1B00':;

SECTION_NUMBER 1
 '@T6G_MB_LIB.T6G(SCH_1):PAGE142_I21@PURE_QUANTA.Q_CAP(CHIPS)':
 C_PATH='@t6g_mb_lib.t6g(sch_1):page142_i21@pure_quanta.q_cap(chips)';

PART_NAME
 C2411 'Q_CAP_0402-0.1UF,25V,10%,X7R,CH4104K1B00':;

SECTION_NUMBER 1
 '@T6G_MB_LIB.T6G(SCH_1):PAGE142_I26@PURE_QUANTA.Q_CAP(CHIPS)':
 C_PATH='@t6g_mb_lib.t6g(sch_1):page142_i26@pure_quanta.q_cap(chips)';

PART_NAME
 C2408 'Q_CAP_0402-0.1UF,25V,10%,X7R,CH4104K1B00':;

SECTION_NUMBER 1
 '@T6G_MB_LIB.T6G(SCH_1):PAGE142_I2@PURE_QUANTA.Q_CAP(CHIPS)':
 C_PATH='@t6g_mb_lib.t6g(sch_1):page142_i2@pure_quanta.q_cap(chips)';

PART_NAME
 C579 'Q_CAP_0402-0.1UF,25V,10%,X7R,CH4104K1B00':;

SECTION_NUMBER 1
 '@T6G_MB_LIB.T6G(SCH_1):PAGE142_I77@PURE_QUANTA.Q_CAP(CHIPS)':
 C_PATH='@t6g_mb_lib.t6g(sch_1):page142_i77@pure_quanta.q_cap(chips)';

PART_NAME
 C578 'Q_CAP_0402-0.1UF,25V,10%,X7R,CH4104K1B00':;

SECTION_NUMBER 1
 '@T6G_MB_LIB.T6G(SCH_1):PAGE142_I91@PURE_QUANTA.Q_CAP(CHIPS)':
 C_PATH='@t6g_mb_lib.t6g(sch_1):page142_i91@pure_quanta.q_cap(chips)';

PART_NAME
 U178 '74LVC1G126GW_SMLF-74LVC1G126GW,IC,AL1G0126023':;

SECTION_NUMBER 1
 '@T6G_MB_LIB.T6G(SCH_1):PAGE145_I35@PURE_QUANTA.74LVC1G126GW(CHIPS)':
 C_PATH='@t6g_mb_lib.t6g(sch_1):page145_i35@pure_quanta.\74lvc1g126gw\(chips)';

PART_NAME
 U175 '74CBTLV3126PW-74CBTLV3126PW,SMLF,EMPTY,AL003126K08':;

SECTION_NUMBER 1
 '@T6G_MB_LIB.T6G(SCH_1):PAGE145_I68@PURE_QUANTA.74CBTLV3126PW(CHIPS)':
 C_PATH='@t6g_mb_lib.t6g(sch_1):page145_i68@pure_quanta.\74cbtlv3126pw\(chips)';

PART_NAME
 U46 'PCA9555PW_SMLF-PCA9555PW,IC,TMP_QAL009555K04':;

SECTION_NUMBER 1
 '@T6G_MB_LIB.T6G(SCH_1):PAGE145_I97@PURE_QUANTA.PCA9555PW(CHIPS)':
 C_PATH='@t6g_mb_lib.t6g(sch_1):page145_i97@pure_quanta.pca9555pw(chips)';

PART_NAME
 U45 'SN74LVC1G08DBVR_SMLF-SN74LVC1G08DBVR,IC,AL1G0008012':;

SECTION_NUMBER 1
 '@T6G_MB_LIB.T6G(SCH_1):PAGE145_I106@PURE_QUANTA.SN74LVC1G08DBVR(CHIPS)':
 C_PATH='@t6g_mb_lib.t6g(sch_1):page145_i106@pure_quanta.sn74lvc1g08dbvr(chips)';

PART_NAME
 U44 'MOSFET_N_SMLF-BSS138K,BSS138K,IC,BAM138K0000':;

SECTION_NUMBER 1
 '@T6G_MB_LIB.T6G(SCH_1):PAGE145_I115@PURE_QUANTA.MOSFET_N(CHIPS)':
 C_PATH='@t6g_mb_lib.t6g(sch_1):page145_i115@pure_quanta.mosfet_n(chips)';

PART_NAME
 R2746 'Q_RES_0402LF-1K,5%,1/16W,CHIP,TMP_QCS21002JB34':;

SECTION_NUMBER 1
 '@T6G_MB_LIB.T6G(SCH_1):PAGE145_I112@PURE_QUANTA.Q_RES(CHIPS)':
 C_PATH='@t6g_mb_lib.t6g(sch_1):page145_i112@pure_quanta.q_res(chips)';

PART_NAME
 R2439 'Q_RES_0402LF-33,5%,1/16W,CHIP,CS03302JB29':;

SECTION_NUMBER 1
 '@T6G_MB_LIB.T6G(SCH_1):PAGE145_I96@PURE_QUANTA.Q_RES(CHIPS)':
 C_PATH='@t6g_mb_lib.t6g(sch_1):page145_i96@pure_quanta.q_res(chips)';

PART_NAME
 R2438 'Q_RES_0402LF-33,5%,1/16W,CHIP,CS03302JB29':;

SECTION_NUMBER 1
 '@T6G_MB_LIB.T6G(SCH_1):PAGE145_I95@PURE_QUANTA.Q_RES(CHIPS)':
 C_PATH='@t6g_mb_lib.t6g(sch_1):page145_i95@pure_quanta.q_res(chips)';

PART_NAME
 R2436 'Q_RES_0402LF-1K,5%,1/16W,CHIP,TMP_QCS21002JB34':;

SECTION_NUMBER 1
 '@T6G_MB_LIB.T6G(SCH_1):PAGE145_I82@PURE_QUANTA.Q_RES(CHIPS)':
 C_PATH='@t6g_mb_lib.t6g(sch_1):page145_i82@pure_quanta.q_res(chips)';

PART_NAME
 R2434 'Q_RES_0402LF-1K,5%,1/16W,EMPTY,TMP_QCS21002JB34':;

SECTION_NUMBER 1
 '@T6G_MB_LIB.T6G(SCH_1):PAGE145_I89@PURE_QUANTA.Q_RES(CHIPS)':
 C_PATH='@t6g_mb_lib.t6g(sch_1):page145_i89@pure_quanta.q_res(chips)';

PART_NAME
 R2433 'Q_RES_0402LF-1K,5%,1/16W,CHIP,TMP_QCS21002JB34':;

SECTION_NUMBER 1
 '@T6G_MB_LIB.T6G(SCH_1):PAGE145_I77@PURE_QUANTA.Q_RES(CHIPS)':
 C_PATH='@t6g_mb_lib.t6g(sch_1):page145_i77@pure_quanta.q_res(chips)';

PART_NAME
 R2419 'Q_RES_0402LF-1K,5%,1/16W,EMPTY,TMP_QCS21002JB34':;

SECTION_NUMBER 1
 '@T6G_MB_LIB.T6G(SCH_1):PAGE145_I79@PURE_QUANTA.Q_RES(CHIPS)':
 C_PATH='@t6g_mb_lib.t6g(sch_1):page145_i79@pure_quanta.q_res(chips)';

PART_NAME
 R2418 'Q_RES_0402LF-1K,5%,1/16W,CHIP,TMP_QCS21002JB34':;

SECTION_NUMBER 1
 '@T6G_MB_LIB.T6G(SCH_1):PAGE145_I76@PURE_QUANTA.Q_RES(CHIPS)':
 C_PATH='@t6g_mb_lib.t6g(sch_1):page145_i76@pure_quanta.q_res(chips)';

PART_NAME
 R2416 'Q_RES_0402LF-1K,5%,1/16W,EMPTY,TMP_QCS21002JB34':;

SECTION_NUMBER 1
 '@T6G_MB_LIB.T6G(SCH_1):PAGE145_I78@PURE_QUANTA.Q_RES(CHIPS)':
 C_PATH='@t6g_mb_lib.t6g(sch_1):page145_i78@pure_quanta.q_res(chips)';

PART_NAME
 R1983 'Q_RES_0402LF-33,5%,1/16W,CHIP,CS03302JB29':;

SECTION_NUMBER 1
 '@T6G_MB_LIB.T6G(SCH_1):PAGE145_I27@PURE_QUANTA.Q_RES(CHIPS)':
 C_PATH='@t6g_mb_lib.t6g(sch_1):page145_i27@pure_quanta.q_res(chips)';

PART_NAME
 R1955 'Q_RES_0402LF-100,1%,1/16W,CHIP,TMP_QCS11002FB22':;

SECTION_NUMBER 1
 '@T6G_MB_LIB.T6G(SCH_1):PAGE145_I65@PURE_QUANTA.Q_RES(CHIPS)':
 C_PATH='@t6g_mb_lib.t6g(sch_1):page145_i65@pure_quanta.q_res(chips)';

PART_NAME
 R1947 'Q_RES_0402LF-100,1%,1/16W,CHIP,TMP_QCS11002FB22':;

SECTION_NUMBER 1
 '@T6G_MB_LIB.T6G(SCH_1):PAGE145_I64@PURE_QUANTA.Q_RES(CHIPS)':
 C_PATH='@t6g_mb_lib.t6g(sch_1):page145_i64@pure_quanta.q_res(chips)';

PART_NAME
 R1946 'Q_RES_0402LF-100,1%,1/16W,CHIP,TMP_QCS11002FB22':;

SECTION_NUMBER 1
 '@T6G_MB_LIB.T6G(SCH_1):PAGE145_I63@PURE_QUANTA.Q_RES(CHIPS)':
 C_PATH='@t6g_mb_lib.t6g(sch_1):page145_i63@pure_quanta.q_res(chips)';

PART_NAME
 R1945 'Q_RES_0402LF-10K,1%,1/16W,CHIP,TMP_QCS31002FB26':;

SECTION_NUMBER 1
 '@T6G_MB_LIB.T6G(SCH_1):PAGE145_I40@PURE_QUANTA.Q_RES(CHIPS)':
 C_PATH='@t6g_mb_lib.t6g(sch_1):page145_i40@pure_quanta.q_res(chips)';

PART_NAME
 R1944 'Q_RES_0402LF-10K,1%,1/16W,EMPTY,TMP_QCS31002FB26':;

SECTION_NUMBER 1
 '@T6G_MB_LIB.T6G(SCH_1):PAGE145_I41@PURE_QUANTA.Q_RES(CHIPS)':
 C_PATH='@t6g_mb_lib.t6g(sch_1):page145_i41@pure_quanta.q_res(chips)';

PART_NAME
 R1943 'Q_RES_0402LF-33,5%,1/16W,CHIP,CS03302JB29':;

SECTION_NUMBER 1
 '@T6G_MB_LIB.T6G(SCH_1):PAGE145_I73@PURE_QUANTA.Q_RES(CHIPS)':
 C_PATH='@t6g_mb_lib.t6g(sch_1):page145_i73@pure_quanta.q_res(chips)';

PART_NAME
 R1920 'Q_RES_0402LF-33,5%,1/16W,CHIP,CS03302JB29':;

SECTION_NUMBER 1
 '@T6G_MB_LIB.T6G(SCH_1):PAGE145_I94@PURE_QUANTA.Q_RES(CHIPS)':
 C_PATH='@t6g_mb_lib.t6g(sch_1):page145_i94@pure_quanta.q_res(chips)';

PART_NAME
 C2439 'Q_CAP_0402-0.1UF,25V,10%,X7R,CH4104K1B00':;

SECTION_NUMBER 1
 '@T6G_MB_LIB.T6G(SCH_1):PAGE145_I29@PURE_QUANTA.Q_CAP(CHIPS)':
 C_PATH='@t6g_mb_lib.t6g(sch_1):page145_i29@pure_quanta.q_cap(chips)';

PART_NAME
 C1298 'Q_CAP_0402-0.1UF,25V,10%,X7R,CH4104K1B00':;

SECTION_NUMBER 1
 '@T6G_MB_LIB.T6G(SCH_1):PAGE145_I36@PURE_QUANTA.Q_CAP(CHIPS)':
 C_PATH='@t6g_mb_lib.t6g(sch_1):page145_i36@pure_quanta.q_cap(chips)';

PART_NAME
 C575 'Q_CAP_0402-0.1UF,25V,10%,X7R,CH4104K1B00':;

SECTION_NUMBER 1
 '@T6G_MB_LIB.T6G(SCH_1):PAGE145_I91@PURE_QUANTA.Q_CAP(CHIPS)':
 C_PATH='@t6g_mb_lib.t6g(sch_1):page145_i91@pure_quanta.q_cap(chips)';

PART_NAME
 C574 'Q_CAP_0402-0.1UF,25V,10%,X7R,CH4104K1B00':;

SECTION_NUMBER 1
 '@T6G_MB_LIB.T6G(SCH_1):PAGE145_I110@PURE_QUANTA.Q_CAP(CHIPS)':
 C_PATH='@t6g_mb_lib.t6g(sch_1):page145_i110@pure_quanta.q_cap(chips)';

PART_NAME
 U195 'PCA9546APWR-PCA9546APWR,SMLF,IC,AL09546AK01':;

SECTION_NUMBER 1
 '@T6G_MB_LIB.T6G(SCH_1):PAGE278_I238@PURE_QUANTA.PCA9546APWR(CHIPS)':
 C_PATH='@t6g_mb_lib.t6g(sch_1):page278_i238@pure_quanta.pca9546apwr(chips)';

PART_NAME
 U20 'PCA9546APWR-PCA9546APWR,SMLF,IC,AL09546AK01':;

SECTION_NUMBER 1
 '@T6G_MB_LIB.T6G(SCH_1):PAGE278_I199@PURE_QUANTA.PCA9546APWR(CHIPS)':
 C_PATH='@t6g_mb_lib.t6g(sch_1):page278_i199@pure_quanta.pca9546apwr(chips)';

PART_NAME
 R3692 'Q_RES_0402LF-33,5%,1/16W,CHIP,CS03302JB29':;

SECTION_NUMBER 1
 '@T6G_MB_LIB.T6G(SCH_1):PAGE278_I272@PURE_QUANTA.Q_RES(CHIPS)':
 C_PATH='@t6g_mb_lib.t6g(sch_1):page278_i272@pure_quanta.q_res(chips)';

PART_NAME
 R3691 'Q_RES_0402LF-0,5%,1/16W,CHIP,CS00002JB38':;

SECTION_NUMBER 1
 '@T6G_MB_LIB.T6G(SCH_1):PAGE278_I273@PURE_QUANTA.Q_RES(CHIPS)':
 C_PATH='@t6g_mb_lib.t6g(sch_1):page278_i273@pure_quanta.q_res(chips)';

PART_NAME
 R3690 'Q_RES_0402LF-33,5%,1/16W,CHIP,CS03302JB29':;

SECTION_NUMBER 1
 '@T6G_MB_LIB.T6G(SCH_1):PAGE278_I274@PURE_QUANTA.Q_RES(CHIPS)':
 C_PATH='@t6g_mb_lib.t6g(sch_1):page278_i274@pure_quanta.q_res(chips)';

PART_NAME
 R3689 'Q_RES_0402LF-0,5%,1/16W,CHIP,CS00002JB38':;

SECTION_NUMBER 1
 '@T6G_MB_LIB.T6G(SCH_1):PAGE278_I275@PURE_QUANTA.Q_RES(CHIPS)':
 C_PATH='@t6g_mb_lib.t6g(sch_1):page278_i275@pure_quanta.q_res(chips)';

PART_NAME
 R3688 'Q_RES_0402LF-0,5%,1/16W,CHIP,CS00002JB38':;

SECTION_NUMBER 1
 '@T6G_MB_LIB.T6G(SCH_1):PAGE278_I279@PURE_QUANTA.Q_RES(CHIPS)':
 C_PATH='@t6g_mb_lib.t6g(sch_1):page278_i279@pure_quanta.q_res(chips)';

PART_NAME
 R3687 'Q_RES_0402LF-33,5%,1/16W,CHIP,CS03302JB29':;

SECTION_NUMBER 1
 '@T6G_MB_LIB.T6G(SCH_1):PAGE278_I278@PURE_QUANTA.Q_RES(CHIPS)':
 C_PATH='@t6g_mb_lib.t6g(sch_1):page278_i278@pure_quanta.q_res(chips)';

PART_NAME
 R3686 'Q_RES_0402LF-0,5%,1/16W,CHIP,CS00002JB38':;

SECTION_NUMBER 1
 '@T6G_MB_LIB.T6G(SCH_1):PAGE278_I277@PURE_QUANTA.Q_RES(CHIPS)':
 C_PATH='@t6g_mb_lib.t6g(sch_1):page278_i277@pure_quanta.q_res(chips)';

PART_NAME
 R3685 'Q_RES_0402LF-33,5%,1/16W,CHIP,CS03302JB29':;

SECTION_NUMBER 1
 '@T6G_MB_LIB.T6G(SCH_1):PAGE278_I276@PURE_QUANTA.Q_RES(CHIPS)':
 C_PATH='@t6g_mb_lib.t6g(sch_1):page278_i276@pure_quanta.q_res(chips)';

PART_NAME
 R3684 'Q_RES_0402LF-1K,1%,1/16W,EMPTY,TMP_QCS21002FB24':;

SECTION_NUMBER 1
 '@T6G_MB_LIB.T6G(SCH_1):PAGE278_I256@PURE_QUANTA.Q_RES(CHIPS)':
 C_PATH='@t6g_mb_lib.t6g(sch_1):page278_i256@pure_quanta.q_res(chips)';

PART_NAME
 R3683 'Q_RES_0402LF-10K,1%,1/16W,CHIP,TMP_QCS31002FB26':;

SECTION_NUMBER 1
 '@T6G_MB_LIB.T6G(SCH_1):PAGE278_I255@PURE_QUANTA.Q_RES(CHIPS)':
 C_PATH='@t6g_mb_lib.t6g(sch_1):page278_i255@pure_quanta.q_res(chips)';

PART_NAME
 R3682 'Q_RES_0402LF-1K,1%,1/16W,EMPTY,TMP_QCS21002FB24':;

SECTION_NUMBER 1
 '@T6G_MB_LIB.T6G(SCH_1):PAGE278_I259@PURE_QUANTA.Q_RES(CHIPS)':
 C_PATH='@t6g_mb_lib.t6g(sch_1):page278_i259@pure_quanta.q_res(chips)';

PART_NAME
 R3681 'Q_RES_0402LF-10K,1%,1/16W,CHIP,TMP_QCS31002FB26':;

SECTION_NUMBER 1
 '@T6G_MB_LIB.T6G(SCH_1):PAGE278_I257@PURE_QUANTA.Q_RES(CHIPS)':
 C_PATH='@t6g_mb_lib.t6g(sch_1):page278_i257@pure_quanta.q_res(chips)';

PART_NAME
 R3680 'Q_RES_0402LF-1K,1%,1/16W,EMPTY,TMP_QCS21002FB24':;

SECTION_NUMBER 1
 '@T6G_MB_LIB.T6G(SCH_1):PAGE278_I261@PURE_QUANTA.Q_RES(CHIPS)':
 C_PATH='@t6g_mb_lib.t6g(sch_1):page278_i261@pure_quanta.q_res(chips)';

PART_NAME
 R3679 'Q_RES_0402LF-10K,1%,1/16W,CHIP,TMP_QCS31002FB26':;

SECTION_NUMBER 1
 '@T6G_MB_LIB.T6G(SCH_1):PAGE278_I258@PURE_QUANTA.Q_RES(CHIPS)':
 C_PATH='@t6g_mb_lib.t6g(sch_1):page278_i258@pure_quanta.q_res(chips)';

PART_NAME
 R3669 'Q_RES_0402LF-0,5%,1/16W,CHIP,CS00002JB38':;

SECTION_NUMBER 1
 '@T6G_MB_LIB.T6G(SCH_1):PAGE278_I249@PURE_QUANTA.Q_RES(CHIPS)':
 C_PATH='@t6g_mb_lib.t6g(sch_1):page278_i249@pure_quanta.q_res(chips)';

PART_NAME
 R3668 'Q_RES_0402LF-0,5%,1/16W,CHIP,CS00002JB38':;

SECTION_NUMBER 1
 '@T6G_MB_LIB.T6G(SCH_1):PAGE278_I250@PURE_QUANTA.Q_RES(CHIPS)':
 C_PATH='@t6g_mb_lib.t6g(sch_1):page278_i250@pure_quanta.q_res(chips)';

PART_NAME
 R3649 'Q_RES_0402LF-10K,1%,1/16W,CHIP,TMP_QCS31002FB26':;

SECTION_NUMBER 1
 '@T6G_MB_LIB.T6G(SCH_1):PAGE278_I243@PURE_QUANTA.Q_RES(CHIPS)':
 C_PATH='@t6g_mb_lib.t6g(sch_1):page278_i243@pure_quanta.q_res(chips)';

PART_NAME
 R3647 'Q_RES_0402LF-10K,1%,1/16W,CHIP,TMP_QCS31002FB26':;

SECTION_NUMBER 1
 '@T6G_MB_LIB.T6G(SCH_1):PAGE278_I230@PURE_QUANTA.Q_RES(CHIPS)':
 C_PATH='@t6g_mb_lib.t6g(sch_1):page278_i230@pure_quanta.q_res(chips)';

PART_NAME
 R3646 'Q_RES_0402LF-10K,1%,1/16W,CHIP,TMP_QCS31002FB26':;

SECTION_NUMBER 1
 '@T6G_MB_LIB.T6G(SCH_1):PAGE278_I229@PURE_QUANTA.Q_RES(CHIPS)':
 C_PATH='@t6g_mb_lib.t6g(sch_1):page278_i229@pure_quanta.q_res(chips)';

PART_NAME
 R3645 'Q_RES_0402LF-10K,1%,1/16W,CHIP,TMP_QCS31002FB26':;

SECTION_NUMBER 1
 '@T6G_MB_LIB.T6G(SCH_1):PAGE278_I227@PURE_QUANTA.Q_RES(CHIPS)':
 C_PATH='@t6g_mb_lib.t6g(sch_1):page278_i227@pure_quanta.q_res(chips)';

PART_NAME
 R3644 'Q_RES_0402LF-10K,1%,1/16W,CHIP,TMP_QCS31002FB26':;

SECTION_NUMBER 1
 '@T6G_MB_LIB.T6G(SCH_1):PAGE278_I228@PURE_QUANTA.Q_RES(CHIPS)':
 C_PATH='@t6g_mb_lib.t6g(sch_1):page278_i228@pure_quanta.q_res(chips)';

PART_NAME
 R3643 'Q_RES_0402LF-10K,1%,1/16W,CHIP,TMP_QCS31002FB26':;

SECTION_NUMBER 1
 '@T6G_MB_LIB.T6G(SCH_1):PAGE278_I225@PURE_QUANTA.Q_RES(CHIPS)':
 C_PATH='@t6g_mb_lib.t6g(sch_1):page278_i225@pure_quanta.q_res(chips)';

PART_NAME
 R3642 'Q_RES_0402LF-10K,1%,1/16W,CHIP,TMP_QCS31002FB26':;

SECTION_NUMBER 1
 '@T6G_MB_LIB.T6G(SCH_1):PAGE278_I226@PURE_QUANTA.Q_RES(CHIPS)':
 C_PATH='@t6g_mb_lib.t6g(sch_1):page278_i226@pure_quanta.q_res(chips)';

PART_NAME
 R3641 'Q_RES_0402LF-10K,1%,1/16W,CHIP,TMP_QCS31002FB26':;

SECTION_NUMBER 1
 '@T6G_MB_LIB.T6G(SCH_1):PAGE278_I224@PURE_QUANTA.Q_RES(CHIPS)':
 C_PATH='@t6g_mb_lib.t6g(sch_1):page278_i224@pure_quanta.q_res(chips)';

PART_NAME
 R3640 'Q_RES_0402LF-10K,1%,1/16W,CHIP,TMP_QCS31002FB26':;

SECTION_NUMBER 1
 '@T6G_MB_LIB.T6G(SCH_1):PAGE278_I223@PURE_QUANTA.Q_RES(CHIPS)':
 C_PATH='@t6g_mb_lib.t6g(sch_1):page278_i223@pure_quanta.q_res(chips)';

PART_NAME
 R956 'Q_RES_0402LF-33,5%,1/16W,CHIP,CS03302JB29':;

SECTION_NUMBER 1
 '@T6G_MB_LIB.T6G(SCH_1):PAGE278_I196@PURE_QUANTA.Q_RES(CHIPS)':
 C_PATH='@t6g_mb_lib.t6g(sch_1):page278_i196@pure_quanta.q_res(chips)';

PART_NAME
 R955 'Q_RES_0402LF-0,5%,1/16W,CHIP,CS00002JB38':;

SECTION_NUMBER 1
 '@T6G_MB_LIB.T6G(SCH_1):PAGE278_I194@PURE_QUANTA.Q_RES(CHIPS)':
 C_PATH='@t6g_mb_lib.t6g(sch_1):page278_i194@pure_quanta.q_res(chips)';

PART_NAME
 R954 'Q_RES_0402LF-0,5%,1/16W,CHIP,CS00002JB38':;

SECTION_NUMBER 1
 '@T6G_MB_LIB.T6G(SCH_1):PAGE278_I195@PURE_QUANTA.Q_RES(CHIPS)':
 C_PATH='@t6g_mb_lib.t6g(sch_1):page278_i195@pure_quanta.q_res(chips)';

PART_NAME
 R952 'Q_RES_0402LF-33,5%,1/16W,CHIP,CS03302JB29':;

SECTION_NUMBER 1
 '@T6G_MB_LIB.T6G(SCH_1):PAGE278_I175@PURE_QUANTA.Q_RES(CHIPS)':
 C_PATH='@t6g_mb_lib.t6g(sch_1):page278_i175@pure_quanta.q_res(chips)';

PART_NAME
 R951 'Q_RES_0402LF-33,5%,1/16W,CHIP,CS03302JB29':;

SECTION_NUMBER 1
 '@T6G_MB_LIB.T6G(SCH_1):PAGE278_I207@PURE_QUANTA.Q_RES(CHIPS)':
 C_PATH='@t6g_mb_lib.t6g(sch_1):page278_i207@pure_quanta.q_res(chips)';

PART_NAME
 R950 'Q_RES_0402LF-0,5%,1/16W,CHIP,CS00002JB38':;

SECTION_NUMBER 1
 '@T6G_MB_LIB.T6G(SCH_1):PAGE278_I206@PURE_QUANTA.Q_RES(CHIPS)':
 C_PATH='@t6g_mb_lib.t6g(sch_1):page278_i206@pure_quanta.q_res(chips)';

PART_NAME
 R949 'Q_RES_0402LF-33,5%,1/16W,CHIP,CS03302JB29':;

SECTION_NUMBER 1
 '@T6G_MB_LIB.T6G(SCH_1):PAGE278_I205@PURE_QUANTA.Q_RES(CHIPS)':
 C_PATH='@t6g_mb_lib.t6g(sch_1):page278_i205@pure_quanta.q_res(chips)';

PART_NAME
 R877 'Q_RES_0402LF-0,5%,1/16W,CHIP,CS00002JB38':;

SECTION_NUMBER 1
 '@T6G_MB_LIB.T6G(SCH_1):PAGE278_I204@PURE_QUANTA.Q_RES(CHIPS)':
 C_PATH='@t6g_mb_lib.t6g(sch_1):page278_i204@pure_quanta.q_res(chips)';

PART_NAME
 R846 'Q_RES_0402LF-10K,1%,1/16W,CHIP,TMP_QCS31002FB26':;

SECTION_NUMBER 1
 '@T6G_MB_LIB.T6G(SCH_1):PAGE278_I203@PURE_QUANTA.Q_RES(CHIPS)':
 C_PATH='@t6g_mb_lib.t6g(sch_1):page278_i203@pure_quanta.q_res(chips)';

PART_NAME
 R845 'Q_RES_0402LF-0,5%,1/16W,CHIP,CS00002JB38':;

SECTION_NUMBER 1
 '@T6G_MB_LIB.T6G(SCH_1):PAGE278_I192@PURE_QUANTA.Q_RES(CHIPS)':
 C_PATH='@t6g_mb_lib.t6g(sch_1):page278_i192@pure_quanta.q_res(chips)';

PART_NAME
 R844 'Q_RES_0402LF-0,5%,1/16W,CHIP,CS00002JB38':;

SECTION_NUMBER 1
 '@T6G_MB_LIB.T6G(SCH_1):PAGE278_I193@PURE_QUANTA.Q_RES(CHIPS)':
 C_PATH='@t6g_mb_lib.t6g(sch_1):page278_i193@pure_quanta.q_res(chips)';

PART_NAME
 R843 'Q_RES_0402LF-1K,1%,1/16W,EMPTY,TMP_QCS21002FB24':;

SECTION_NUMBER 1
 '@T6G_MB_LIB.T6G(SCH_1):PAGE278_I213@PURE_QUANTA.Q_RES(CHIPS)':
 C_PATH='@t6g_mb_lib.t6g(sch_1):page278_i213@pure_quanta.q_res(chips)';

PART_NAME
 R842 'Q_RES_0402LF-10K,1%,1/16W,CHIP,TMP_QCS31002FB26':;

SECTION_NUMBER 1
 '@T6G_MB_LIB.T6G(SCH_1):PAGE278_I182@PURE_QUANTA.Q_RES(CHIPS)':
 C_PATH='@t6g_mb_lib.t6g(sch_1):page278_i182@pure_quanta.q_res(chips)';

PART_NAME
 R841 'Q_RES_0402LF-1K,1%,1/16W,EMPTY,TMP_QCS21002FB24':;

SECTION_NUMBER 1
 '@T6G_MB_LIB.T6G(SCH_1):PAGE278_I214@PURE_QUANTA.Q_RES(CHIPS)':
 C_PATH='@t6g_mb_lib.t6g(sch_1):page278_i214@pure_quanta.q_res(chips)';

PART_NAME
 R840 'Q_RES_0402LF-10K,1%,1/16W,CHIP,TMP_QCS31002FB26':;

SECTION_NUMBER 1
 '@T6G_MB_LIB.T6G(SCH_1):PAGE278_I184@PURE_QUANTA.Q_RES(CHIPS)':
 C_PATH='@t6g_mb_lib.t6g(sch_1):page278_i184@pure_quanta.q_res(chips)';

PART_NAME
 R839 'Q_RES_0402LF-1K,1%,1/16W,CHIP,TMP_QCS21002FB24':;

SECTION_NUMBER 1
 '@T6G_MB_LIB.T6G(SCH_1):PAGE278_I216@PURE_QUANTA.Q_RES(CHIPS)':
 C_PATH='@t6g_mb_lib.t6g(sch_1):page278_i216@pure_quanta.q_res(chips)';

PART_NAME
 R838 'Q_RES_0402LF-10K,1%,1/16W,EMPTY,TMP_QCS31002FB26':;

SECTION_NUMBER 1
 '@T6G_MB_LIB.T6G(SCH_1):PAGE278_I185@PURE_QUANTA.Q_RES(CHIPS)':
 C_PATH='@t6g_mb_lib.t6g(sch_1):page278_i185@pure_quanta.q_res(chips)';

PART_NAME
 JP33 'CONN3_210HP1030BR1-CONN3_210-HP1-030BR1,THLF,IO,DFHD03MS213':;

SECTION_NUMBER 1
 '@T6G_MB_LIB.T6G(SCH_1):PAGE278_I282@PURE_QUANTA.CONN3_210HP1030BR1(CHIPS)':
 C_PATH='@t6g_mb_lib.t6g(sch_1):page278_i282@pure_quanta.conn3_210hp1030br1(chip~
s)';

PART_NAME
 C2893 'Q_CAP_0402-0.1UF,25V,10%,X7R,CH4104K1B00':;

SECTION_NUMBER 1
 '@T6G_MB_LIB.T6G(SCH_1):PAGE278_I241@PURE_QUANTA.Q_CAP(CHIPS)':
 C_PATH='@t6g_mb_lib.t6g(sch_1):page278_i241@pure_quanta.q_cap(chips)';

PART_NAME
 C567 'Q_CAP_0402-0.1UF,25V,10%,X7R,CH4104K1B00':;

SECTION_NUMBER 1
 '@T6G_MB_LIB.T6G(SCH_1):PAGE278_I176@PURE_QUANTA.Q_CAP(CHIPS)':
 C_PATH='@t6g_mb_lib.t6g(sch_1):page278_i176@pure_quanta.q_cap(chips)';

PART_NAME
 Y12 'X_4S_EXS00ACS00468-26MHZ,SMLF,MISC,BG626000067':;

SECTION_NUMBER 1
 '@T6G_MB_LIB.T6G(SCH_1):PAGE267_I60@PURE_QUANTA.X_4S_EXS00ACS00468(CHIPS)':
 C_PATH='@t6g_mb_lib.t6g(sch_1):page267_i60@pure_quanta.x_4s_exs00acs00468(chips~
)';

PART_NAME
 U204 'CYUSB330468LTXI-CYUSB3304-68LTXI,SMLF,IC,AJ033040001':;

SECTION_NUMBER 1
 '@T6G_MB_LIB.T6G(SCH_1):PAGE267_I37@PURE_QUANTA.CYUSB330468LTXI(CHIPS)':
 C_PATH='@t6g_mb_lib.t6g(sch_1):page267_i37@pure_quanta.cyusb330468ltxi(chips)';

SECTION_NUMBER 2
 '@T6G_MB_LIB.T6G(SCH_1):PAGE266_I70@PURE_QUANTA.CYUSB330468LTXI(CHIPS)':
 C_PATH='@t6g_mb_lib.t6g(sch_1):page266_i70@pure_quanta.cyusb330468ltxi(chips)';

PART_NAME
 U190 'M24128BWMN6TP-M24128-BWMN6TP,SMLF,IC,AKE30Z00613':;

SECTION_NUMBER 1
 '@T6G_MB_LIB.T6G(SCH_1):PAGE267_I149@PURE_QUANTA.M24128BWMN6TP(CHIPS)':
 C_PATH='@t6g_mb_lib.t6g(sch_1):page267_i149@pure_quanta.m24128bwmn6tp(chips)';

PART_NAME
 R2162 'Q_RES_0402LF-10K,1%,1/16W,EMPTY,TMP_QCS31002FB26':;

SECTION_NUMBER 1
 '@T6G_MB_LIB.T6G(SCH_1):PAGE267_I26@PURE_QUANTA.Q_RES(CHIPS)':
 C_PATH='@t6g_mb_lib.t6g(sch_1):page267_i26@pure_quanta.q_res(chips)';

PART_NAME
 R2161 'Q_RES_0402LF-10K,1%,1/16W,CHIP,TMP_QCS31002FB26':;

SECTION_NUMBER 1
 '@T6G_MB_LIB.T6G(SCH_1):PAGE267_I23@PURE_QUANTA.Q_RES(CHIPS)':
 C_PATH='@t6g_mb_lib.t6g(sch_1):page267_i23@pure_quanta.q_res(chips)';

PART_NAME
 R2159 'Q_RES_0402LF-10K,1%,1/16W,EMPTY,TMP_QCS31002FB26':;

SECTION_NUMBER 1
 '@T6G_MB_LIB.T6G(SCH_1):PAGE267_I29@PURE_QUANTA.Q_RES(CHIPS)':
 C_PATH='@t6g_mb_lib.t6g(sch_1):page267_i29@pure_quanta.q_res(chips)';

PART_NAME
 R2158 'Q_RES_0402LF-10K,1%,1/16W,CHIP,TMP_QCS31002FB26':;

SECTION_NUMBER 1
 '@T6G_MB_LIB.T6G(SCH_1):PAGE267_I25@PURE_QUANTA.Q_RES(CHIPS)':
 C_PATH='@t6g_mb_lib.t6g(sch_1):page267_i25@pure_quanta.q_res(chips)';

PART_NAME
 R2156 'Q_RES_0603-0,5%,1/10W,CHIP,TMP_QCS00003J951':;

SECTION_NUMBER 1
 '@T6G_MB_LIB.T6G(SCH_1):PAGE267_I10@PURE_QUANTA.Q_RES(CHIPS)':
 C_PATH='@t6g_mb_lib.t6g(sch_1):page267_i10@pure_quanta.q_res(chips)';

PART_NAME
 R2154 'Q_RES_0402LF-0,5%,1/16W,CHIP,CS00002JB38':;

SECTION_NUMBER 1
 '@T6G_MB_LIB.T6G(SCH_1):PAGE267_I43@PURE_QUANTA.Q_RES(CHIPS)':
 C_PATH='@t6g_mb_lib.t6g(sch_1):page267_i43@pure_quanta.q_res(chips)';

PART_NAME
 R2152 'Q_RES_0402LF-6.04K,1%,1/16W,CHIP,CS26042FB00':;

SECTION_NUMBER 1
 '@T6G_MB_LIB.T6G(SCH_1):PAGE267_I49@PURE_QUANTA.Q_RES(CHIPS)':
 C_PATH='@t6g_mb_lib.t6g(sch_1):page267_i49@pure_quanta.q_res(chips)';

PART_NAME
 R2151 'Q_RES_0402LF-200,1%,1/16W,CHIP,CS12002FB25':;

SECTION_NUMBER 1
 '@T6G_MB_LIB.T6G(SCH_1):PAGE267_I48@PURE_QUANTA.Q_RES(CHIPS)':
 C_PATH='@t6g_mb_lib.t6g(sch_1):page267_i48@pure_quanta.q_res(chips)';

PART_NAME
 R2150 'Q_RES_0402LF-10K,1%,1/16W,EMPTY,TMP_QCS31002FB26':;

SECTION_NUMBER 1
 '@T6G_MB_LIB.T6G(SCH_1):PAGE267_I63@PURE_QUANTA.Q_RES(CHIPS)':
 C_PATH='@t6g_mb_lib.t6g(sch_1):page267_i63@pure_quanta.q_res(chips)';

PART_NAME
 R2149 'Q_RES_0402LF-10K,1%,1/16W,CHIP,TMP_QCS31002FB26':;

SECTION_NUMBER 1
 '@T6G_MB_LIB.T6G(SCH_1):PAGE267_I58@PURE_QUANTA.Q_RES(CHIPS)':
 C_PATH='@t6g_mb_lib.t6g(sch_1):page267_i58@pure_quanta.q_res(chips)';

PART_NAME
 R2148 'Q_RES_0402LF-10K,1%,1/16W,CHIP,TMP_QCS31002FB26':;

SECTION_NUMBER 1
 '@T6G_MB_LIB.T6G(SCH_1):PAGE267_I59@PURE_QUANTA.Q_RES(CHIPS)':
 C_PATH='@t6g_mb_lib.t6g(sch_1):page267_i59@pure_quanta.q_res(chips)';

PART_NAME
 R1145 'Q_RES_0402LF-10K,1%,1/16W,CHIP,TMP_QCS31002FB26':;

SECTION_NUMBER 1
 '@T6G_MB_LIB.T6G(SCH_1):PAGE267_I20@PURE_QUANTA.Q_RES(CHIPS)':
 C_PATH='@t6g_mb_lib.t6g(sch_1):page267_i20@pure_quanta.q_res(chips)';

PART_NAME
 R1144 'Q_RES_0402LF-10K,1%,1/16W,CHIP,TMP_QCS31002FB26':;

SECTION_NUMBER 1
 '@T6G_MB_LIB.T6G(SCH_1):PAGE267_I18@PURE_QUANTA.Q_RES(CHIPS)':
 C_PATH='@t6g_mb_lib.t6g(sch_1):page267_i18@pure_quanta.q_res(chips)';

PART_NAME
 R1143 'Q_RES_0402LF-10K,1%,1/16W,CHIP,TMP_QCS31002FB26':;

SECTION_NUMBER 1
 '@T6G_MB_LIB.T6G(SCH_1):PAGE267_I55@PURE_QUANTA.Q_RES(CHIPS)':
 C_PATH='@t6g_mb_lib.t6g(sch_1):page267_i55@pure_quanta.q_res(chips)';

PART_NAME
 R1142 'Q_RES_0402LF-10K,1%,1/16W,CHIP,TMP_QCS31002FB26':;

SECTION_NUMBER 1
 '@T6G_MB_LIB.T6G(SCH_1):PAGE267_I56@PURE_QUANTA.Q_RES(CHIPS)':
 C_PATH='@t6g_mb_lib.t6g(sch_1):page267_i56@pure_quanta.q_res(chips)';

PART_NAME
 R1033 'Q_RES_0402LF-0,5%,1/16W,CHIP,CS00002JB38':;

SECTION_NUMBER 1
 '@T6G_MB_LIB.T6G(SCH_1):PAGE267_I153@PURE_QUANTA.Q_RES(CHIPS)':
 C_PATH='@t6g_mb_lib.t6g(sch_1):page267_i153@pure_quanta.q_res(chips)';

PART_NAME
 R1032 'Q_RES_0402LF-0,5%,1/16W,CHIP,CS00002JB38':;

SECTION_NUMBER 1
 '@T6G_MB_LIB.T6G(SCH_1):PAGE267_I152@PURE_QUANTA.Q_RES(CHIPS)':
 C_PATH='@t6g_mb_lib.t6g(sch_1):page267_i152@pure_quanta.q_res(chips)';

PART_NAME
 R606 'Q_RES_0402LF-10K,1%,1/16W,CHIP,TMP_QCS31002FB26':;

SECTION_NUMBER 1
 '@T6G_MB_LIB.T6G(SCH_1):PAGE267_I124@PURE_QUANTA.Q_RES(CHIPS)':
 C_PATH='@t6g_mb_lib.t6g(sch_1):page267_i124@pure_quanta.q_res(chips)';

PART_NAME
 R603 'Q_RES_0402LF-10K,1%,1/16W,EMPTY,TMP_QCS31002FB26':;

SECTION_NUMBER 1
 '@T6G_MB_LIB.T6G(SCH_1):PAGE267_I120@PURE_QUANTA.Q_RES(CHIPS)':
 C_PATH='@t6g_mb_lib.t6g(sch_1):page267_i120@pure_quanta.q_res(chips)';

PART_NAME
 R602 'Q_RES_0402LF-10K,1%,1/16W,CHIP,TMP_QCS31002FB26':;

SECTION_NUMBER 1
 '@T6G_MB_LIB.T6G(SCH_1):PAGE267_I125@PURE_QUANTA.Q_RES(CHIPS)':
 C_PATH='@t6g_mb_lib.t6g(sch_1):page267_i125@pure_quanta.q_res(chips)';

PART_NAME
 R540 'Q_RES_0402LF-10K,1%,1/16W,EMPTY,TMP_QCS31002FB26':;

SECTION_NUMBER 1
 '@T6G_MB_LIB.T6G(SCH_1):PAGE267_I121@PURE_QUANTA.Q_RES(CHIPS)':
 C_PATH='@t6g_mb_lib.t6g(sch_1):page267_i121@pure_quanta.q_res(chips)';

PART_NAME
 R539 'Q_RES_0402LF-10K,1%,1/16W,EMPTY,TMP_QCS31002FB26':;

SECTION_NUMBER 1
 '@T6G_MB_LIB.T6G(SCH_1):PAGE267_I126@PURE_QUANTA.Q_RES(CHIPS)':
 C_PATH='@t6g_mb_lib.t6g(sch_1):page267_i126@pure_quanta.q_res(chips)';

PART_NAME
 R538 'Q_RES_0402LF-10K,1%,1/16W,CHIP,TMP_QCS31002FB26':;

SECTION_NUMBER 1
 '@T6G_MB_LIB.T6G(SCH_1):PAGE267_I123@PURE_QUANTA.Q_RES(CHIPS)':
 C_PATH='@t6g_mb_lib.t6g(sch_1):page267_i123@pure_quanta.q_res(chips)';

PART_NAME
 R537 'Q_RES_0402LF-33,5%,1/16W,CHIP,CS03302JB29':;

SECTION_NUMBER 1
 '@T6G_MB_LIB.T6G(SCH_1):PAGE267_I135@PURE_QUANTA.Q_RES(CHIPS)':
 C_PATH='@t6g_mb_lib.t6g(sch_1):page267_i135@pure_quanta.q_res(chips)';

PART_NAME
 R536 'Q_RES_0402LF-33,5%,1/16W,CHIP,CS03302JB29':;

SECTION_NUMBER 1
 '@T6G_MB_LIB.T6G(SCH_1):PAGE267_I136@PURE_QUANTA.Q_RES(CHIPS)':
 C_PATH='@t6g_mb_lib.t6g(sch_1):page267_i136@pure_quanta.q_res(chips)';

PART_NAME
 R428 'Q_RES_0402LF-1K,1%,1/16W,CHIP,TMP_QCS21002FB24':;

SECTION_NUMBER 1
 '@T6G_MB_LIB.T6G(SCH_1):PAGE267_I133@PURE_QUANTA.Q_RES(CHIPS)':
 C_PATH='@t6g_mb_lib.t6g(sch_1):page267_i133@pure_quanta.q_res(chips)';

PART_NAME
 C2816 'Q_CAP_0402-0.1UF,25V,10%,X7R,CH4104K1B00':;

SECTION_NUMBER 1
 '@T6G_MB_LIB.T6G(SCH_1):PAGE267_I47@PURE_QUANTA.Q_CAP(CHIPS)':
 C_PATH='@t6g_mb_lib.t6g(sch_1):page267_i47@pure_quanta.q_cap(chips)';

PART_NAME
 C2706 'Q_CAP_0402-470PF,50V,10%,X7R,TMP_QCH14706KB18':;

SECTION_NUMBER 1
 '@T6G_MB_LIB.T6G(SCH_1):PAGE267_I80@PURE_QUANTA.Q_CAP(CHIPS)':
 C_PATH='@t6g_mb_lib.t6g(sch_1):page267_i80@pure_quanta.q_cap(chips)';

PART_NAME
 C2705 'Q_CAP_C0805-22UF,16V,20%,X6S,CH6223MEA00':;

SECTION_NUMBER 1
 '@T6G_MB_LIB.T6G(SCH_1):PAGE267_I82@PURE_QUANTA.Q_CAP(CHIPS)':
 C_PATH='@t6g_mb_lib.t6g(sch_1):page267_i82@pure_quanta.q_cap(chips)';

PART_NAME
 C2704 'Q_CAP_0402-0.1UF,25V,10%,X7R,CH4104K1B00':;

SECTION_NUMBER 1
 '@T6G_MB_LIB.T6G(SCH_1):PAGE267_I173@PURE_QUANTA.Q_CAP(CHIPS)':
 C_PATH='@t6g_mb_lib.t6g(sch_1):page267_i173@pure_quanta.q_cap(chips)';

PART_NAME
 C2703 'Q_CAP_0402-0.1UF,25V,10%,X7R,CH4104K1B00':;

SECTION_NUMBER 1
 '@T6G_MB_LIB.T6G(SCH_1):PAGE267_I174@PURE_QUANTA.Q_CAP(CHIPS)':
 C_PATH='@t6g_mb_lib.t6g(sch_1):page267_i174@pure_quanta.q_cap(chips)';

PART_NAME
 C2701 'Q_CAP_0402-10PF,50V,1%,NPO,TMP_QCH0106F0B00':;

SECTION_NUMBER 1
 '@T6G_MB_LIB.T6G(SCH_1):PAGE267_I40@PURE_QUANTA.Q_CAP(CHIPS)':
 C_PATH='@t6g_mb_lib.t6g(sch_1):page267_i40@pure_quanta.q_cap(chips)';

PART_NAME
 C2700 'Q_CAP_0402-0.1UF,25V,10%,X7R,CH4104K1B00':;

SECTION_NUMBER 1
 '@T6G_MB_LIB.T6G(SCH_1):PAGE267_I44@PURE_QUANTA.Q_CAP(CHIPS)':
 C_PATH='@t6g_mb_lib.t6g(sch_1):page267_i44@pure_quanta.q_cap(chips)';

PART_NAME
 C2698 'Q_CAP_0402-0.1UF,25V,10%,X7R,CH4104K1B00':;

SECTION_NUMBER 1
 '@T6G_MB_LIB.T6G(SCH_1):PAGE267_I46@PURE_QUANTA.Q_CAP(CHIPS)':
 C_PATH='@t6g_mb_lib.t6g(sch_1):page267_i46@pure_quanta.q_cap(chips)';

PART_NAME
 C2697 'Q_CAP_0402-0.1UF,25V,10%,X7R,CH4104K1B00':;

SECTION_NUMBER 1
 '@T6G_MB_LIB.T6G(SCH_1):PAGE267_I45@PURE_QUANTA.Q_CAP(CHIPS)':
 C_PATH='@t6g_mb_lib.t6g(sch_1):page267_i45@pure_quanta.q_cap(chips)';

PART_NAME
 C2696 'Q_CAP_0402-2.2UF,10V,20%,EMPTY,TMP_QCH5222M9B07':;

SECTION_NUMBER 1
 '@T6G_MB_LIB.T6G(SCH_1):PAGE267_I65@PURE_QUANTA.Q_CAP(CHIPS)':
 C_PATH='@t6g_mb_lib.t6g(sch_1):page267_i65@pure_quanta.q_cap(chips)';

PART_NAME
 C2695 'Q_CAP_0402-10PF,50V,1%,NPO,TMP_QCH0106F0B00':;

SECTION_NUMBER 1
 '@T6G_MB_LIB.T6G(SCH_1):PAGE267_I61@PURE_QUANTA.Q_CAP(CHIPS)':
 C_PATH='@t6g_mb_lib.t6g(sch_1):page267_i61@pure_quanta.q_cap(chips)';

PART_NAME
 C902 'Q_CAP_0402-0.1UF,25V,10%,X7R,CH4104K1B00':;

SECTION_NUMBER 1
 '@T6G_MB_LIB.T6G(SCH_1):PAGE267_I178@PURE_QUANTA.Q_CAP(CHIPS)':
 C_PATH='@t6g_mb_lib.t6g(sch_1):page267_i178@pure_quanta.q_cap(chips)';

PART_NAME
 C901 'Q_CAP_0402-0.1UF,25V,10%,X7R,CH4104K1B00':;

SECTION_NUMBER 1
 '@T6G_MB_LIB.T6G(SCH_1):PAGE267_I177@PURE_QUANTA.Q_CAP(CHIPS)':
 C_PATH='@t6g_mb_lib.t6g(sch_1):page267_i177@pure_quanta.q_cap(chips)';

PART_NAME
 C566 'Q_CAP_0402-0.1UF,25V,10%,X7R,CH4104K1B00':;

SECTION_NUMBER 1
 '@T6G_MB_LIB.T6G(SCH_1):PAGE267_I130@PURE_QUANTA.Q_CAP(CHIPS)':
 C_PATH='@t6g_mb_lib.t6g(sch_1):page267_i130@pure_quanta.q_cap(chips)';

PART_NAME
 U29 'PCA9617ADP-PCA9617ADP,SMLF,IC,AL009617K02':;

SECTION_NUMBER 1
 '@T6G_MB_LIB.T6G(SCH_1):PAGE225_I1@PURE_QUANTA.PCA9617ADP(CHIPS)':
 C_PATH='@t6g_mb_lib.t6g(sch_1):page225_i1@pure_quanta.pca9617adp(chips)';

PART_NAME
 U28 'PCA9617ADP-PCA9617ADP,SMLF,IC,AL009617K02':;

SECTION_NUMBER 1
 '@T6G_MB_LIB.T6G(SCH_1):PAGE225_I26@PURE_QUANTA.PCA9617ADP(CHIPS)':
 C_PATH='@t6g_mb_lib.t6g(sch_1):page225_i26@pure_quanta.pca9617adp(chips)';

PART_NAME
 R3827 'Q_RES_0402LF-0,5%,1/16W,CHIP,CS00002JB38':;

SECTION_NUMBER 1
 '@T6G_MB_LIB.T6G(SCH_1):PAGE225_I45@PURE_QUANTA.Q_RES(CHIPS)':
 C_PATH='@t6g_mb_lib.t6g(sch_1):page225_i45@pure_quanta.q_res(chips)';

PART_NAME
 R3826 'Q_RES_0402LF-0,5%,1/16W,CHIP,CS00002JB38':;

SECTION_NUMBER 1
 '@T6G_MB_LIB.T6G(SCH_1):PAGE225_I46@PURE_QUANTA.Q_RES(CHIPS)':
 C_PATH='@t6g_mb_lib.t6g(sch_1):page225_i46@pure_quanta.q_res(chips)';

PART_NAME
 R3763 'Q_RES_0402LF-33,5%,1/16W,CHIP,CS03302JB29':;

SECTION_NUMBER 1
 '@T6G_MB_LIB.T6G(SCH_1):PAGE225_I41@PURE_QUANTA.Q_RES(CHIPS)':
 C_PATH='@t6g_mb_lib.t6g(sch_1):page225_i41@pure_quanta.q_res(chips)';

PART_NAME
 R3762 'Q_RES_0402LF-33,5%,1/16W,CHIP,CS03302JB29':;

SECTION_NUMBER 1
 '@T6G_MB_LIB.T6G(SCH_1):PAGE225_I43@PURE_QUANTA.Q_RES(CHIPS)':
 C_PATH='@t6g_mb_lib.t6g(sch_1):page225_i43@pure_quanta.q_res(chips)';

PART_NAME
 R968 'Q_RES_0402LF-1K,1%,1/16W,CHIP,TMP_QCS21002FB24':;

SECTION_NUMBER 1
 '@T6G_MB_LIB.T6G(SCH_1):PAGE225_I21@PURE_QUANTA.Q_RES(CHIPS)':
 C_PATH='@t6g_mb_lib.t6g(sch_1):page225_i21@pure_quanta.q_res(chips)';

PART_NAME
 R967 'Q_RES_0402LF-1K,1%,1/16W,CHIP,TMP_QCS21002FB24':;

SECTION_NUMBER 1
 '@T6G_MB_LIB.T6G(SCH_1):PAGE225_I7@PURE_QUANTA.Q_RES(CHIPS)':
 C_PATH='@t6g_mb_lib.t6g(sch_1):page225_i7@pure_quanta.q_res(chips)';

PART_NAME
 R966 'Q_RES_0402LF-1K,1%,1/16W,CHIP,TMP_QCS21002FB24':;

SECTION_NUMBER 1
 '@T6G_MB_LIB.T6G(SCH_1):PAGE225_I22@PURE_QUANTA.Q_RES(CHIPS)':
 C_PATH='@t6g_mb_lib.t6g(sch_1):page225_i22@pure_quanta.q_res(chips)';

PART_NAME
 R965 'Q_RES_0402LF-1K,1%,1/16W,CHIP,TMP_QCS21002FB24':;

SECTION_NUMBER 1
 '@T6G_MB_LIB.T6G(SCH_1):PAGE225_I8@PURE_QUANTA.Q_RES(CHIPS)':
 C_PATH='@t6g_mb_lib.t6g(sch_1):page225_i8@pure_quanta.q_res(chips)';

PART_NAME
 R964 'Q_RES_0402LF-240,1%,1/16W,CHIP,CS12402FB03':;

SECTION_NUMBER 1
 '@T6G_MB_LIB.T6G(SCH_1):PAGE225_I32@PURE_QUANTA.Q_RES(CHIPS)':
 C_PATH='@t6g_mb_lib.t6g(sch_1):page225_i32@pure_quanta.q_res(chips)';

PART_NAME
 R963 'Q_RES_0402LF-240,1%,1/16W,CHIP,CS12402FB03':;

SECTION_NUMBER 1
 '@T6G_MB_LIB.T6G(SCH_1):PAGE225_I34@PURE_QUANTA.Q_RES(CHIPS)':
 C_PATH='@t6g_mb_lib.t6g(sch_1):page225_i34@pure_quanta.q_res(chips)';

PART_NAME
 R962 'Q_RES_0402LF-33,5%,1/16W,CHIP,CS03302JB29':;

SECTION_NUMBER 1
 '@T6G_MB_LIB.T6G(SCH_1):PAGE225_I36@PURE_QUANTA.Q_RES(CHIPS)':
 C_PATH='@t6g_mb_lib.t6g(sch_1):page225_i36@pure_quanta.q_res(chips)';

PART_NAME
 R961 'Q_RES_0402LF-33,5%,1/16W,CHIP,CS03302JB29':;

SECTION_NUMBER 1
 '@T6G_MB_LIB.T6G(SCH_1):PAGE225_I35@PURE_QUANTA.Q_RES(CHIPS)':
 C_PATH='@t6g_mb_lib.t6g(sch_1):page225_i35@pure_quanta.q_res(chips)';

PART_NAME
 R960 'Q_RES_0402LF-33,5%,1/16W,CHIP,CS03302JB29':;

SECTION_NUMBER 1
 '@T6G_MB_LIB.T6G(SCH_1):PAGE225_I18@PURE_QUANTA.Q_RES(CHIPS)':
 C_PATH='@t6g_mb_lib.t6g(sch_1):page225_i18@pure_quanta.q_res(chips)';

PART_NAME
 R911 'Q_RES_0402LF-240,1%,1/16W,CHIP,CS12402FB03':;

SECTION_NUMBER 1
 '@T6G_MB_LIB.T6G(SCH_1):PAGE225_I15@PURE_QUANTA.Q_RES(CHIPS)':
 C_PATH='@t6g_mb_lib.t6g(sch_1):page225_i15@pure_quanta.q_res(chips)';

PART_NAME
 R910 'Q_RES_0402LF-240,1%,1/16W,CHIP,CS12402FB03':;

SECTION_NUMBER 1
 '@T6G_MB_LIB.T6G(SCH_1):PAGE225_I17@PURE_QUANTA.Q_RES(CHIPS)':
 C_PATH='@t6g_mb_lib.t6g(sch_1):page225_i17@pure_quanta.q_res(chips)';

PART_NAME
 R909 'Q_RES_0402LF-33,5%,1/16W,CHIP,CS03302JB29':;

SECTION_NUMBER 1
 '@T6G_MB_LIB.T6G(SCH_1):PAGE225_I19@PURE_QUANTA.Q_RES(CHIPS)':
 C_PATH='@t6g_mb_lib.t6g(sch_1):page225_i19@pure_quanta.q_res(chips)';

PART_NAME
 C562 'Q_CAP_0402-0.1UF,25V,10%,X7R,CH4104K1B00':;

SECTION_NUMBER 1
 '@T6G_MB_LIB.T6G(SCH_1):PAGE225_I24@PURE_QUANTA.Q_CAP(CHIPS)':
 C_PATH='@t6g_mb_lib.t6g(sch_1):page225_i24@pure_quanta.q_cap(chips)';

PART_NAME
 C561 'Q_CAP_0402-0.1UF,25V,10%,X7R,CH4104K1B00':;

SECTION_NUMBER 1
 '@T6G_MB_LIB.T6G(SCH_1):PAGE225_I11@PURE_QUANTA.Q_CAP(CHIPS)':
 C_PATH='@t6g_mb_lib.t6g(sch_1):page225_i11@pure_quanta.q_cap(chips)';

PART_NAME
 C560 'Q_CAP_0402-0.1UF,25V,10%,X7R,CH4104K1B00':;

SECTION_NUMBER 1
 '@T6G_MB_LIB.T6G(SCH_1):PAGE225_I29@PURE_QUANTA.Q_CAP(CHIPS)':
 C_PATH='@t6g_mb_lib.t6g(sch_1):page225_i29@pure_quanta.q_cap(chips)';

PART_NAME
 C559 'Q_CAP_0402-0.1UF,25V,10%,X7R,CH4104K1B00':;

SECTION_NUMBER 1
 '@T6G_MB_LIB.T6G(SCH_1):PAGE225_I13@PURE_QUANTA.Q_CAP(CHIPS)':
 C_PATH='@t6g_mb_lib.t6g(sch_1):page225_i13@pure_quanta.q_cap(chips)';

PART_NAME
 U26 'GTL2014PW-GTL2014PW,SMLF,IC,AL002014K01':;

SECTION_NUMBER 1
 '@T6G_MB_LIB.T6G(SCH_1):PAGE85_I85@PURE_QUANTA.GTL2014PW(CHIPS)':
 C_PATH='@t6g_mb_lib.t6g(sch_1):page85_i85@pure_quanta.gtl2014pw(chips)';

PART_NAME
 U25 'GTL2014PW-GTL2014PW,SMLF,IC,AL002014K01':;

SECTION_NUMBER 1
 '@T6G_MB_LIB.T6G(SCH_1):PAGE85_I72@PURE_QUANTA.GTL2014PW(CHIPS)':
 C_PATH='@t6g_mb_lib.t6g(sch_1):page85_i72@pure_quanta.gtl2014pw(chips)';

PART_NAME
 R2036 'Q_RES_0402LF-0,5%,1/16W,EMPTY,CS00002JB38':;

SECTION_NUMBER 1
 '@T6G_MB_LIB.T6G(SCH_1):PAGE85_I70@PURE_QUANTA.Q_RES(CHIPS)':
 C_PATH='@t6g_mb_lib.t6g(sch_1):page85_i70@pure_quanta.q_res(chips)';

PART_NAME
 R939 'Q_RES_0402LF-10K,1%,1/16W,CHIP,TMP_QCS31002FB26':;

SECTION_NUMBER 1
 '@T6G_MB_LIB.T6G(SCH_1):PAGE85_I115@PURE_QUANTA.Q_RES(CHIPS)':
 C_PATH='@t6g_mb_lib.t6g(sch_1):page85_i115@pure_quanta.q_res(chips)';

PART_NAME
 R938 'Q_RES_0402LF-10K,1%,1/16W,CHIP,TMP_QCS31002FB26':;

SECTION_NUMBER 1
 '@T6G_MB_LIB.T6G(SCH_1):PAGE85_I100@PURE_QUANTA.Q_RES(CHIPS)':
 C_PATH='@t6g_mb_lib.t6g(sch_1):page85_i100@pure_quanta.q_res(chips)';

PART_NAME
 R937 'Q_RES_0402LF-10K,1%,1/16W,CHIP,TMP_QCS31002FB26':;

SECTION_NUMBER 1
 '@T6G_MB_LIB.T6G(SCH_1):PAGE85_I116@PURE_QUANTA.Q_RES(CHIPS)':
 C_PATH='@t6g_mb_lib.t6g(sch_1):page85_i116@pure_quanta.q_res(chips)';

PART_NAME
 R936 'Q_RES_0402LF-10K,1%,1/16W,CHIP,TMP_QCS31002FB26':;

SECTION_NUMBER 1
 '@T6G_MB_LIB.T6G(SCH_1):PAGE85_I102@PURE_QUANTA.Q_RES(CHIPS)':
 C_PATH='@t6g_mb_lib.t6g(sch_1):page85_i102@pure_quanta.q_res(chips)';

PART_NAME
 R935 'Q_RES_0402LF-10K,1%,1/16W,CHIP,TMP_QCS31002FB26':;

SECTION_NUMBER 1
 '@T6G_MB_LIB.T6G(SCH_1):PAGE85_I117@PURE_QUANTA.Q_RES(CHIPS)':
 C_PATH='@t6g_mb_lib.t6g(sch_1):page85_i117@pure_quanta.q_res(chips)';

PART_NAME
 R934 'Q_RES_0402LF-10K,1%,1/16W,CHIP,TMP_QCS31002FB26':;

SECTION_NUMBER 1
 '@T6G_MB_LIB.T6G(SCH_1):PAGE85_I103@PURE_QUANTA.Q_RES(CHIPS)':
 C_PATH='@t6g_mb_lib.t6g(sch_1):page85_i103@pure_quanta.q_res(chips)';

PART_NAME
 R933 'Q_RES_0402LF-10K,1%,1/16W,CHIP,TMP_QCS31002FB26':;

SECTION_NUMBER 1
 '@T6G_MB_LIB.T6G(SCH_1):PAGE85_I114@PURE_QUANTA.Q_RES(CHIPS)':
 C_PATH='@t6g_mb_lib.t6g(sch_1):page85_i114@pure_quanta.q_res(chips)';

PART_NAME
 R932 'Q_RES_0402LF-10K,1%,1/16W,CHIP,TMP_QCS31002FB26':;

SECTION_NUMBER 1
 '@T6G_MB_LIB.T6G(SCH_1):PAGE85_I104@PURE_QUANTA.Q_RES(CHIPS)':
 C_PATH='@t6g_mb_lib.t6g(sch_1):page85_i104@pure_quanta.q_res(chips)';

PART_NAME
 R876 'Q_RES_0402LF-1K,1%,1/16W,CHIP,TMP_QCS21002FB24':;

SECTION_NUMBER 1
 '@T6G_MB_LIB.T6G(SCH_1):PAGE85_I79@PURE_QUANTA.Q_RES(CHIPS)':
 C_PATH='@t6g_mb_lib.t6g(sch_1):page85_i79@pure_quanta.q_res(chips)';

PART_NAME
 R875 'Q_RES_0402LF-1K,1%,1/16W,CHIP,TMP_QCS21002FB24':;

SECTION_NUMBER 1
 '@T6G_MB_LIB.T6G(SCH_1):PAGE85_I66@PURE_QUANTA.Q_RES(CHIPS)':
 C_PATH='@t6g_mb_lib.t6g(sch_1):page85_i66@pure_quanta.q_res(chips)';

PART_NAME
 R874 'Q_RES_0402LF-0,5%,1/16W,EMPTY,CS00002JB38':;

SECTION_NUMBER 1
 '@T6G_MB_LIB.T6G(SCH_1):PAGE85_I83@PURE_QUANTA.Q_RES(CHIPS)':
 C_PATH='@t6g_mb_lib.t6g(sch_1):page85_i83@pure_quanta.q_res(chips)';

PART_NAME
 R873 'Q_RES_0402LF-0,5%,1/16W,EMPTY,CS00002JB38':;

SECTION_NUMBER 1
 '@T6G_MB_LIB.T6G(SCH_1):PAGE85_I82@PURE_QUANTA.Q_RES(CHIPS)':
 C_PATH='@t6g_mb_lib.t6g(sch_1):page85_i82@pure_quanta.q_res(chips)';

PART_NAME
 R872 'Q_RES_0402LF-0,5%,1/16W,EMPTY,CS00002JB38':;

SECTION_NUMBER 1
 '@T6G_MB_LIB.T6G(SCH_1):PAGE85_I81@PURE_QUANTA.Q_RES(CHIPS)':
 C_PATH='@t6g_mb_lib.t6g(sch_1):page85_i81@pure_quanta.q_res(chips)';

PART_NAME
 R871 'Q_RES_0402LF-0,5%,1/16W,EMPTY,CS00002JB38':;

SECTION_NUMBER 1
 '@T6G_MB_LIB.T6G(SCH_1):PAGE85_I80@PURE_QUANTA.Q_RES(CHIPS)':
 C_PATH='@t6g_mb_lib.t6g(sch_1):page85_i80@pure_quanta.q_res(chips)';

PART_NAME
 R870 'Q_RES_0402LF-0,5%,1/16W,EMPTY,CS00002JB38':;

SECTION_NUMBER 1
 '@T6G_MB_LIB.T6G(SCH_1):PAGE85_I69@PURE_QUANTA.Q_RES(CHIPS)':
 C_PATH='@t6g_mb_lib.t6g(sch_1):page85_i69@pure_quanta.q_res(chips)';

PART_NAME
 R868 'Q_RES_0402LF-0,5%,1/16W,EMPTY,CS00002JB38':;

SECTION_NUMBER 1
 '@T6G_MB_LIB.T6G(SCH_1):PAGE85_I68@PURE_QUANTA.Q_RES(CHIPS)':
 C_PATH='@t6g_mb_lib.t6g(sch_1):page85_i68@pure_quanta.q_res(chips)';

PART_NAME
 R867 'Q_RES_0402LF-0,5%,1/16W,EMPTY,CS00002JB38':;

SECTION_NUMBER 1
 '@T6G_MB_LIB.T6G(SCH_1):PAGE85_I67@PURE_QUANTA.Q_RES(CHIPS)':
 C_PATH='@t6g_mb_lib.t6g(sch_1):page85_i67@pure_quanta.q_res(chips)';

PART_NAME
 R866 'Q_RES_0402LF-1K,1%,1/16W,CHIP,TMP_QCS21002FB24':;

SECTION_NUMBER 1
 '@T6G_MB_LIB.T6G(SCH_1):PAGE85_I75@PURE_QUANTA.Q_RES(CHIPS)':
 C_PATH='@t6g_mb_lib.t6g(sch_1):page85_i75@pure_quanta.q_res(chips)';

PART_NAME
 R865 'Q_RES_0402LF-4.32K,1%,1/16W,CHIP,TMP_QCS24322FB14':;

SECTION_NUMBER 1
 '@T6G_MB_LIB.T6G(SCH_1):PAGE85_I74@PURE_QUANTA.Q_RES(CHIPS)':
 C_PATH='@t6g_mb_lib.t6g(sch_1):page85_i74@pure_quanta.q_res(chips)';

PART_NAME
 R864 'Q_RES_0402LF-1K,1%,1/16W,CHIP,TMP_QCS21002FB24':;

SECTION_NUMBER 1
 '@T6G_MB_LIB.T6G(SCH_1):PAGE85_I64@PURE_QUANTA.Q_RES(CHIPS)':
 C_PATH='@t6g_mb_lib.t6g(sch_1):page85_i64@pure_quanta.q_res(chips)';

PART_NAME
 R863 'Q_RES_0402LF-4.32K,1%,1/16W,CHIP,TMP_QCS24322FB14':;

SECTION_NUMBER 1
 '@T6G_MB_LIB.T6G(SCH_1):PAGE85_I47@PURE_QUANTA.Q_RES(CHIPS)':
 C_PATH='@t6g_mb_lib.t6g(sch_1):page85_i47@pure_quanta.q_res(chips)';

PART_NAME
 R862 'Q_RES_0402LF-0,5%,1/16W,CHIP,CS00002JB38':;

SECTION_NUMBER 1
 '@T6G_MB_LIB.T6G(SCH_1):PAGE85_I120@PURE_QUANTA.Q_RES(CHIPS)':
 C_PATH='@t6g_mb_lib.t6g(sch_1):page85_i120@pure_quanta.q_res(chips)';

PART_NAME
 R861 'Q_RES_0402LF-0,5%,1/16W,CHIP,CS00002JB38':;

SECTION_NUMBER 1
 '@T6G_MB_LIB.T6G(SCH_1):PAGE85_I119@PURE_QUANTA.Q_RES(CHIPS)':
 C_PATH='@t6g_mb_lib.t6g(sch_1):page85_i119@pure_quanta.q_res(chips)';

PART_NAME
 R860 'Q_RES_0402LF-0,5%,1/16W,CHIP,CS00002JB38':;

SECTION_NUMBER 1
 '@T6G_MB_LIB.T6G(SCH_1):PAGE85_I118@PURE_QUANTA.Q_RES(CHIPS)':
 C_PATH='@t6g_mb_lib.t6g(sch_1):page85_i118@pure_quanta.q_res(chips)';

PART_NAME
 R859 'Q_RES_0402LF-0,5%,1/16W,CHIP,CS00002JB38':;

SECTION_NUMBER 1
 '@T6G_MB_LIB.T6G(SCH_1):PAGE85_I113@PURE_QUANTA.Q_RES(CHIPS)':
 C_PATH='@t6g_mb_lib.t6g(sch_1):page85_i113@pure_quanta.q_res(chips)';

PART_NAME
 R858 'Q_RES_0402LF-0,5%,1/16W,EMPTY,CS00002JB38':;

SECTION_NUMBER 1
 '@T6G_MB_LIB.T6G(SCH_1):PAGE85_I99@PURE_QUANTA.Q_RES(CHIPS)':
 C_PATH='@t6g_mb_lib.t6g(sch_1):page85_i99@pure_quanta.q_res(chips)';

PART_NAME
 R857 'Q_RES_0402LF-0,5%,1/16W,EMPTY,CS00002JB38':;

SECTION_NUMBER 1
 '@T6G_MB_LIB.T6G(SCH_1):PAGE85_I97@PURE_QUANTA.Q_RES(CHIPS)':
 C_PATH='@t6g_mb_lib.t6g(sch_1):page85_i97@pure_quanta.q_res(chips)';

PART_NAME
 R856 'Q_RES_0402LF-0,5%,1/16W,EMPTY,CS00002JB38':;

SECTION_NUMBER 1
 '@T6G_MB_LIB.T6G(SCH_1):PAGE85_I98@PURE_QUANTA.Q_RES(CHIPS)':
 C_PATH='@t6g_mb_lib.t6g(sch_1):page85_i98@pure_quanta.q_res(chips)';

PART_NAME
 R855 'Q_RES_0402LF-0,5%,1/16W,EMPTY,CS00002JB38':;

SECTION_NUMBER 1
 '@T6G_MB_LIB.T6G(SCH_1):PAGE85_I96@PURE_QUANTA.Q_RES(CHIPS)':
 C_PATH='@t6g_mb_lib.t6g(sch_1):page85_i96@pure_quanta.q_res(chips)';

PART_NAME
 R854 'Q_RES_0402LF-0,5%,1/16W,CHIP,CS00002JB38':;

SECTION_NUMBER 1
 '@T6G_MB_LIB.T6G(SCH_1):PAGE85_I93@PURE_QUANTA.Q_RES(CHIPS)':
 C_PATH='@t6g_mb_lib.t6g(sch_1):page85_i93@pure_quanta.q_res(chips)';

PART_NAME
 R853 'Q_RES_0402LF-0,5%,1/16W,CHIP,CS00002JB38':;

SECTION_NUMBER 1
 '@T6G_MB_LIB.T6G(SCH_1):PAGE85_I94@PURE_QUANTA.Q_RES(CHIPS)':
 C_PATH='@t6g_mb_lib.t6g(sch_1):page85_i94@pure_quanta.q_res(chips)';

PART_NAME
 R852 'Q_RES_0402LF-0,5%,1/16W,CHIP,CS00002JB38':;

SECTION_NUMBER 1
 '@T6G_MB_LIB.T6G(SCH_1):PAGE85_I92@PURE_QUANTA.Q_RES(CHIPS)':
 C_PATH='@t6g_mb_lib.t6g(sch_1):page85_i92@pure_quanta.q_res(chips)';

PART_NAME
 R851 'Q_RES_0402LF-0,5%,1/16W,CHIP,CS00002JB38':;

SECTION_NUMBER 1
 '@T6G_MB_LIB.T6G(SCH_1):PAGE85_I91@PURE_QUANTA.Q_RES(CHIPS)':
 C_PATH='@t6g_mb_lib.t6g(sch_1):page85_i91@pure_quanta.q_res(chips)';

PART_NAME
 R850 'Q_RES_0402LF-0,5%,1/16W,EMPTY,CS00002JB38':;

SECTION_NUMBER 1
 '@T6G_MB_LIB.T6G(SCH_1):PAGE85_I89@PURE_QUANTA.Q_RES(CHIPS)':
 C_PATH='@t6g_mb_lib.t6g(sch_1):page85_i89@pure_quanta.q_res(chips)';

PART_NAME
 R849 'Q_RES_0402LF-0,5%,1/16W,EMPTY,CS00002JB38':;

SECTION_NUMBER 1
 '@T6G_MB_LIB.T6G(SCH_1):PAGE85_I90@PURE_QUANTA.Q_RES(CHIPS)':
 C_PATH='@t6g_mb_lib.t6g(sch_1):page85_i90@pure_quanta.q_res(chips)';

PART_NAME
 R848 'Q_RES_0402LF-0,5%,1/16W,EMPTY,CS00002JB38':;

SECTION_NUMBER 1
 '@T6G_MB_LIB.T6G(SCH_1):PAGE85_I87@PURE_QUANTA.Q_RES(CHIPS)':
 C_PATH='@t6g_mb_lib.t6g(sch_1):page85_i87@pure_quanta.q_res(chips)';

PART_NAME
 R847 'Q_RES_0402LF-0,5%,1/16W,EMPTY,CS00002JB38':;

SECTION_NUMBER 1
 '@T6G_MB_LIB.T6G(SCH_1):PAGE85_I88@PURE_QUANTA.Q_RES(CHIPS)':
 C_PATH='@t6g_mb_lib.t6g(sch_1):page85_i88@pure_quanta.q_res(chips)';

PART_NAME
 C558 'Q_CAP_0402-0.1UF,25V,10%,X7R,CH4104K1B00':;

SECTION_NUMBER 1
 '@T6G_MB_LIB.T6G(SCH_1):PAGE85_I62@PURE_QUANTA.Q_CAP(CHIPS)':
 C_PATH='@t6g_mb_lib.t6g(sch_1):page85_i62@pure_quanta.q_cap(chips)';

PART_NAME
 C557 'Q_CAP_0402-0.1UF,25V,10%,X7R,CH4104K1B00':;

SECTION_NUMBER 1
 '@T6G_MB_LIB.T6G(SCH_1):PAGE85_I54@PURE_QUANTA.Q_CAP(CHIPS)':
 C_PATH='@t6g_mb_lib.t6g(sch_1):page85_i54@pure_quanta.q_cap(chips)';

PART_NAME
 C556 'Q_CAP_C0402-1UF,25V,10%,X6S,CH5104KEB02':;

SECTION_NUMBER 1
 '@T6G_MB_LIB.T6G(SCH_1):PAGE85_I78@PURE_QUANTA.Q_CAP(CHIPS)':
 C_PATH='@t6g_mb_lib.t6g(sch_1):page85_i78@pure_quanta.q_cap(chips)';

PART_NAME
 C555 'Q_CAP_C0402-1UF,25V,10%,X6S,CH5104KEB02':;

SECTION_NUMBER 1
 '@T6G_MB_LIB.T6G(SCH_1):PAGE85_I48@PURE_QUANTA.Q_CAP(CHIPS)':
 C_PATH='@t6g_mb_lib.t6g(sch_1):page85_i48@pure_quanta.q_cap(chips)';

PART_NAME
 R1743 'Q_RES_0402LF-0,5%,1/16W,EMPTY,CS00002JB38':;

SECTION_NUMBER 1
 '@T6G_MB_LIB.T6G(SCH_1):PAGE245_I5@PURE_QUANTA.Q_RES(CHIPS)':
 C_PATH='@t6g_mb_lib.t6g(sch_1):page245_i5@pure_quanta.q_res(chips)';

PART_NAME
 R931 'Q_RES_0402LF-0,5%,1/16W,CHIP,CS00002JB38':;

SECTION_NUMBER 1
 '@T6G_MB_LIB.T6G(SCH_1):PAGE245_I4@PURE_QUANTA.Q_RES(CHIPS)':
 C_PATH='@t6g_mb_lib.t6g(sch_1):page245_i4@pure_quanta.q_res(chips)';

PART_NAME
 R930 'Q_RES_0402LF-4.7K,1%,1/16W,CHIP,CS24702FB10':;

SECTION_NUMBER 1
 '@T6G_MB_LIB.T6G(SCH_1):PAGE245_I28@PURE_QUANTA.Q_RES(CHIPS)':
 C_PATH='@t6g_mb_lib.t6g(sch_1):page245_i28@pure_quanta.q_res(chips)';

PART_NAME
 R929 'Q_RES_0402LF-10K,1%,1/16W,CHIP,TMP_QCS31002FB26':;

SECTION_NUMBER 1
 '@T6G_MB_LIB.T6G(SCH_1):PAGE245_I25@PURE_QUANTA.Q_RES(CHIPS)':
 C_PATH='@t6g_mb_lib.t6g(sch_1):page245_i25@pure_quanta.q_res(chips)';

PART_NAME
 R928 'Q_RES_0402LF-10K,1%,1/16W,CHIP,TMP_QCS31002FB26':;

SECTION_NUMBER 1
 '@T6G_MB_LIB.T6G(SCH_1):PAGE245_I26@PURE_QUANTA.Q_RES(CHIPS)':
 C_PATH='@t6g_mb_lib.t6g(sch_1):page245_i26@pure_quanta.q_res(chips)';

PART_NAME
 R927 'Q_RES_0402LF-10K,1%,1/16W,CHIP,TMP_QCS31002FB26':;

SECTION_NUMBER 1
 '@T6G_MB_LIB.T6G(SCH_1):PAGE245_I27@PURE_QUANTA.Q_RES(CHIPS)':
 C_PATH='@t6g_mb_lib.t6g(sch_1):page245_i27@pure_quanta.q_res(chips)';

PART_NAME
 R920 'Q_RES_0402LF-1K,5%,1/16W,EMPTY,TMP_QCS21002JB34':;

SECTION_NUMBER 1
 '@T6G_MB_LIB.T6G(SCH_1):PAGE245_I22@PURE_QUANTA.Q_RES(CHIPS)':
 C_PATH='@t6g_mb_lib.t6g(sch_1):page245_i22@pure_quanta.q_res(chips)';

PART_NAME
 R919 'Q_RES_0402LF-10K,1%,1/16W,CHIP,TMP_QCS31002FB26':;

SECTION_NUMBER 1
 '@T6G_MB_LIB.T6G(SCH_1):PAGE245_I21@PURE_QUANTA.Q_RES(CHIPS)':
 C_PATH='@t6g_mb_lib.t6g(sch_1):page245_i21@pure_quanta.q_res(chips)';

PART_NAME
 R806 'Q_RES_0402LF-33,5%,1/16W,CHIP,CS03302JB29':;

SECTION_NUMBER 1
 '@T6G_MB_LIB.T6G(SCH_1):PAGE245_I33@PURE_QUANTA.Q_RES(CHIPS)':
 C_PATH='@t6g_mb_lib.t6g(sch_1):page245_i33@pure_quanta.q_res(chips)';

PART_NAME
 R805 'Q_RES_0402LF-33,5%,1/16W,CHIP,CS03302JB29':;

SECTION_NUMBER 1
 '@T6G_MB_LIB.T6G(SCH_1):PAGE245_I32@PURE_QUANTA.Q_RES(CHIPS)':
 C_PATH='@t6g_mb_lib.t6g(sch_1):page245_i32@pure_quanta.q_res(chips)';

PART_NAME
 R804 'Q_RES_0402LF-33,5%,1/16W,CHIP,CS03302JB29':;

SECTION_NUMBER 1
 '@T6G_MB_LIB.T6G(SCH_1):PAGE245_I31@PURE_QUANTA.Q_RES(CHIPS)':
 C_PATH='@t6g_mb_lib.t6g(sch_1):page245_i31@pure_quanta.q_res(chips)';

PART_NAME
 R803 'Q_RES_0402LF-33,5%,1/16W,CHIP,CS03302JB29':;

SECTION_NUMBER 1
 '@T6G_MB_LIB.T6G(SCH_1):PAGE245_I30@PURE_QUANTA.Q_RES(CHIPS)':
 C_PATH='@t6g_mb_lib.t6g(sch_1):page245_i30@pure_quanta.q_res(chips)';

PART_NAME
 J43 'CONN10_G2100HT0038071-CONN10_G2100HT0038-071,THLF,IO,DFHD10MS268':;

SECTION_NUMBER 1
 '@T6G_MB_LIB.T6G(SCH_1):PAGE245_I3@PURE_QUANTA.CONN10_G2100HT0038071(CHIPS)':
 C_PATH='@t6g_mb_lib.t6g(sch_1):page245_i3@pure_quanta.conn10_g2100ht0038071(chi~
ps)';

PART_NAME
 C563 'Q_CAP_C0805-10UF,25V,10%,X6S,CH6104KEA00':;

SECTION_NUMBER 1
 '@T6G_MB_LIB.T6G(SCH_1):PAGE245_I7@PURE_QUANTA.Q_CAP(CHIPS)':
 C_PATH='@t6g_mb_lib.t6g(sch_1):page245_i7@pure_quanta.q_cap(chips)';

PART_NAME
 C554 'Q_CAP_0402-0.1UF,25V,10%,X7R,CH4104K1B00':;

SECTION_NUMBER 1
 '@T6G_MB_LIB.T6G(SCH_1):PAGE245_I8@PURE_QUANTA.Q_CAP(CHIPS)':
 C_PATH='@t6g_mb_lib.t6g(sch_1):page245_i8@pure_quanta.q_cap(chips)';

PART_NAME
 R3825 'Q_RES_0402LF-33,5%,1/16W,CHIP,CS03302JB29':;

SECTION_NUMBER 1
 '@T6G_MB_LIB.T6G(SCH_1):PAGE197_I284@PURE_QUANTA.Q_RES(CHIPS)':
 C_PATH='@t6g_mb_lib.t6g(sch_1):page197_i284@pure_quanta.q_res(chips)';

PART_NAME
 R1615 'Q_RES_0402LF-10K,1%,1/16W,CHIP,TMP_QCS31002FB26':;

SECTION_NUMBER 1
 '@T6G_MB_LIB.T6G(SCH_1):PAGE197_I201@PURE_QUANTA.Q_RES(CHIPS)':
 C_PATH='@t6g_mb_lib.t6g(sch_1):page197_i201@pure_quanta.q_res(chips)';

PART_NAME
 R1614 'Q_RES_0402LF-150,5%,1/16W,CHIP,TMP_QCS11502JB22':;

SECTION_NUMBER 1
 '@T6G_MB_LIB.T6G(SCH_1):PAGE197_I205@PURE_QUANTA.Q_RES(CHIPS)':
 C_PATH='@t6g_mb_lib.t6g(sch_1):page197_i205@pure_quanta.q_res(chips)';

PART_NAME
 R1613 'Q_RES_0402LF-33,5%,1/16W,CHIP,CS03302JB29':;

SECTION_NUMBER 1
 '@T6G_MB_LIB.T6G(SCH_1):PAGE197_I228@PURE_QUANTA.Q_RES(CHIPS)':
 C_PATH='@t6g_mb_lib.t6g(sch_1):page197_i228@pure_quanta.q_res(chips)';

PART_NAME
 R1612 'Q_RES_0402LF-1K,1%,1/16W,CHIP,TMP_QCS21002FB24':;

SECTION_NUMBER 1
 '@T6G_MB_LIB.T6G(SCH_1):PAGE197_I225@PURE_QUANTA.Q_RES(CHIPS)':
 C_PATH='@t6g_mb_lib.t6g(sch_1):page197_i225@pure_quanta.q_res(chips)';

PART_NAME
 R1611 'Q_RES_0402LF-1K,1%,1/16W,CHIP,TMP_QCS21002FB24':;

SECTION_NUMBER 1
 '@T6G_MB_LIB.T6G(SCH_1):PAGE197_I230@PURE_QUANTA.Q_RES(CHIPS)':
 C_PATH='@t6g_mb_lib.t6g(sch_1):page197_i230@pure_quanta.q_res(chips)';

PART_NAME
 R1610 'Q_RES_0402LF-1K,1%,1/16W,EMPTY,TMP_QCS21002FB24':;

SECTION_NUMBER 1
 '@T6G_MB_LIB.T6G(SCH_1):PAGE197_I232@PURE_QUANTA.Q_RES(CHIPS)':
 C_PATH='@t6g_mb_lib.t6g(sch_1):page197_i232@pure_quanta.q_res(chips)';

PART_NAME
 R1609 'Q_RES_0402LF-0,5%,1/16W,CHIP,CS00002JB38':;

SECTION_NUMBER 1
 '@T6G_MB_LIB.T6G(SCH_1):PAGE197_I276@PURE_QUANTA.Q_RES(CHIPS)':
 C_PATH='@t6g_mb_lib.t6g(sch_1):page197_i276@pure_quanta.q_res(chips)';

PART_NAME
 R1608 'Q_RES_0402LF-0,5%,1/16W,CHIP,CS00002JB38':;

SECTION_NUMBER 1
 '@T6G_MB_LIB.T6G(SCH_1):PAGE197_I264@PURE_QUANTA.Q_RES(CHIPS)':
 C_PATH='@t6g_mb_lib.t6g(sch_1):page197_i264@pure_quanta.q_res(chips)';

PART_NAME
 R1607 'Q_RES_0402LF-10,1%,1/16W,CHIP,TMP_QCS01002FB21':;

SECTION_NUMBER 1
 '@T6G_MB_LIB.T6G(SCH_1):PAGE197_I263@PURE_QUANTA.Q_RES(CHIPS)':
 C_PATH='@t6g_mb_lib.t6g(sch_1):page197_i263@pure_quanta.q_res(chips)';

PART_NAME
 R1605 'Q_RES_0402LF-0,5%,1/16W,CHIP,CS00002JB38':;

SECTION_NUMBER 1
 '@T6G_MB_LIB.T6G(SCH_1):PAGE197_I262@PURE_QUANTA.Q_RES(CHIPS)':
 C_PATH='@t6g_mb_lib.t6g(sch_1):page197_i262@pure_quanta.q_res(chips)';

PART_NAME
 R780 'Q_RES_0402LF-49.9     ,1%  ,1/16W,CHIP,CS04992FB31':;

SECTION_NUMBER 1
 '@T6G_MB_LIB.T6G(SCH_1):PAGE197_I204@PURE_QUANTA.Q_RES(CHIPS)':
 C_PATH='@t6g_mb_lib.t6g(sch_1):page197_i204@pure_quanta.q_res(chips)';

PART_NAME
 R778 'Q_RES_0402LF-1K,1%,1/16W,CHIP,TMP_QCS21002FB24':;

SECTION_NUMBER 1
 '@T6G_MB_LIB.T6G(SCH_1):PAGE197_I214@PURE_QUANTA.Q_RES(CHIPS)':
 C_PATH='@t6g_mb_lib.t6g(sch_1):page197_i214@pure_quanta.q_res(chips)';

PART_NAME
 R777 'Q_RES_0402LF-10,1%,1/16W,CHIP,TMP_QCS01002FB21':;

SECTION_NUMBER 1
 '@T6G_MB_LIB.T6G(SCH_1):PAGE197_I215@PURE_QUANTA.Q_RES(CHIPS)':
 C_PATH='@t6g_mb_lib.t6g(sch_1):page197_i215@pure_quanta.q_res(chips)';

PART_NAME
 R776 'Q_RES_0402LF-100,1%,1/16W,CHIP,TMP_QCS11002FB22':;

SECTION_NUMBER 1
 '@T6G_MB_LIB.T6G(SCH_1):PAGE197_I212@PURE_QUANTA.Q_RES(CHIPS)':
 C_PATH='@t6g_mb_lib.t6g(sch_1):page197_i212@pure_quanta.q_res(chips)';

PART_NAME
 R775 'Q_RES_0402LF-10,1%,1/16W,CHIP,TMP_QCS01002FB21':;

SECTION_NUMBER 1
 '@T6G_MB_LIB.T6G(SCH_1):PAGE197_I211@PURE_QUANTA.Q_RES(CHIPS)':
 C_PATH='@t6g_mb_lib.t6g(sch_1):page197_i211@pure_quanta.q_res(chips)';

PART_NAME
 R774 'Q_RES_0402LF-75,1%,1/16W,CHIP,CS07502FB17':;

SECTION_NUMBER 1
 '@T6G_MB_LIB.T6G(SCH_1):PAGE197_I236@PURE_QUANTA.Q_RES(CHIPS)':
 C_PATH='@t6g_mb_lib.t6g(sch_1):page197_i236@pure_quanta.q_res(chips)';

PART_NAME
 R773 'Q_RES_0402LF-1K,1%,1/16W,CHIP,TMP_QCS21002FB24':;

SECTION_NUMBER 1
 '@T6G_MB_LIB.T6G(SCH_1):PAGE197_I233@PURE_QUANTA.Q_RES(CHIPS)':
 C_PATH='@t6g_mb_lib.t6g(sch_1):page197_i233@pure_quanta.q_res(chips)';

PART_NAME
 R772 'Q_RES_0402LF-1K,1%,1/16W,CHIP,TMP_QCS21002FB24':;

SECTION_NUMBER 1
 '@T6G_MB_LIB.T6G(SCH_1):PAGE197_I226@PURE_QUANTA.Q_RES(CHIPS)':
 C_PATH='@t6g_mb_lib.t6g(sch_1):page197_i226@pure_quanta.q_res(chips)';

PART_NAME
 R771 'Q_RES_0402LF-1K,1%,1/16W,CHIP,TMP_QCS21002FB24':;

SECTION_NUMBER 1
 '@T6G_MB_LIB.T6G(SCH_1):PAGE197_I227@PURE_QUANTA.Q_RES(CHIPS)':
 C_PATH='@t6g_mb_lib.t6g(sch_1):page197_i227@pure_quanta.q_res(chips)';

PART_NAME
 J42 'SCONN60_QSH03001LDAKTR-SCONN60_QSH-030-01-L-D-A-K-TR,SMLF,IO,DFHS60FS001':;

SECTION_NUMBER 1
 '@T6G_MB_LIB.T6G(SCH_1):PAGE197_I191@PURE_QUANTA.SCONN60_QSH03001LDAKTR(CHIPS)':
 C_PATH='@t6g_mb_lib.t6g(sch_1):page197_i191@pure_quanta.sconn60_qsh03001ldaktr(~
chips)';

PART_NAME
 C1170 'Q_CAP_0402-0.1UF,25V,10%,X7R,CH4104K1B00':;

SECTION_NUMBER 1
 '@T6G_MB_LIB.T6G(SCH_1):PAGE197_I239@PURE_QUANTA.Q_CAP(CHIPS)':
 C_PATH='@t6g_mb_lib.t6g(sch_1):page197_i239@pure_quanta.q_cap(chips)';

PART_NAME
 C1105 'Q_CAP_C0402-1UF,25V,10%,X6S,CH5104KEB02':;

SECTION_NUMBER 1
 '@T6G_MB_LIB.T6G(SCH_1):PAGE197_I243@PURE_QUANTA.Q_CAP(CHIPS)':
 C_PATH='@t6g_mb_lib.t6g(sch_1):page197_i243@pure_quanta.q_cap(chips)';

PART_NAME
 C552 'Q_CAP_0402-0.1UF,25V,10%,X7R,CH4104K1B00':;

SECTION_NUMBER 1
 '@T6G_MB_LIB.T6G(SCH_1):PAGE197_I206@PURE_QUANTA.Q_CAP(CHIPS)':
 C_PATH='@t6g_mb_lib.t6g(sch_1):page197_i206@pure_quanta.q_cap(chips)';

PART_NAME
 C551 'Q_CAP_C0402-1UF,25V,10%,X6S,CH5104KEB02':;

SECTION_NUMBER 1
 '@T6G_MB_LIB.T6G(SCH_1):PAGE197_I222@PURE_QUANTA.Q_CAP(CHIPS)':
 C_PATH='@t6g_mb_lib.t6g(sch_1):page197_i222@pure_quanta.q_cap(chips)';

PART_NAME
 C550 'Q_CAP_C0402-1UF,25V,10%,X6S,CH5104KEB02':;

SECTION_NUMBER 1
 '@T6G_MB_LIB.T6G(SCH_1):PAGE197_I217@PURE_QUANTA.Q_CAP(CHIPS)':
 C_PATH='@t6g_mb_lib.t6g(sch_1):page197_i217@pure_quanta.q_cap(chips)';

PART_NAME
 C549 'Q_CAP_0402-0.1UF,25V,10%,X7R,CH4104K1B00':;

SECTION_NUMBER 1
 '@T6G_MB_LIB.T6G(SCH_1):PAGE197_I238@PURE_QUANTA.Q_CAP(CHIPS)':
 C_PATH='@t6g_mb_lib.t6g(sch_1):page197_i238@pure_quanta.q_cap(chips)';

PART_NAME
 U18 '74CBTLV3126PW-74CBTLV3126PW,SMLF,IC,AL003126K08':;

SECTION_NUMBER 1
 '@T6G_MB_LIB.T6G(SCH_1):PAGE198_I121@PURE_QUANTA.74CBTLV3126PW(CHIPS)':
 C_PATH='@t6g_mb_lib.t6g(sch_1):page198_i121@pure_quanta.\74cbtlv3126pw\(chips)';

PART_NAME
 U17 '74CBTLV3126PW-74CBTLV3126PW,SMLF,IC,AL003126K08':;

SECTION_NUMBER 1
 '@T6G_MB_LIB.T6G(SCH_1):PAGE198_I118@PURE_QUANTA.74CBTLV3126PW(CHIPS)':
 C_PATH='@t6g_mb_lib.t6g(sch_1):page198_i118@pure_quanta.\74cbtlv3126pw\(chips)';

PART_NAME
 R2311 'Q_RES_0402LF-499,1%,1/16W,CHIP,CS14992FB24':;

SECTION_NUMBER 1
 '@T6G_MB_LIB.T6G(SCH_1):PAGE198_I88@PURE_QUANTA.Q_RES(CHIPS)':
 C_PATH='@t6g_mb_lib.t6g(sch_1):page198_i88@pure_quanta.q_res(chips)';

PART_NAME
 R2310 'Q_RES_0402LF-150,1%,1/16W,CHIP,TMP_QCS11502FB21':;

SECTION_NUMBER 1
 '@T6G_MB_LIB.T6G(SCH_1):PAGE198_I93@PURE_QUANTA.Q_RES(CHIPS)':
 C_PATH='@t6g_mb_lib.t6g(sch_1):page198_i93@pure_quanta.q_res(chips)';

PART_NAME
 R2309 'Q_RES_0402LF-499,1%,1/16W,CHIP,CS14992FB24':;

SECTION_NUMBER 1
 '@T6G_MB_LIB.T6G(SCH_1):PAGE198_I98@PURE_QUANTA.Q_RES(CHIPS)':
 C_PATH='@t6g_mb_lib.t6g(sch_1):page198_i98@pure_quanta.q_res(chips)';

PART_NAME
 R2308 'Q_RES_0402LF-150,1%,1/16W,CHIP,TMP_QCS11502FB21':;

SECTION_NUMBER 1
 '@T6G_MB_LIB.T6G(SCH_1):PAGE198_I107@PURE_QUANTA.Q_RES(CHIPS)':
 C_PATH='@t6g_mb_lib.t6g(sch_1):page198_i107@pure_quanta.q_res(chips)';

PART_NAME
 R2294 'Q_RES_0402LF-150,1%,1/16W,CHIP,TMP_QCS11502FB21':;

SECTION_NUMBER 1
 '@T6G_MB_LIB.T6G(SCH_1):PAGE198_I99@PURE_QUANTA.Q_RES(CHIPS)':
 C_PATH='@t6g_mb_lib.t6g(sch_1):page198_i99@pure_quanta.q_res(chips)';

PART_NAME
 R2293 'Q_RES_0402LF-75,1%,1/16W,CHIP,CS07502FB17':;

SECTION_NUMBER 1
 '@T6G_MB_LIB.T6G(SCH_1):PAGE198_I108@PURE_QUANTA.Q_RES(CHIPS)':
 C_PATH='@t6g_mb_lib.t6g(sch_1):page198_i108@pure_quanta.q_res(chips)';

PART_NAME
 R2288 'Q_RES_0402LF-75,1%,1/16W,CHIP,CS07502FB17':;

SECTION_NUMBER 1
 '@T6G_MB_LIB.T6G(SCH_1):PAGE198_I109@PURE_QUANTA.Q_RES(CHIPS)':
 C_PATH='@t6g_mb_lib.t6g(sch_1):page198_i109@pure_quanta.q_res(chips)';

PART_NAME
 R2285 'Q_RES_0402LF-150,1%,1/16W,CHIP,TMP_QCS11502FB21':;

SECTION_NUMBER 1
 '@T6G_MB_LIB.T6G(SCH_1):PAGE198_I101@PURE_QUANTA.Q_RES(CHIPS)':
 C_PATH='@t6g_mb_lib.t6g(sch_1):page198_i101@pure_quanta.q_res(chips)';

PART_NAME
 R2281 'Q_RES_0402LF-120,1%,1/16W,CHIP,CS11202FB11':;

SECTION_NUMBER 1
 '@T6G_MB_LIB.T6G(SCH_1):PAGE198_I94@PURE_QUANTA.Q_RES(CHIPS)':
 C_PATH='@t6g_mb_lib.t6g(sch_1):page198_i94@pure_quanta.q_res(chips)';

PART_NAME
 R2280 'Q_RES_0402LF-150,1%,1/16W,CHIP,TMP_QCS11502FB21':;

SECTION_NUMBER 1
 '@T6G_MB_LIB.T6G(SCH_1):PAGE198_I113@PURE_QUANTA.Q_RES(CHIPS)':
 C_PATH='@t6g_mb_lib.t6g(sch_1):page198_i113@pure_quanta.q_res(chips)';

PART_NAME
 R2279 'Q_RES_0402LF-10,1%,1/16W,CHIP,TMP_QCS01002FB21':;

SECTION_NUMBER 1
 '@T6G_MB_LIB.T6G(SCH_1):PAGE198_I135@PURE_QUANTA.Q_RES(CHIPS)':
 C_PATH='@t6g_mb_lib.t6g(sch_1):page198_i135@pure_quanta.q_res(chips)';

PART_NAME
 R2278 'Q_RES_0402LF-10,1%,1/16W,CHIP,TMP_QCS01002FB21':;

SECTION_NUMBER 1
 '@T6G_MB_LIB.T6G(SCH_1):PAGE198_I134@PURE_QUANTA.Q_RES(CHIPS)':
 C_PATH='@t6g_mb_lib.t6g(sch_1):page198_i134@pure_quanta.q_res(chips)';

PART_NAME
 R2277 'Q_RES_0402LF-10,1%,1/16W,CHIP,TMP_QCS01002FB21':;

SECTION_NUMBER 1
 '@T6G_MB_LIB.T6G(SCH_1):PAGE198_I132@PURE_QUANTA.Q_RES(CHIPS)':
 C_PATH='@t6g_mb_lib.t6g(sch_1):page198_i132@pure_quanta.q_res(chips)';

PART_NAME
 R2276 'Q_RES_0402LF-10,1%,1/16W,CHIP,TMP_QCS01002FB21':;

SECTION_NUMBER 1
 '@T6G_MB_LIB.T6G(SCH_1):PAGE198_I133@PURE_QUANTA.Q_RES(CHIPS)':
 C_PATH='@t6g_mb_lib.t6g(sch_1):page198_i133@pure_quanta.q_res(chips)';

PART_NAME
 R2274 'Q_RES_0402LF-10,1%,1/16W,CHIP,TMP_QCS01002FB21':;

SECTION_NUMBER 1
 '@T6G_MB_LIB.T6G(SCH_1):PAGE198_I131@PURE_QUANTA.Q_RES(CHIPS)':
 C_PATH='@t6g_mb_lib.t6g(sch_1):page198_i131@pure_quanta.q_res(chips)';

PART_NAME
 R2267 'Q_RES_0402LF-0,5%,1/16W,CHIP,CS00002JB38':;

SECTION_NUMBER 1
 '@T6G_MB_LIB.T6G(SCH_1):PAGE198_I119@PURE_QUANTA.Q_RES(CHIPS)':
 C_PATH='@t6g_mb_lib.t6g(sch_1):page198_i119@pure_quanta.q_res(chips)';

PART_NAME
 C546 'Q_CAP_C0402-1UF,25V,10%,X6S,CH5104KEB02':;

SECTION_NUMBER 1
 '@T6G_MB_LIB.T6G(SCH_1):PAGE198_I105@PURE_QUANTA.Q_CAP(CHIPS)':
 C_PATH='@t6g_mb_lib.t6g(sch_1):page198_i105@pure_quanta.q_cap(chips)';

PART_NAME
 C545 'Q_CAP_C0402-1UF,25V,10%,X6S,CH5104KEB02':;

SECTION_NUMBER 1
 '@T6G_MB_LIB.T6G(SCH_1):PAGE198_I103@PURE_QUANTA.Q_CAP(CHIPS)':
 C_PATH='@t6g_mb_lib.t6g(sch_1):page198_i103@pure_quanta.q_cap(chips)';

PART_NAME
 U181 '74LVC1G02GW_SMLF-74LVC1G02GW,IC,ALVC1G02000':;

SECTION_NUMBER 1
 '@T6G_MB_LIB.T6G(SCH_1):PAGE199_I128@PURE_QUANTA.74LVC1G02GW(CHIPS)':
 C_PATH='@t6g_mb_lib.t6g(sch_1):page199_i128@pure_quanta.\74lvc1g02gw\(chips)';

PART_NAME
 U22 'NC7SB3157_SMLF-NC7SB3157P6X,NC7SB3157P6X,IC,ALSB3157000':;

SECTION_NUMBER 1
 '@T6G_MB_LIB.T6G(SCH_1):PAGE199_I144@PURE_QUANTA.NC7SB3157(CHIPS)':
 C_PATH='@t6g_mb_lib.t6g(sch_1):page199_i144@pure_quanta.nc7sb3157(chips)';

PART_NAME
 U21 'NC7SB3157_SMLF-NC7SB3157P6X,NC7SB3157P6X,IC,ALSB3157000':;

SECTION_NUMBER 1
 '@T6G_MB_LIB.T6G(SCH_1):PAGE199_I132@PURE_QUANTA.NC7SB3157(CHIPS)':
 C_PATH='@t6g_mb_lib.t6g(sch_1):page199_i132@pure_quanta.nc7sb3157(chips)';

PART_NAME
 U16 'NC7SZ66M5X_SMLF-NC7SZ66M5X,NC7SZ66M5X,IC,AL07SZ66004':;

SECTION_NUMBER 1
 '@T6G_MB_LIB.T6G(SCH_1):PAGE199_I106@PURE_QUANTA.NC7SZ66M5X(CHIPS)':
 C_PATH='@t6g_mb_lib.t6g(sch_1):page199_i106@pure_quanta.nc7sz66m5x(chips)';

PART_NAME
 R2313 'Q_RES_0402LF-10K,1%,1/16W,CHIP,TMP_QCS31002FB26':;

SECTION_NUMBER 1
 '@T6G_MB_LIB.T6G(SCH_1):PAGE199_I146@PURE_QUANTA.Q_RES(CHIPS)':
 C_PATH='@t6g_mb_lib.t6g(sch_1):page199_i146@pure_quanta.q_res(chips)';

PART_NAME
 R2312 'Q_RES_0402LF-0,5%,1/16W,CHIP,CS00002JB38':;

SECTION_NUMBER 1
 '@T6G_MB_LIB.T6G(SCH_1):PAGE199_I149@PURE_QUANTA.Q_RES(CHIPS)':
 C_PATH='@t6g_mb_lib.t6g(sch_1):page199_i149@pure_quanta.q_res(chips)';

PART_NAME
 R745 'Q_RES_0402LF-33,5%,1/16W,CHIP,CS03302JB29':;

SECTION_NUMBER 1
 '@T6G_MB_LIB.T6G(SCH_1):PAGE199_I124@PURE_QUANTA.Q_RES(CHIPS)':
 C_PATH='@t6g_mb_lib.t6g(sch_1):page199_i124@pure_quanta.q_res(chips)';

PART_NAME
 R744 'Q_RES_0402LF-75,1%,1/16W,CHIP,CS07502FB17':;

SECTION_NUMBER 1
 '@T6G_MB_LIB.T6G(SCH_1):PAGE199_I118@PURE_QUANTA.Q_RES(CHIPS)':
 C_PATH='@t6g_mb_lib.t6g(sch_1):page199_i118@pure_quanta.q_res(chips)';

PART_NAME
 R743 'Q_RES_0402LF-150,1%,1/16W,CHIP,TMP_QCS11502FB21':;

SECTION_NUMBER 1
 '@T6G_MB_LIB.T6G(SCH_1):PAGE199_I116@PURE_QUANTA.Q_RES(CHIPS)':
 C_PATH='@t6g_mb_lib.t6g(sch_1):page199_i116@pure_quanta.q_res(chips)';

PART_NAME
 R742 'Q_RES_0402LF-75,1%,1/16W,CHIP,CS07502FB17':;

SECTION_NUMBER 1
 '@T6G_MB_LIB.T6G(SCH_1):PAGE199_I121@PURE_QUANTA.Q_RES(CHIPS)':
 C_PATH='@t6g_mb_lib.t6g(sch_1):page199_i121@pure_quanta.q_res(chips)';

PART_NAME
 R741 'Q_RES_0402LF-150,1%,1/16W,CHIP,TMP_QCS11502FB21':;

SECTION_NUMBER 1
 '@T6G_MB_LIB.T6G(SCH_1):PAGE199_I119@PURE_QUANTA.Q_RES(CHIPS)':
 C_PATH='@t6g_mb_lib.t6g(sch_1):page199_i119@pure_quanta.q_res(chips)';

PART_NAME
 R739 'Q_RES_0402LF-10K,1%,1/16W,CHIP,TMP_QCS31002FB26':;

SECTION_NUMBER 1
 '@T6G_MB_LIB.T6G(SCH_1):PAGE199_I147@PURE_QUANTA.Q_RES(CHIPS)':
 C_PATH='@t6g_mb_lib.t6g(sch_1):page199_i147@pure_quanta.q_res(chips)';

PART_NAME
 R738 'Q_RES_0402LF-0,5%,1/16W,CHIP,CS00002JB38':;

SECTION_NUMBER 1
 '@T6G_MB_LIB.T6G(SCH_1):PAGE199_I148@PURE_QUANTA.Q_RES(CHIPS)':
 C_PATH='@t6g_mb_lib.t6g(sch_1):page199_i148@pure_quanta.q_res(chips)';

PART_NAME
 C544 'Q_CAP_0402-0.1UF,25V,10%,X7R,CH4104K1B00':;

SECTION_NUMBER 1
 '@T6G_MB_LIB.T6G(SCH_1):PAGE199_I112@PURE_QUANTA.Q_CAP(CHIPS)':
 C_PATH='@t6g_mb_lib.t6g(sch_1):page199_i112@pure_quanta.q_cap(chips)';

PART_NAME
 C543 'Q_CAP_0402-0.1UF,25V,10%,X7R,CH4104K1B00':;

SECTION_NUMBER 1
 '@T6G_MB_LIB.T6G(SCH_1):PAGE199_I126@PURE_QUANTA.Q_CAP(CHIPS)':
 C_PATH='@t6g_mb_lib.t6g(sch_1):page199_i126@pure_quanta.q_cap(chips)';

PART_NAME
 C542 'Q_CAP_C0402-1UF,25V,10%,X6S,CH5104KEB02':;

SECTION_NUMBER 1
 '@T6G_MB_LIB.T6G(SCH_1):PAGE199_I140@PURE_QUANTA.Q_CAP(CHIPS)':
 C_PATH='@t6g_mb_lib.t6g(sch_1):page199_i140@pure_quanta.q_cap(chips)';

PART_NAME
 C541 'Q_CAP_C0402-1UF,25V,10%,X6S,CH5104KEB02':;

SECTION_NUMBER 1
 '@T6G_MB_LIB.T6G(SCH_1):PAGE199_I135@PURE_QUANTA.Q_CAP(CHIPS)':
 C_PATH='@t6g_mb_lib.t6g(sch_1):page199_i135@pure_quanta.q_cap(chips)';

PART_NAME
 C540 'Q_CAP_0402-0.1UF,25V,10%,X7R,CH4104K1B00':;

SECTION_NUMBER 1
 '@T6G_MB_LIB.T6G(SCH_1):PAGE199_I141@PURE_QUANTA.Q_CAP(CHIPS)':
 C_PATH='@t6g_mb_lib.t6g(sch_1):page199_i141@pure_quanta.q_cap(chips)';

PART_NAME
 C539 'Q_CAP_0402-0.1UF,25V,10%,X7R,CH4104K1B00':;

SECTION_NUMBER 1
 '@T6G_MB_LIB.T6G(SCH_1):PAGE199_I136@PURE_QUANTA.Q_CAP(CHIPS)':
 C_PATH='@t6g_mb_lib.t6g(sch_1):page199_i136@pure_quanta.q_cap(chips)';

PART_NAME
 R3589 'Q_RES_0402LF-10K,1%,1/16W,CHIP,TMP_QCS31002FB26':;

SECTION_NUMBER 1
 '@T6G_MB_LIB.T6G(SCH_1):PAGE281_I307@PURE_QUANTA.Q_RES(CHIPS)':
 C_PATH='@t6g_mb_lib.t6g(sch_1):page281_i307@pure_quanta.q_res(chips)';

PART_NAME
 R3588 'Q_RES_0402LF-10K,1%,1/16W,CHIP,TMP_QCS31002FB26':;

SECTION_NUMBER 1
 '@T6G_MB_LIB.T6G(SCH_1):PAGE281_I304@PURE_QUANTA.Q_RES(CHIPS)':
 C_PATH='@t6g_mb_lib.t6g(sch_1):page281_i304@pure_quanta.q_res(chips)';

PART_NAME
 R3587 'Q_RES_0402LF-10K,1%,1/16W,CHIP,TMP_QCS31002FB26':;

SECTION_NUMBER 1
 '@T6G_MB_LIB.T6G(SCH_1):PAGE281_I309@PURE_QUANTA.Q_RES(CHIPS)':
 C_PATH='@t6g_mb_lib.t6g(sch_1):page281_i309@pure_quanta.q_res(chips)';

PART_NAME
 R3586 'Q_RES_0402LF-10K,1%,1/16W,CHIP,TMP_QCS31002FB26':;

SECTION_NUMBER 1
 '@T6G_MB_LIB.T6G(SCH_1):PAGE281_I311@PURE_QUANTA.Q_RES(CHIPS)':
 C_PATH='@t6g_mb_lib.t6g(sch_1):page281_i311@pure_quanta.q_res(chips)';

PART_NAME
 R1281 'Q_RES_0402LF-0,5%,1/16W,CHIP,CS00002JB38':;

SECTION_NUMBER 1
 '@T6G_MB_LIB.T6G(SCH_1):PAGE281_I350@PURE_QUANTA.Q_RES(CHIPS)':
 C_PATH='@t6g_mb_lib.t6g(sch_1):page281_i350@pure_quanta.q_res(chips)';

PART_NAME
 R1280 'Q_RES_0402LF-0,5%,1/16W,CHIP,CS00002JB38':;

SECTION_NUMBER 1
 '@T6G_MB_LIB.T6G(SCH_1):PAGE281_I320@PURE_QUANTA.Q_RES(CHIPS)':
 C_PATH='@t6g_mb_lib.t6g(sch_1):page281_i320@pure_quanta.q_res(chips)';

PART_NAME
 R1279 'Q_RES_0402LF-0,5%,1/16W,CHIP,CS00002JB38':;

SECTION_NUMBER 1
 '@T6G_MB_LIB.T6G(SCH_1):PAGE281_I344@PURE_QUANTA.Q_RES(CHIPS)':
 C_PATH='@t6g_mb_lib.t6g(sch_1):page281_i344@pure_quanta.q_res(chips)';

PART_NAME
 R1278 'Q_RES_0402LF-0,5%,1/16W,CHIP,CS00002JB38':;

SECTION_NUMBER 1
 '@T6G_MB_LIB.T6G(SCH_1):PAGE281_I348@PURE_QUANTA.Q_RES(CHIPS)':
 C_PATH='@t6g_mb_lib.t6g(sch_1):page281_i348@pure_quanta.q_res(chips)';

PART_NAME
 R1277 'Q_RES_0402LF-0,5%,1/16W,CHIP,CS00002JB38':;

SECTION_NUMBER 1
 '@T6G_MB_LIB.T6G(SCH_1):PAGE281_I332@PURE_QUANTA.Q_RES(CHIPS)':
 C_PATH='@t6g_mb_lib.t6g(sch_1):page281_i332@pure_quanta.q_res(chips)';

PART_NAME
 R1276 'Q_RES_0402LF-0,5%,1/16W,CHIP,CS00002JB38':;

SECTION_NUMBER 1
 '@T6G_MB_LIB.T6G(SCH_1):PAGE281_I335@PURE_QUANTA.Q_RES(CHIPS)':
 C_PATH='@t6g_mb_lib.t6g(sch_1):page281_i335@pure_quanta.q_res(chips)';

PART_NAME
 J101 'CONN50_10147875001LF-CONN50_10147875-001LF,THLF,IO,DFHS50FR096':;

SECTION_NUMBER 1
 '@T6G_MB_LIB.T6G(SCH_1):PAGE281_I357@PURE_QUANTA.CONN50_10147875001LF(CHIPS)':
 C_PATH='@t6g_mb_lib.t6g(sch_1):page281_i357@pure_quanta.conn50_10147875001lf(ch~
ips)';

PART_NAME
 J100 'CONN50_10147875001LF-CONN50_10147875-001LF,THLF,IO,DFHS50FR096':;

SECTION_NUMBER 1
 '@T6G_MB_LIB.T6G(SCH_1):PAGE281_I358@PURE_QUANTA.CONN50_10147875001LF(CHIPS)':
 C_PATH='@t6g_mb_lib.t6g(sch_1):page281_i358@pure_quanta.conn50_10147875001lf(ch~
ips)';

PART_NAME
 D46 'Q_DIODE_SMLF-SDMK0340L-7-F,IC,BC000340033':;

SECTION_NUMBER 1
 '@T6G_MB_LIB.T6G(SCH_1):PAGE281_I343@PURE_QUANTA.Q_DIODE(CHIPS)':
 C_PATH='@t6g_mb_lib.t6g(sch_1):page281_i343@pure_quanta.q_diode(chips)';

PART_NAME
 D45 'Q_DIODE_SMLF-SDMK0340L-7-F,IC,BC000340033':;

SECTION_NUMBER 1
 '@T6G_MB_LIB.T6G(SCH_1):PAGE281_I331@PURE_QUANTA.Q_DIODE(CHIPS)':
 C_PATH='@t6g_mb_lib.t6g(sch_1):page281_i331@pure_quanta.q_diode(chips)';

PART_NAME
 C565 'Q_CAP_0402-0.1UF,25V,10%,X7R,CH4104K1B00':;

SECTION_NUMBER 1
 '@T6G_MB_LIB.T6G(SCH_1):PAGE281_I281@PURE_QUANTA.Q_CAP(CHIPS)':
 C_PATH='@t6g_mb_lib.t6g(sch_1):page281_i281@pure_quanta.q_cap(chips)';

PART_NAME
 C564 'Q_CAP_0402-0.1UF,25V,10%,X7R,CH4104K1B00':;

SECTION_NUMBER 1
 '@T6G_MB_LIB.T6G(SCH_1):PAGE281_I214@PURE_QUANTA.Q_CAP(CHIPS)':
 C_PATH='@t6g_mb_lib.t6g(sch_1):page281_i214@pure_quanta.q_cap(chips)';

PART_NAME
 C553 'Q_CAP_C0805-10UF,25V,10%,X6S,CH6104KEA00':;

SECTION_NUMBER 1
 '@T6G_MB_LIB.T6G(SCH_1):PAGE281_I282@PURE_QUANTA.Q_CAP(CHIPS)':
 C_PATH='@t6g_mb_lib.t6g(sch_1):page281_i282@pure_quanta.q_cap(chips)';

PART_NAME
 C548 'Q_CAP_C0805-10UF,25V,10%,X6S,CH6104KEA00':;

SECTION_NUMBER 1
 '@T6G_MB_LIB.T6G(SCH_1):PAGE281_I216@PURE_QUANTA.Q_CAP(CHIPS)':
 C_PATH='@t6g_mb_lib.t6g(sch_1):page281_i216@pure_quanta.q_cap(chips)';

PART_NAME
 C547 'Q_CAPP_RDLF-270UF,16V,20%,ALUM,CC72703MD23':;

SECTION_NUMBER 1
 '@T6G_MB_LIB.T6G(SCH_1):PAGE281_I284@PURE_QUANTA.Q_CAPP(CHIPS)':
 C_PATH='@t6g_mb_lib.t6g(sch_1):page281_i284@pure_quanta.q_capp(chips)';

PART_NAME
 C538 'Q_CAPP_RDLF-270UF,16V,20%,ALUM,CC72703MD23':;

SECTION_NUMBER 1
 '@T6G_MB_LIB.T6G(SCH_1):PAGE281_I217@PURE_QUANTA.Q_CAPP(CHIPS)':
 C_PATH='@t6g_mb_lib.t6g(sch_1):page281_i217@pure_quanta.q_capp(chips)';

PART_NAME
 U35 'ADS7830IPWR_SMLF-ADS7830IPWR,IC,AL007830K00':;

SECTION_NUMBER 1
 '@T6G_MB_LIB.T6G(SCH_1):PAGE250_I21@PURE_QUANTA.ADS7830IPWR(CHIPS)':
 C_PATH='@t6g_mb_lib.t6g(sch_1):page250_i21@pure_quanta.ads7830ipwr(chips)';

PART_NAME
 U34 'ADS7830IPWR_SMLF-ADS7830IPWR,IC,AL007830K00':;

SECTION_NUMBER 1
 '@T6G_MB_LIB.T6G(SCH_1):PAGE250_I1@PURE_QUANTA.ADS7830IPWR(CHIPS)':
 C_PATH='@t6g_mb_lib.t6g(sch_1):page250_i1@pure_quanta.ads7830ipwr(chips)';

PART_NAME
 R3858 'Q_RES_0402LF-33,5%,1/16W,CHIP,CS03302JB29':;

SECTION_NUMBER 1
 '@T6G_MB_LIB.T6G(SCH_1):PAGE250_I207@PURE_QUANTA.Q_RES(CHIPS)':
 C_PATH='@t6g_mb_lib.t6g(sch_1):page250_i207@pure_quanta.q_res(chips)';

PART_NAME
 R3857 'Q_RES_0402LF-33,5%,1/16W,CHIP,CS03302JB29':;

SECTION_NUMBER 1
 '@T6G_MB_LIB.T6G(SCH_1):PAGE250_I206@PURE_QUANTA.Q_RES(CHIPS)':
 C_PATH='@t6g_mb_lib.t6g(sch_1):page250_i206@pure_quanta.q_res(chips)';

PART_NAME
 R3765 'Q_RES_0402LF-33,5%,1/16W,CHIP,CS03302JB29':;

SECTION_NUMBER 1
 '@T6G_MB_LIB.T6G(SCH_1):PAGE250_I185@PURE_QUANTA.Q_RES(CHIPS)':
 C_PATH='@t6g_mb_lib.t6g(sch_1):page250_i185@pure_quanta.q_res(chips)';

PART_NAME
 R3764 'Q_RES_0402LF-33,5%,1/16W,CHIP,CS03302JB29':;

SECTION_NUMBER 1
 '@T6G_MB_LIB.T6G(SCH_1):PAGE250_I179@PURE_QUANTA.Q_RES(CHIPS)':
 C_PATH='@t6g_mb_lib.t6g(sch_1):page250_i179@pure_quanta.q_res(chips)';

PART_NAME
 R1031 'Q_RES_0402LF-1K,1%,1/16W,CHIP,TMP_QCS21002FB24':;

SECTION_NUMBER 1
 '@T6G_MB_LIB.T6G(SCH_1):PAGE250_I162@PURE_QUANTA.Q_RES(CHIPS)':
 C_PATH='@t6g_mb_lib.t6g(sch_1):page250_i162@pure_quanta.q_res(chips)';

PART_NAME
 R1019 'Q_RES_0402LF-1K,1%,1/16W,CHIP,TMP_QCS21002FB24':;

SECTION_NUMBER 1
 '@T6G_MB_LIB.T6G(SCH_1):PAGE250_I156@PURE_QUANTA.Q_RES(CHIPS)':
 C_PATH='@t6g_mb_lib.t6g(sch_1):page250_i156@pure_quanta.q_res(chips)';

PART_NAME
 R1018 'Q_RES_0402LF-2K,1%,1/16W,CHIP,TMP_QCS22002FB19':;

SECTION_NUMBER 1
 '@T6G_MB_LIB.T6G(SCH_1):PAGE250_I153@PURE_QUANTA.Q_RES(CHIPS)':
 C_PATH='@t6g_mb_lib.t6g(sch_1):page250_i153@pure_quanta.q_res(chips)';

PART_NAME
 R1017 'Q_RES_0402LF-665,1%,1/16W,CHIP,CS16652FB04':;

SECTION_NUMBER 1
 '@T6G_MB_LIB.T6G(SCH_1):PAGE250_I152@PURE_QUANTA.Q_RES(CHIPS)':
 C_PATH='@t6g_mb_lib.t6g(sch_1):page250_i152@pure_quanta.q_res(chips)';

PART_NAME
 R1016 'Q_RES_0402LF-2K,1%,1/16W,CHIP,TMP_QCS22002FB19':;

SECTION_NUMBER 1
 '@T6G_MB_LIB.T6G(SCH_1):PAGE250_I146@PURE_QUANTA.Q_RES(CHIPS)':
 C_PATH='@t6g_mb_lib.t6g(sch_1):page250_i146@pure_quanta.q_res(chips)';

PART_NAME
 R1015 'Q_RES_0402LF-665,1%,1/16W,CHIP,CS16652FB04':;

SECTION_NUMBER 1
 '@T6G_MB_LIB.T6G(SCH_1):PAGE250_I141@PURE_QUANTA.Q_RES(CHIPS)':
 C_PATH='@t6g_mb_lib.t6g(sch_1):page250_i141@pure_quanta.q_res(chips)';

PART_NAME
 R1014 'Q_RES_0402LF-2K,1%,1/16W,CHIP,TMP_QCS22002FB19':;

SECTION_NUMBER 1
 '@T6G_MB_LIB.T6G(SCH_1):PAGE250_I136@PURE_QUANTA.Q_RES(CHIPS)':
 C_PATH='@t6g_mb_lib.t6g(sch_1):page250_i136@pure_quanta.q_res(chips)';

PART_NAME
 R1013 'Q_RES_0402LF-665,1%,1/16W,CHIP,CS16652FB04':;

SECTION_NUMBER 1
 '@T6G_MB_LIB.T6G(SCH_1):PAGE250_I132@PURE_QUANTA.Q_RES(CHIPS)':
 C_PATH='@t6g_mb_lib.t6g(sch_1):page250_i132@pure_quanta.q_res(chips)';

PART_NAME
 R1012 'Q_RES_0402LF-2K,1%,1/16W,CHIP,TMP_QCS22002FB19':;

SECTION_NUMBER 1
 '@T6G_MB_LIB.T6G(SCH_1):PAGE250_I129@PURE_QUANTA.Q_RES(CHIPS)':
 C_PATH='@t6g_mb_lib.t6g(sch_1):page250_i129@pure_quanta.q_res(chips)';

PART_NAME
 R1011 'Q_RES_0402LF-665,1%,1/16W,CHIP,CS16652FB04':;

SECTION_NUMBER 1
 '@T6G_MB_LIB.T6G(SCH_1):PAGE250_I128@PURE_QUANTA.Q_RES(CHIPS)':
 C_PATH='@t6g_mb_lib.t6g(sch_1):page250_i128@pure_quanta.q_res(chips)';

PART_NAME
 R1010 'Q_RES_0402LF-2K,1%,1/16W,CHIP,TMP_QCS22002FB19':;

SECTION_NUMBER 1
 '@T6G_MB_LIB.T6G(SCH_1):PAGE250_I93@PURE_QUANTA.Q_RES(CHIPS)':
 C_PATH='@t6g_mb_lib.t6g(sch_1):page250_i93@pure_quanta.q_res(chips)';

PART_NAME
 R996 'Q_RES_0402LF-665,1%,1/16W,CHIP,CS16652FB04':;

SECTION_NUMBER 1
 '@T6G_MB_LIB.T6G(SCH_1):PAGE250_I95@PURE_QUANTA.Q_RES(CHIPS)':
 C_PATH='@t6g_mb_lib.t6g(sch_1):page250_i95@pure_quanta.q_res(chips)';

PART_NAME
 R995 'Q_RES_0402LF-1K,1%,1/16W,CHIP,TMP_QCS21002FB24':;

SECTION_NUMBER 1
 '@T6G_MB_LIB.T6G(SCH_1):PAGE250_I86@PURE_QUANTA.Q_RES(CHIPS)':
 C_PATH='@t6g_mb_lib.t6g(sch_1):page250_i86@pure_quanta.q_res(chips)';

PART_NAME
 R994 'Q_RES_0402LF-100K,1%,1/16W,CHIP,TMP_QCS41002FB28':;

SECTION_NUMBER 1
 '@T6G_MB_LIB.T6G(SCH_1):PAGE250_I77@PURE_QUANTA.Q_RES(CHIPS)':
 C_PATH='@t6g_mb_lib.t6g(sch_1):page250_i77@pure_quanta.q_res(chips)';

PART_NAME
 R993 'Q_RES_0402LF-100K,1%,1/16W,CHIP,TMP_QCS41002FB28':;

SECTION_NUMBER 1
 '@T6G_MB_LIB.T6G(SCH_1):PAGE250_I76@PURE_QUANTA.Q_RES(CHIPS)':
 C_PATH='@t6g_mb_lib.t6g(sch_1):page250_i76@pure_quanta.q_res(chips)';

PART_NAME
 R992 'Q_RES_0402LF-2K,1%,1/16W,CHIP,TMP_QCS22002FB19':;

SECTION_NUMBER 1
 '@T6G_MB_LIB.T6G(SCH_1):PAGE250_I115@PURE_QUANTA.Q_RES(CHIPS)':
 C_PATH='@t6g_mb_lib.t6g(sch_1):page250_i115@pure_quanta.q_res(chips)';

PART_NAME
 R991 'Q_RES_0402LF-2.87K,1%,1/16W,CHIP,CS22872FB10':;

SECTION_NUMBER 1
 '@T6G_MB_LIB.T6G(SCH_1):PAGE250_I114@PURE_QUANTA.Q_RES(CHIPS)':
 C_PATH='@t6g_mb_lib.t6g(sch_1):page250_i114@pure_quanta.q_res(chips)';

PART_NAME
 R990 'Q_RES_0402LF-2K,1%,1/16W,CHIP,TMP_QCS22002FB19':;

SECTION_NUMBER 1
 '@T6G_MB_LIB.T6G(SCH_1):PAGE250_I111@PURE_QUANTA.Q_RES(CHIPS)':
 C_PATH='@t6g_mb_lib.t6g(sch_1):page250_i111@pure_quanta.q_res(chips)';

PART_NAME
 R989 'Q_RES_0402LF-5.36K,1%,1/16W,CHIP,TMP_QCS25362FB15':;

SECTION_NUMBER 1
 '@T6G_MB_LIB.T6G(SCH_1):PAGE250_I110@PURE_QUANTA.Q_RES(CHIPS)':
 C_PATH='@t6g_mb_lib.t6g(sch_1):page250_i110@pure_quanta.q_res(chips)';

PART_NAME
 R985 'Q_RES_0402LF-2K,1%,1/16W,CHIP,TMP_QCS22002FB19':;

SECTION_NUMBER 1
 '@T6G_MB_LIB.T6G(SCH_1):PAGE250_I107@PURE_QUANTA.Q_RES(CHIPS)':
 C_PATH='@t6g_mb_lib.t6g(sch_1):page250_i107@pure_quanta.q_res(chips)';

PART_NAME
 R984 'Q_RES_0402LF-15.8K,1%,1/16W,CHIP,CS31582FB12':;

SECTION_NUMBER 1
 '@T6G_MB_LIB.T6G(SCH_1):PAGE250_I106@PURE_QUANTA.Q_RES(CHIPS)':
 C_PATH='@t6g_mb_lib.t6g(sch_1):page250_i106@pure_quanta.q_res(chips)';

PART_NAME
 R983 'Q_RES_0402LF-2K,1%,1/16W,CHIP,TMP_QCS22002FB19':;

SECTION_NUMBER 1
 '@T6G_MB_LIB.T6G(SCH_1):PAGE250_I57@PURE_QUANTA.Q_RES(CHIPS)':
 C_PATH='@t6g_mb_lib.t6g(sch_1):page250_i57@pure_quanta.q_res(chips)';

PART_NAME
 R982 'Q_RES_0402LF-2.87K,1%,1/16W,CHIP,CS22872FB10':;

SECTION_NUMBER 1
 '@T6G_MB_LIB.T6G(SCH_1):PAGE250_I59@PURE_QUANTA.Q_RES(CHIPS)':
 C_PATH='@t6g_mb_lib.t6g(sch_1):page250_i59@pure_quanta.q_res(chips)';

PART_NAME
 R981 'Q_RES_0402LF-2K,1%,1/16W,CHIP,TMP_QCS22002FB19':;

SECTION_NUMBER 1
 '@T6G_MB_LIB.T6G(SCH_1):PAGE250_I65@PURE_QUANTA.Q_RES(CHIPS)':
 C_PATH='@t6g_mb_lib.t6g(sch_1):page250_i65@pure_quanta.q_res(chips)';

PART_NAME
 R980 'Q_RES_0402LF-5.36K,1%,1/16W,CHIP,TMP_QCS25362FB15':;

SECTION_NUMBER 1
 '@T6G_MB_LIB.T6G(SCH_1):PAGE250_I67@PURE_QUANTA.Q_RES(CHIPS)':
 C_PATH='@t6g_mb_lib.t6g(sch_1):page250_i67@pure_quanta.q_res(chips)';

PART_NAME
 R978 'Q_RES_0402LF-2K,1%,1/16W,CHIP,TMP_QCS22002FB19':;

SECTION_NUMBER 1
 '@T6G_MB_LIB.T6G(SCH_1):PAGE250_I46@PURE_QUANTA.Q_RES(CHIPS)':
 C_PATH='@t6g_mb_lib.t6g(sch_1):page250_i46@pure_quanta.q_res(chips)';

PART_NAME
 R977 'Q_RES_0402LF-15.8K,1%,1/16W,CHIP,CS31582FB12':;

SECTION_NUMBER 1
 '@T6G_MB_LIB.T6G(SCH_1):PAGE250_I45@PURE_QUANTA.Q_RES(CHIPS)':
 C_PATH='@t6g_mb_lib.t6g(sch_1):page250_i45@pure_quanta.q_res(chips)';

PART_NAME
 R889 'Q_RES_0402LF-100K,1%,1/16W,CHIP,TMP_QCS41002FB28':;

SECTION_NUMBER 1
 '@T6G_MB_LIB.T6G(SCH_1):PAGE250_I37@PURE_QUANTA.Q_RES(CHIPS)':
 C_PATH='@t6g_mb_lib.t6g(sch_1):page250_i37@pure_quanta.q_res(chips)';

PART_NAME
 R886 'Q_RES_0402LF-100K,1%,1/16W,CHIP,TMP_QCS41002FB28':;

SECTION_NUMBER 1
 '@T6G_MB_LIB.T6G(SCH_1):PAGE250_I29@PURE_QUANTA.Q_RES(CHIPS)':
 C_PATH='@t6g_mb_lib.t6g(sch_1):page250_i29@pure_quanta.q_res(chips)';

PART_NAME
 R885 'Q_RES_0402LF-10K,1%,1/16W,CHIP,TMP_QCS31002FB26':;

SECTION_NUMBER 1
 '@T6G_MB_LIB.T6G(SCH_1):PAGE250_I17@PURE_QUANTA.Q_RES(CHIPS)':
 C_PATH='@t6g_mb_lib.t6g(sch_1):page250_i17@pure_quanta.q_res(chips)';

PART_NAME
 R883 'Q_RES_0402LF-10K,1%,1/16W,CHIP,TMP_QCS31002FB26':;

SECTION_NUMBER 1
 '@T6G_MB_LIB.T6G(SCH_1):PAGE250_I11@PURE_QUANTA.Q_RES(CHIPS)':
 C_PATH='@t6g_mb_lib.t6g(sch_1):page250_i11@pure_quanta.q_res(chips)';

PART_NAME
 C686 'Q_CAP_0402-0.1UF,25V,10%,X7R,CH4104K1B00':;

SECTION_NUMBER 1
 '@T6G_MB_LIB.T6G(SCH_1):PAGE250_I149@PURE_QUANTA.Q_CAP(CHIPS)':
 C_PATH='@t6g_mb_lib.t6g(sch_1):page250_i149@pure_quanta.q_cap(chips)';

PART_NAME
 C685 'Q_CAP_0402-0.1UF,25V,10%,X7R,CH4104K1B00':;

SECTION_NUMBER 1
 '@T6G_MB_LIB.T6G(SCH_1):PAGE250_I165@PURE_QUANTA.Q_CAP(CHIPS)':
 C_PATH='@t6g_mb_lib.t6g(sch_1):page250_i165@pure_quanta.q_cap(chips)';

PART_NAME
 C684 'Q_CAP_0402-0.1UF,25V,10%,X7R,CH4104K1B00':;

SECTION_NUMBER 1
 '@T6G_MB_LIB.T6G(SCH_1):PAGE250_I159@PURE_QUANTA.Q_CAP(CHIPS)':
 C_PATH='@t6g_mb_lib.t6g(sch_1):page250_i159@pure_quanta.q_cap(chips)';

PART_NAME
 C683 'Q_CAP_0402-0.1UF,25V,10%,X7R,CH4104K1B00':;

SECTION_NUMBER 1
 '@T6G_MB_LIB.T6G(SCH_1):PAGE250_I143@PURE_QUANTA.Q_CAP(CHIPS)':
 C_PATH='@t6g_mb_lib.t6g(sch_1):page250_i143@pure_quanta.q_cap(chips)';

PART_NAME
 C682 'Q_CAP_0402-0.1UF,25V,10%,X7R,CH4104K1B00':;

SECTION_NUMBER 1
 '@T6G_MB_LIB.T6G(SCH_1):PAGE250_I134@PURE_QUANTA.Q_CAP(CHIPS)':
 C_PATH='@t6g_mb_lib.t6g(sch_1):page250_i134@pure_quanta.q_cap(chips)';

PART_NAME
 C681 'Q_CAP_0402-0.1UF,25V,10%,X7R,CH4104K1B00':;

SECTION_NUMBER 1
 '@T6G_MB_LIB.T6G(SCH_1):PAGE250_I127@PURE_QUANTA.Q_CAP(CHIPS)':
 C_PATH='@t6g_mb_lib.t6g(sch_1):page250_i127@pure_quanta.q_cap(chips)';

PART_NAME
 C680 'Q_CAP_0402-0.1UF,25V,10%,X7R,CH4104K1B00':;

SECTION_NUMBER 1
 '@T6G_MB_LIB.T6G(SCH_1):PAGE250_I89@PURE_QUANTA.Q_CAP(CHIPS)':
 C_PATH='@t6g_mb_lib.t6g(sch_1):page250_i89@pure_quanta.q_cap(chips)';

PART_NAME
 C584 'Q_CAP_0402-0.1UF,25V,10%,X7R,CH4104K1B00':;

SECTION_NUMBER 1
 '@T6G_MB_LIB.T6G(SCH_1):PAGE250_I70@PURE_QUANTA.Q_CAP(CHIPS)':
 C_PATH='@t6g_mb_lib.t6g(sch_1):page250_i70@pure_quanta.q_cap(chips)';

PART_NAME
 C583 'Q_CAP_0402-0.1UF,25V,10%,X7R,CH4104K1B00':;

SECTION_NUMBER 1
 '@T6G_MB_LIB.T6G(SCH_1):PAGE250_I79@PURE_QUANTA.Q_CAP(CHIPS)':
 C_PATH='@t6g_mb_lib.t6g(sch_1):page250_i79@pure_quanta.q_cap(chips)';

PART_NAME
 C582 'Q_CAP_0402-0.1UF,25V,10%,X7R,CH4104K1B00':;

SECTION_NUMBER 1
 '@T6G_MB_LIB.T6G(SCH_1):PAGE250_I103@PURE_QUANTA.Q_CAP(CHIPS)':
 C_PATH='@t6g_mb_lib.t6g(sch_1):page250_i103@pure_quanta.q_cap(chips)';

PART_NAME
 C581 'Q_CAP_0402-0.1UF,25V,10%,X7R,CH4104K1B00':;

SECTION_NUMBER 1
 '@T6G_MB_LIB.T6G(SCH_1):PAGE250_I100@PURE_QUANTA.Q_CAP(CHIPS)':
 C_PATH='@t6g_mb_lib.t6g(sch_1):page250_i100@pure_quanta.q_cap(chips)';

PART_NAME
 C580 'Q_CAP_0402-0.1UF,25V,10%,X7R,CH4104K1B00':;

SECTION_NUMBER 1
 '@T6G_MB_LIB.T6G(SCH_1):PAGE250_I98@PURE_QUANTA.Q_CAP(CHIPS)':
 C_PATH='@t6g_mb_lib.t6g(sch_1):page250_i98@pure_quanta.q_cap(chips)';

PART_NAME
 C577 'Q_CAP_0402-0.1UF,25V,10%,X7R,CH4104K1B00':;

SECTION_NUMBER 1
 '@T6G_MB_LIB.T6G(SCH_1):PAGE250_I53@PURE_QUANTA.Q_CAP(CHIPS)':
 C_PATH='@t6g_mb_lib.t6g(sch_1):page250_i53@pure_quanta.q_cap(chips)';

PART_NAME
 C576 'Q_CAP_0402-0.1UF,25V,10%,X7R,CH4104K1B00':;

SECTION_NUMBER 1
 '@T6G_MB_LIB.T6G(SCH_1):PAGE250_I61@PURE_QUANTA.Q_CAP(CHIPS)':
 C_PATH='@t6g_mb_lib.t6g(sch_1):page250_i61@pure_quanta.q_cap(chips)';

PART_NAME
 C571 'Q_CAP_C0402-0.1UF,16V,10%,X7R,CH4103K1B08':;

SECTION_NUMBER 1
 '@T6G_MB_LIB.T6G(SCH_1):PAGE250_I25@PURE_QUANTA.Q_CAP(CHIPS)':
 C_PATH='@t6g_mb_lib.t6g(sch_1):page250_i25@pure_quanta.q_cap(chips)';

PART_NAME
 C570 'Q_CAP_C0402-0.1UF,16V,10%,X7R,CH4103K1B08':;

SECTION_NUMBER 1
 '@T6G_MB_LIB.T6G(SCH_1):PAGE250_I35@PURE_QUANTA.Q_CAP(CHIPS)':
 C_PATH='@t6g_mb_lib.t6g(sch_1):page250_i35@pure_quanta.q_cap(chips)';

PART_NAME
 C569 'Q_CAP_C0402-0.1UF,16V,10%,X7R,CH4103K1B08':;

SECTION_NUMBER 1
 '@T6G_MB_LIB.T6G(SCH_1):PAGE250_I10@PURE_QUANTA.Q_CAP(CHIPS)':
 C_PATH='@t6g_mb_lib.t6g(sch_1):page250_i10@pure_quanta.q_cap(chips)';

PART_NAME
 C568 'Q_CAP_C0402-0.1UF,16V,10%,X7R,CH4103K1B08':;

SECTION_NUMBER 1
 '@T6G_MB_LIB.T6G(SCH_1):PAGE250_I9@PURE_QUANTA.Q_CAP(CHIPS)':
 C_PATH='@t6g_mb_lib.t6g(sch_1):page250_i9@pure_quanta.q_cap(chips)';

PART_NAME
 C469 'Q_CAP_0402-0.1UF,25V,10%,X7R,CH4104K1B00':;

SECTION_NUMBER 1
 '@T6G_MB_LIB.T6G(SCH_1):PAGE250_I48@PURE_QUANTA.Q_CAP(CHIPS)':
 C_PATH='@t6g_mb_lib.t6g(sch_1):page250_i48@pure_quanta.q_cap(chips)';

PART_NAME
 C1400 'Q_CAP_0805-47UF,4V,20%,X6S,CH647KMEA00':;

SECTION_NUMBER 1
 '@T6G_MB_LIB.T6G(SCH_1):PAGE79_I161@PURE_QUANTA.Q_CAP(CHIPS)':
 C_PATH='@t6g_mb_lib.t6g(sch_1):page79_i161@pure_quanta.q_cap(chips)';

PART_NAME
 C1399 'Q_CAP_0805-47UF,4V,20%,X6S,CH647KMEA00':;

SECTION_NUMBER 1
 '@T6G_MB_LIB.T6G(SCH_1):PAGE79_I162@PURE_QUANTA.Q_CAP(CHIPS)':
 C_PATH='@t6g_mb_lib.t6g(sch_1):page79_i162@pure_quanta.q_cap(chips)';

PART_NAME
 C1362 'Q_CAP_C0402-10UF,4V,20%,X6S,CH610KMEB09':;

SECTION_NUMBER 1
 '@T6G_MB_LIB.T6G(SCH_1):PAGE79_I159@PURE_QUANTA.Q_CAP(CHIPS)':
 C_PATH='@t6g_mb_lib.t6g(sch_1):page79_i159@pure_quanta.q_cap(chips)';

PART_NAME
 C531 'Q_CAP_0805-47UF,4V,20%,X6S,CH647KMEA00':;

SECTION_NUMBER 1
 '@T6G_MB_LIB.T6G(SCH_1):PAGE79_I144@PURE_QUANTA.Q_CAP(CHIPS)':
 C_PATH='@t6g_mb_lib.t6g(sch_1):page79_i144@pure_quanta.q_cap(chips)';

PART_NAME
 C530 'Q_CAP_0805-47UF,4V,20%,X6S,CH647KMEA00':;

SECTION_NUMBER 1
 '@T6G_MB_LIB.T6G(SCH_1):PAGE79_I168@PURE_QUANTA.Q_CAP(CHIPS)':
 C_PATH='@t6g_mb_lib.t6g(sch_1):page79_i168@pure_quanta.q_cap(chips)';

PART_NAME
 C529 'Q_CAP_0805-47UF,4V,20%,X6S,CH647KMEA00':;

SECTION_NUMBER 1
 '@T6G_MB_LIB.T6G(SCH_1):PAGE79_I134@PURE_QUANTA.Q_CAP(CHIPS)':
 C_PATH='@t6g_mb_lib.t6g(sch_1):page79_i134@pure_quanta.q_cap(chips)';

PART_NAME
 C528 'Q_CAP_0805-47UF,4V,20%,X6S,CH647KMEA00':;

SECTION_NUMBER 1
 '@T6G_MB_LIB.T6G(SCH_1):PAGE79_I169@PURE_QUANTA.Q_CAP(CHIPS)':
 C_PATH='@t6g_mb_lib.t6g(sch_1):page79_i169@pure_quanta.q_cap(chips)';

PART_NAME
 C526 'Q_CAP_0805-47UF,4V,20%,X6S,CH647KMEA00':;

SECTION_NUMBER 1
 '@T6G_MB_LIB.T6G(SCH_1):PAGE79_I136@PURE_QUANTA.Q_CAP(CHIPS)':
 C_PATH='@t6g_mb_lib.t6g(sch_1):page79_i136@pure_quanta.q_cap(chips)';

PART_NAME
 C525 'Q_CAP_0805-47UF,4V,20%,X6S,CH647KMEA00':;

SECTION_NUMBER 1
 '@T6G_MB_LIB.T6G(SCH_1):PAGE79_I170@PURE_QUANTA.Q_CAP(CHIPS)':
 C_PATH='@t6g_mb_lib.t6g(sch_1):page79_i170@pure_quanta.q_cap(chips)';

PART_NAME
 C523 'Q_CAP_0805-47UF,4V,20%,X6S,CH647KMEA00':;

SECTION_NUMBER 1
 '@T6G_MB_LIB.T6G(SCH_1):PAGE79_I137@PURE_QUANTA.Q_CAP(CHIPS)':
 C_PATH='@t6g_mb_lib.t6g(sch_1):page79_i137@pure_quanta.q_cap(chips)';

PART_NAME
 C521 'Q_CAP_0805-47UF,4V,20%,X6S,CH647KMEA00':;

SECTION_NUMBER 1
 '@T6G_MB_LIB.T6G(SCH_1):PAGE79_I138@PURE_QUANTA.Q_CAP(CHIPS)':
 C_PATH='@t6g_mb_lib.t6g(sch_1):page79_i138@pure_quanta.q_cap(chips)';

PART_NAME
 C520 'Q_CAP_0805-47UF,4V,20%,X6S,CH647KMEA00':;

SECTION_NUMBER 1
 '@T6G_MB_LIB.T6G(SCH_1):PAGE79_I139@PURE_QUANTA.Q_CAP(CHIPS)':
 C_PATH='@t6g_mb_lib.t6g(sch_1):page79_i139@pure_quanta.q_cap(chips)';

PART_NAME
 C519 'Q_CAP_C0603-47UF,2.5V,20%,X6S,CH647LME901':;

SECTION_NUMBER 1
 '@T6G_MB_LIB.T6G(SCH_1):PAGE79_I140@PURE_QUANTA.Q_CAP(CHIPS)':
 C_PATH='@t6g_mb_lib.t6g(sch_1):page79_i140@pure_quanta.q_cap(chips)';

PART_NAME
 C517 'Q_CAP_0805-47UF,4V,20%,X6S,CH647KMEA00':;

SECTION_NUMBER 1
 '@T6G_MB_LIB.T6G(SCH_1):PAGE79_I146@PURE_QUANTA.Q_CAP(CHIPS)':
 C_PATH='@t6g_mb_lib.t6g(sch_1):page79_i146@pure_quanta.q_cap(chips)';

PART_NAME
 C516 'Q_CAP_C0603-47UF,2.5V,20%,X6S,CH647LME901':;

SECTION_NUMBER 1
 '@T6G_MB_LIB.T6G(SCH_1):PAGE79_I142@PURE_QUANTA.Q_CAP(CHIPS)':
 C_PATH='@t6g_mb_lib.t6g(sch_1):page79_i142@pure_quanta.q_cap(chips)';

PART_NAME
 C514 'Q_CAP_0805-47UF,4V,20%,X6S,CH647KMEA00':;

SECTION_NUMBER 1
 '@T6G_MB_LIB.T6G(SCH_1):PAGE79_I147@PURE_QUANTA.Q_CAP(CHIPS)':
 C_PATH='@t6g_mb_lib.t6g(sch_1):page79_i147@pure_quanta.q_cap(chips)';

PART_NAME
 C512 'Q_CAP_0805-47UF,4V,20%,X6S,CH647KMEA00':;

SECTION_NUMBER 1
 '@T6G_MB_LIB.T6G(SCH_1):PAGE79_I143@PURE_QUANTA.Q_CAP(CHIPS)':
 C_PATH='@t6g_mb_lib.t6g(sch_1):page79_i143@pure_quanta.q_cap(chips)';

PART_NAME
 C511 'Q_CAP_0805-47UF,4V,20%,X6S,CH647KMEA00':;

SECTION_NUMBER 1
 '@T6G_MB_LIB.T6G(SCH_1):PAGE79_I132@PURE_QUANTA.Q_CAP(CHIPS)':
 C_PATH='@t6g_mb_lib.t6g(sch_1):page79_i132@pure_quanta.q_cap(chips)';

PART_NAME
 C510 'Q_CAP_0805-47UF,4V,20%,X6S,CH647KMEA00':;

SECTION_NUMBER 1
 '@T6G_MB_LIB.T6G(SCH_1):PAGE79_I148@PURE_QUANTA.Q_CAP(CHIPS)':
 C_PATH='@t6g_mb_lib.t6g(sch_1):page79_i148@pure_quanta.q_cap(chips)';

PART_NAME
 C508 'Q_CAP_0805-47UF,4V,20%,X6S,CH647KMEA00':;

SECTION_NUMBER 1
 '@T6G_MB_LIB.T6G(SCH_1):PAGE79_I164@PURE_QUANTA.Q_CAP(CHIPS)':
 C_PATH='@t6g_mb_lib.t6g(sch_1):page79_i164@pure_quanta.q_cap(chips)';

PART_NAME
 C507 'Q_CAP_0805-47UF,4V,20%,X6S,CH647KMEA00':;

SECTION_NUMBER 1
 '@T6G_MB_LIB.T6G(SCH_1):PAGE79_I154@PURE_QUANTA.Q_CAP(CHIPS)':
 C_PATH='@t6g_mb_lib.t6g(sch_1):page79_i154@pure_quanta.q_cap(chips)';

PART_NAME
 C506 'Q_CAP_0805-47UF,4V,20%,X6S,CH647KMEA00':;

SECTION_NUMBER 1
 '@T6G_MB_LIB.T6G(SCH_1):PAGE79_I149@PURE_QUANTA.Q_CAP(CHIPS)':
 C_PATH='@t6g_mb_lib.t6g(sch_1):page79_i149@pure_quanta.q_cap(chips)';

PART_NAME
 C504 'Q_CAP_0805-47UF,4V,20%,X6S,CH647KMEA00':;

SECTION_NUMBER 1
 '@T6G_MB_LIB.T6G(SCH_1):PAGE79_I165@PURE_QUANTA.Q_CAP(CHIPS)':
 C_PATH='@t6g_mb_lib.t6g(sch_1):page79_i165@pure_quanta.q_cap(chips)';

PART_NAME
 C503 'Q_CAP_0805-47UF,4V,20%,X6S,CH647KMEA00':;

SECTION_NUMBER 1
 '@T6G_MB_LIB.T6G(SCH_1):PAGE79_I155@PURE_QUANTA.Q_CAP(CHIPS)':
 C_PATH='@t6g_mb_lib.t6g(sch_1):page79_i155@pure_quanta.q_cap(chips)';

PART_NAME
 C502 'Q_CAP_0805-47UF,4V,20%,X6S,CH647KMEA00':;

SECTION_NUMBER 1
 '@T6G_MB_LIB.T6G(SCH_1):PAGE79_I172@PURE_QUANTA.Q_CAP(CHIPS)':
 C_PATH='@t6g_mb_lib.t6g(sch_1):page79_i172@pure_quanta.q_cap(chips)';

PART_NAME
 C500 'Q_CAP_0805-47UF,4V,20%,X6S,CH647KMEA00':;

SECTION_NUMBER 1
 '@T6G_MB_LIB.T6G(SCH_1):PAGE79_I166@PURE_QUANTA.Q_CAP(CHIPS)':
 C_PATH='@t6g_mb_lib.t6g(sch_1):page79_i166@pure_quanta.q_cap(chips)';

PART_NAME
 C499 'Q_CAP_0805-47UF,4V,20%,X6S,CH647KMEA00':;

SECTION_NUMBER 1
 '@T6G_MB_LIB.T6G(SCH_1):PAGE79_I157@PURE_QUANTA.Q_CAP(CHIPS)':
 C_PATH='@t6g_mb_lib.t6g(sch_1):page79_i157@pure_quanta.q_cap(chips)';

PART_NAME
 C498 'Q_CAP_0805-47UF,4V,20%,X6S,CH647KMEA00':;

SECTION_NUMBER 1
 '@T6G_MB_LIB.T6G(SCH_1):PAGE79_I173@PURE_QUANTA.Q_CAP(CHIPS)':
 C_PATH='@t6g_mb_lib.t6g(sch_1):page79_i173@pure_quanta.q_cap(chips)';

PART_NAME
 C494 'Q_CAP_0805-47UF,4V,20%,X6S,CH647KMEA00':;

SECTION_NUMBER 1
 '@T6G_MB_LIB.T6G(SCH_1):PAGE79_I174@PURE_QUANTA.Q_CAP(CHIPS)':
 C_PATH='@t6g_mb_lib.t6g(sch_1):page79_i174@pure_quanta.q_cap(chips)';

PART_NAME
 C398 'Q_CAP_0805-47UF,4V,20%,X6S,CH647KMEA00':;

SECTION_NUMBER 1
 '@T6G_MB_LIB.T6G(SCH_1):PAGE79_I128@PURE_QUANTA.Q_CAP(CHIPS)':
 C_PATH='@t6g_mb_lib.t6g(sch_1):page79_i128@pure_quanta.q_cap(chips)';

PART_NAME
 C396 'Q_CAP_0805-47UF,4V,20%,X6S,CH647KMEA00':;

SECTION_NUMBER 1
 '@T6G_MB_LIB.T6G(SCH_1):PAGE79_I129@PURE_QUANTA.Q_CAP(CHIPS)':
 C_PATH='@t6g_mb_lib.t6g(sch_1):page79_i129@pure_quanta.q_cap(chips)';

PART_NAME
 C394 'Q_CAP_0805-47UF,4V,20%,X6S,CH647KMEA00':;

SECTION_NUMBER 1
 '@T6G_MB_LIB.T6G(SCH_1):PAGE79_I130@PURE_QUANTA.Q_CAP(CHIPS)':
 C_PATH='@t6g_mb_lib.t6g(sch_1):page79_i130@pure_quanta.q_cap(chips)';

PART_NAME
 C392 'Q_CAP_0805-47UF,4V,20%,X6S,CH647KMEA00':;

SECTION_NUMBER 1
 '@T6G_MB_LIB.T6G(SCH_1):PAGE79_I131@PURE_QUANTA.Q_CAP(CHIPS)':
 C_PATH='@t6g_mb_lib.t6g(sch_1):page79_i131@pure_quanta.q_cap(chips)';

PART_NAME
 C390 'Q_CAP_0805-47UF,4V,20%,X6S,CH647KMEA00':;

SECTION_NUMBER 1
 '@T6G_MB_LIB.T6G(SCH_1):PAGE79_I150@PURE_QUANTA.Q_CAP(CHIPS)':
 C_PATH='@t6g_mb_lib.t6g(sch_1):page79_i150@pure_quanta.q_cap(chips)';

PART_NAME
 C388 'Q_CAP_0805-47UF,4V,20%,X6S,CH647KMEA00':;

SECTION_NUMBER 1
 '@T6G_MB_LIB.T6G(SCH_1):PAGE79_I152@PURE_QUANTA.Q_CAP(CHIPS)':
 C_PATH='@t6g_mb_lib.t6g(sch_1):page79_i152@pure_quanta.q_cap(chips)';

PART_NAME
 C386 'Q_CAP_0805-47UF,4V,20%,X6S,CH647KMEA00':;

SECTION_NUMBER 1
 '@T6G_MB_LIB.T6G(SCH_1):PAGE79_I153@PURE_QUANTA.Q_CAP(CHIPS)':
 C_PATH='@t6g_mb_lib.t6g(sch_1):page79_i153@pure_quanta.q_cap(chips)';

PART_NAME
 C383 'Q_CAP_0805-47UF,4V,20%,X6S,CH647KMEA00':;

SECTION_NUMBER 1
 '@T6G_MB_LIB.T6G(SCH_1):PAGE79_I121@PURE_QUANTA.Q_CAP(CHIPS)':
 C_PATH='@t6g_mb_lib.t6g(sch_1):page79_i121@pure_quanta.q_cap(chips)';

PART_NAME
 C380 'Q_CAP_0805-47UF,4V,20%,X6S,CH647KMEA00':;

SECTION_NUMBER 1
 '@T6G_MB_LIB.T6G(SCH_1):PAGE79_I122@PURE_QUANTA.Q_CAP(CHIPS)':
 C_PATH='@t6g_mb_lib.t6g(sch_1):page79_i122@pure_quanta.q_cap(chips)';

PART_NAME
 C377 'Q_CAP_0805-47UF,4V,20%,X6S,CH647KMEA00':;

SECTION_NUMBER 1
 '@T6G_MB_LIB.T6G(SCH_1):PAGE79_I123@PURE_QUANTA.Q_CAP(CHIPS)':
 C_PATH='@t6g_mb_lib.t6g(sch_1):page79_i123@pure_quanta.q_cap(chips)';

PART_NAME
 C374 'Q_CAP_0805-47UF,4V,20%,X6S,CH647KMEA00':;

SECTION_NUMBER 1
 '@T6G_MB_LIB.T6G(SCH_1):PAGE79_I124@PURE_QUANTA.Q_CAP(CHIPS)':
 C_PATH='@t6g_mb_lib.t6g(sch_1):page79_i124@pure_quanta.q_cap(chips)';

PART_NAME
 C372 'Q_CAP_0805-47UF,4V,20%,X6S,CH647KMEA00':;

SECTION_NUMBER 1
 '@T6G_MB_LIB.T6G(SCH_1):PAGE79_I125@PURE_QUANTA.Q_CAP(CHIPS)':
 C_PATH='@t6g_mb_lib.t6g(sch_1):page79_i125@pure_quanta.q_cap(chips)';

PART_NAME
 C369 'Q_CAP_0805-47UF,4V,20%,X6S,CH647KMEA00':;

SECTION_NUMBER 1
 '@T6G_MB_LIB.T6G(SCH_1):PAGE79_I126@PURE_QUANTA.Q_CAP(CHIPS)':
 C_PATH='@t6g_mb_lib.t6g(sch_1):page79_i126@pure_quanta.q_cap(chips)';

PART_NAME
 C366 'Q_CAP_0805-47UF,4V,20%,X6S,CH647KMEA00':;

SECTION_NUMBER 1
 '@T6G_MB_LIB.T6G(SCH_1):PAGE79_I127@PURE_QUANTA.Q_CAP(CHIPS)':
 C_PATH='@t6g_mb_lib.t6g(sch_1):page79_i127@pure_quanta.q_cap(chips)';

PART_NAME
 C1407 'Q_CAP_C0603-47UF,2.5V,20%,X6S,CH647LME901':;

SECTION_NUMBER 1
 '@T6G_MB_LIB.T6G(SCH_1):PAGE78_I155@PURE_QUANTA.Q_CAP(CHIPS)':
 C_PATH='@t6g_mb_lib.t6g(sch_1):page78_i155@pure_quanta.q_cap(chips)';

PART_NAME
 C1406 'Q_CAP_C0603-47UF,2.5V,20%,X6S,CH647LME901':;

SECTION_NUMBER 1
 '@T6G_MB_LIB.T6G(SCH_1):PAGE78_I156@PURE_QUANTA.Q_CAP(CHIPS)':
 C_PATH='@t6g_mb_lib.t6g(sch_1):page78_i156@pure_quanta.q_cap(chips)';

PART_NAME
 C1405 'Q_CAP_C0603-47UF,2.5V,20%,X6S,CH647LME901':;

SECTION_NUMBER 1
 '@T6G_MB_LIB.T6G(SCH_1):PAGE78_I169@PURE_QUANTA.Q_CAP(CHIPS)':
 C_PATH='@t6g_mb_lib.t6g(sch_1):page78_i169@pure_quanta.q_cap(chips)';

PART_NAME
 C1398 'Q_CAP_0805-47UF,4V,20%,X6S,CH647KMEA00':;

SECTION_NUMBER 1
 '@T6G_MB_LIB.T6G(SCH_1):PAGE78_I158@PURE_QUANTA.Q_CAP(CHIPS)':
 C_PATH='@t6g_mb_lib.t6g(sch_1):page78_i158@pure_quanta.q_cap(chips)';

PART_NAME
 C1397 'Q_CAP_0805-47UF,4V,20%,X6S,CH647KMEA00':;

SECTION_NUMBER 1
 '@T6G_MB_LIB.T6G(SCH_1):PAGE78_I172@PURE_QUANTA.Q_CAP(CHIPS)':
 C_PATH='@t6g_mb_lib.t6g(sch_1):page78_i172@pure_quanta.q_cap(chips)';

PART_NAME
 C1396 'Q_CAP_0805-47UF,4V,20%,X6S,CH647KMEA00':;

SECTION_NUMBER 1
 '@T6G_MB_LIB.T6G(SCH_1):PAGE78_I173@PURE_QUANTA.Q_CAP(CHIPS)':
 C_PATH='@t6g_mb_lib.t6g(sch_1):page78_i173@pure_quanta.q_cap(chips)';

PART_NAME
 C534 'Q_CAP_C0402-10UF,4V,20%,X6S,CH610KMEB09':;

SECTION_NUMBER 1
 '@T6G_MB_LIB.T6G(SCH_1):PAGE78_I187@PURE_QUANTA.Q_CAP(CHIPS)':
 C_PATH='@t6g_mb_lib.t6g(sch_1):page78_i187@pure_quanta.q_cap(chips)';

PART_NAME
 C533 'Q_CAP_C0603-47UF,2.5V,20%,X6S,CH647LME901':;

SECTION_NUMBER 1
 '@T6G_MB_LIB.T6G(SCH_1):PAGE78_I199@PURE_QUANTA.Q_CAP(CHIPS)':
 C_PATH='@t6g_mb_lib.t6g(sch_1):page78_i199@pure_quanta.q_cap(chips)';

PART_NAME
 C532 'Q_CAP_C0603-47UF,2.5V,20%,X6S,CH647LME901':;

SECTION_NUMBER 1
 '@T6G_MB_LIB.T6G(SCH_1):PAGE78_I202@PURE_QUANTA.Q_CAP(CHIPS)':
 C_PATH='@t6g_mb_lib.t6g(sch_1):page78_i202@pure_quanta.q_cap(chips)';

PART_NAME
 C527 'Q_CAP_C0603-47UF,2.5V,20%,X6S,CH647LME901':;

SECTION_NUMBER 1
 '@T6G_MB_LIB.T6G(SCH_1):PAGE78_I148@PURE_QUANTA.Q_CAP(CHIPS)':
 C_PATH='@t6g_mb_lib.t6g(sch_1):page78_i148@pure_quanta.q_cap(chips)';

PART_NAME
 C524 'Q_CAP_C0603-47UF,2.5V,20%,X6S,CH647LME901':;

SECTION_NUMBER 1
 '@T6G_MB_LIB.T6G(SCH_1):PAGE78_I149@PURE_QUANTA.Q_CAP(CHIPS)':
 C_PATH='@t6g_mb_lib.t6g(sch_1):page78_i149@pure_quanta.q_cap(chips)';

PART_NAME
 C522 'Q_CAP_0805-47UF,4V,20%,X6S,CH647KMEA00':;

SECTION_NUMBER 1
 '@T6G_MB_LIB.T6G(SCH_1):PAGE78_I207@PURE_QUANTA.Q_CAP(CHIPS)':
 C_PATH='@t6g_mb_lib.t6g(sch_1):page78_i207@pure_quanta.q_cap(chips)';

PART_NAME
 C518 'Q_CAP_C0603-47UF,2.5V,20%,X6S,CH647LME901':;

SECTION_NUMBER 1
 '@T6G_MB_LIB.T6G(SCH_1):PAGE78_I185@PURE_QUANTA.Q_CAP(CHIPS)':
 C_PATH='@t6g_mb_lib.t6g(sch_1):page78_i185@pure_quanta.q_cap(chips)';

PART_NAME
 C515 'Q_CAP_C0603-47UF,2.5V,20%,X6S,CH647LME901':;

SECTION_NUMBER 1
 '@T6G_MB_LIB.T6G(SCH_1):PAGE78_I197@PURE_QUANTA.Q_CAP(CHIPS)':
 C_PATH='@t6g_mb_lib.t6g(sch_1):page78_i197@pure_quanta.q_cap(chips)';

PART_NAME
 C509 'Q_CAP_C0603-47UF,2.5V,20%,X6S,CH647LME901':;

SECTION_NUMBER 1
 '@T6G_MB_LIB.T6G(SCH_1):PAGE78_I208@PURE_QUANTA.Q_CAP(CHIPS)':
 C_PATH='@t6g_mb_lib.t6g(sch_1):page78_i208@pure_quanta.q_cap(chips)';

PART_NAME
 C505 'Q_CAP_0805-47UF,4V,20%,X6S,CH647KMEA00':;

SECTION_NUMBER 1
 '@T6G_MB_LIB.T6G(SCH_1):PAGE78_I210@PURE_QUANTA.Q_CAP(CHIPS)':
 C_PATH='@t6g_mb_lib.t6g(sch_1):page78_i210@pure_quanta.q_cap(chips)';

PART_NAME
 C501 'Q_CAP_0805-47UF,4V,20%,X6S,CH647KMEA00':;

SECTION_NUMBER 1
 '@T6G_MB_LIB.T6G(SCH_1):PAGE78_I212@PURE_QUANTA.Q_CAP(CHIPS)':
 C_PATH='@t6g_mb_lib.t6g(sch_1):page78_i212@pure_quanta.q_cap(chips)';

PART_NAME
 C497 'Q_CAP_0805-47UF,4V,20%,X6S,CH647KMEA00':;

SECTION_NUMBER 1
 '@T6G_MB_LIB.T6G(SCH_1):PAGE78_I213@PURE_QUANTA.Q_CAP(CHIPS)':
 C_PATH='@t6g_mb_lib.t6g(sch_1):page78_i213@pure_quanta.q_cap(chips)';

PART_NAME
 C496 'Q_CAP_0805-47UF,4V,20%,X6S,CH647KMEA00':;

SECTION_NUMBER 1
 '@T6G_MB_LIB.T6G(SCH_1):PAGE78_I200@PURE_QUANTA.Q_CAP(CHIPS)':
 C_PATH='@t6g_mb_lib.t6g(sch_1):page78_i200@pure_quanta.q_cap(chips)';

PART_NAME
 C495 'Q_CAP_0805-47UF,4V,20%,X6S,CH647KMEA00':;

SECTION_NUMBER 1
 '@T6G_MB_LIB.T6G(SCH_1):PAGE78_I198@PURE_QUANTA.Q_CAP(CHIPS)':
 C_PATH='@t6g_mb_lib.t6g(sch_1):page78_i198@pure_quanta.q_cap(chips)';

PART_NAME
 C493 'Q_CAP_0805-47UF,4V,20%,X6S,CH647KMEA00':;

SECTION_NUMBER 1
 '@T6G_MB_LIB.T6G(SCH_1):PAGE78_I215@PURE_QUANTA.Q_CAP(CHIPS)':
 C_PATH='@t6g_mb_lib.t6g(sch_1):page78_i215@pure_quanta.q_cap(chips)';

PART_NAME
 C492 'Q_CAP_0805-47UF,4V,20%,X6S,CH647KMEA00':;

SECTION_NUMBER 1
 '@T6G_MB_LIB.T6G(SCH_1):PAGE78_I205@PURE_QUANTA.Q_CAP(CHIPS)':
 C_PATH='@t6g_mb_lib.t6g(sch_1):page78_i205@pure_quanta.q_cap(chips)';

PART_NAME
 C491 'Q_CAP_0805-47UF,4V,20%,X6S,CH647KMEA00':;

SECTION_NUMBER 1
 '@T6G_MB_LIB.T6G(SCH_1):PAGE78_I203@PURE_QUANTA.Q_CAP(CHIPS)':
 C_PATH='@t6g_mb_lib.t6g(sch_1):page78_i203@pure_quanta.q_cap(chips)';

PART_NAME
 C397 'Q_CAP_0805-47UF,4V,20%,X6S,CH647KMEA00':;

SECTION_NUMBER 1
 '@T6G_MB_LIB.T6G(SCH_1):PAGE78_I179@PURE_QUANTA.Q_CAP(CHIPS)':
 C_PATH='@t6g_mb_lib.t6g(sch_1):page78_i179@pure_quanta.q_cap(chips)';

PART_NAME
 C395 'Q_CAP_0805-47UF,4V,20%,X6S,CH647KMEA00':;

SECTION_NUMBER 1
 '@T6G_MB_LIB.T6G(SCH_1):PAGE78_I170@PURE_QUANTA.Q_CAP(CHIPS)':
 C_PATH='@t6g_mb_lib.t6g(sch_1):page78_i170@pure_quanta.q_cap(chips)';

PART_NAME
 C393 'Q_CAP_0805-47UF,4V,20%,X6S,CH647KMEA00':;

SECTION_NUMBER 1
 '@T6G_MB_LIB.T6G(SCH_1):PAGE78_I164@PURE_QUANTA.Q_CAP(CHIPS)':
 C_PATH='@t6g_mb_lib.t6g(sch_1):page78_i164@pure_quanta.q_cap(chips)';

PART_NAME
 C391 'Q_CAP_0805-47UF,4V,20%,X6S,CH647KMEA00':;

SECTION_NUMBER 1
 '@T6G_MB_LIB.T6G(SCH_1):PAGE78_I167@PURE_QUANTA.Q_CAP(CHIPS)':
 C_PATH='@t6g_mb_lib.t6g(sch_1):page78_i167@pure_quanta.q_cap(chips)';

PART_NAME
 C389 'Q_CAP_0805-47UF,4V,20%,X6S,CH647KMEA00':;

SECTION_NUMBER 1
 '@T6G_MB_LIB.T6G(SCH_1):PAGE78_I168@PURE_QUANTA.Q_CAP(CHIPS)':
 C_PATH='@t6g_mb_lib.t6g(sch_1):page78_i168@pure_quanta.q_cap(chips)';

PART_NAME
 C387 'Q_CAP_0805-47UF,4V,20%,X6S,CH647KMEA00':;

SECTION_NUMBER 1
 '@T6G_MB_LIB.T6G(SCH_1):PAGE78_I160@PURE_QUANTA.Q_CAP(CHIPS)':
 C_PATH='@t6g_mb_lib.t6g(sch_1):page78_i160@pure_quanta.q_cap(chips)';

PART_NAME
 C385 'Q_CAP_0805-47UF,4V,20%,X6S,CH647KMEA00':;

SECTION_NUMBER 1
 '@T6G_MB_LIB.T6G(SCH_1):PAGE78_I161@PURE_QUANTA.Q_CAP(CHIPS)':
 C_PATH='@t6g_mb_lib.t6g(sch_1):page78_i161@pure_quanta.q_cap(chips)';

PART_NAME
 C384 'Q_CAP_C0603-47UF,2.5V,20%,X6S,CH647LME901':;

SECTION_NUMBER 1
 '@T6G_MB_LIB.T6G(SCH_1):PAGE78_I150@PURE_QUANTA.Q_CAP(CHIPS)':
 C_PATH='@t6g_mb_lib.t6g(sch_1):page78_i150@pure_quanta.q_cap(chips)';

PART_NAME
 C382 'Q_CAP_0805-47UF,4V,20%,X6S,CH647KMEA00':;

SECTION_NUMBER 1
 '@T6G_MB_LIB.T6G(SCH_1):PAGE78_I165@PURE_QUANTA.Q_CAP(CHIPS)':
 C_PATH='@t6g_mb_lib.t6g(sch_1):page78_i165@pure_quanta.q_cap(chips)';

PART_NAME
 C381 'Q_CAP_C0603-47UF,2.5V,20%,X6S,CH647LME901':;

SECTION_NUMBER 1
 '@T6G_MB_LIB.T6G(SCH_1):PAGE78_I152@PURE_QUANTA.Q_CAP(CHIPS)':
 C_PATH='@t6g_mb_lib.t6g(sch_1):page78_i152@pure_quanta.q_cap(chips)';

PART_NAME
 C379 'Q_CAP_0805-47UF,4V,20%,X6S,CH647KMEA00':;

SECTION_NUMBER 1
 '@T6G_MB_LIB.T6G(SCH_1):PAGE78_I166@PURE_QUANTA.Q_CAP(CHIPS)':
 C_PATH='@t6g_mb_lib.t6g(sch_1):page78_i166@pure_quanta.q_cap(chips)';

PART_NAME
 C376 'Q_CAP_0805-47UF,4V,20%,X6S,CH647KMEA00':;

SECTION_NUMBER 1
 '@T6G_MB_LIB.T6G(SCH_1):PAGE78_I175@PURE_QUANTA.Q_CAP(CHIPS)':
 C_PATH='@t6g_mb_lib.t6g(sch_1):page78_i175@pure_quanta.q_cap(chips)';

PART_NAME
 C373 'Q_CAP_0805-47UF,4V,20%,X6S,CH647KMEA00':;

SECTION_NUMBER 1
 '@T6G_MB_LIB.T6G(SCH_1):PAGE78_I176@PURE_QUANTA.Q_CAP(CHIPS)':
 C_PATH='@t6g_mb_lib.t6g(sch_1):page78_i176@pure_quanta.q_cap(chips)';

PART_NAME
 C371 'Q_CAP_0805-47UF,4V,20%,X6S,CH647KMEA00':;

SECTION_NUMBER 1
 '@T6G_MB_LIB.T6G(SCH_1):PAGE78_I180@PURE_QUANTA.Q_CAP(CHIPS)':
 C_PATH='@t6g_mb_lib.t6g(sch_1):page78_i180@pure_quanta.q_cap(chips)';

PART_NAME
 C370 'Q_CAP_0805-47UF,4V,20%,X6S,CH647KMEA00':;

SECTION_NUMBER 1
 '@T6G_MB_LIB.T6G(SCH_1):PAGE78_I177@PURE_QUANTA.Q_CAP(CHIPS)':
 C_PATH='@t6g_mb_lib.t6g(sch_1):page78_i177@pure_quanta.q_cap(chips)';

PART_NAME
 C368 'Q_CAP_0805-47UF,4V,20%,X6S,CH647KMEA00':;

SECTION_NUMBER 1
 '@T6G_MB_LIB.T6G(SCH_1):PAGE78_I183@PURE_QUANTA.Q_CAP(CHIPS)':
 C_PATH='@t6g_mb_lib.t6g(sch_1):page78_i183@pure_quanta.q_cap(chips)';

PART_NAME
 C367 'Q_CAP_0805-47UF,4V,20%,X6S,CH647KMEA00':;

SECTION_NUMBER 1
 '@T6G_MB_LIB.T6G(SCH_1):PAGE78_I181@PURE_QUANTA.Q_CAP(CHIPS)':
 C_PATH='@t6g_mb_lib.t6g(sch_1):page78_i181@pure_quanta.q_cap(chips)';

PART_NAME
 C365 'Q_CAP_0805-47UF,4V,20%,X6S,CH647KMEA00':;

SECTION_NUMBER 1
 '@T6G_MB_LIB.T6G(SCH_1):PAGE78_I184@PURE_QUANTA.Q_CAP(CHIPS)':
 C_PATH='@t6g_mb_lib.t6g(sch_1):page78_i184@pure_quanta.q_cap(chips)';

PART_NAME
 C364 'Q_CAP_0805-47UF,4V,20%,X6S,CH647KMEA00':;

SECTION_NUMBER 1
 '@T6G_MB_LIB.T6G(SCH_1):PAGE78_I182@PURE_QUANTA.Q_CAP(CHIPS)':
 C_PATH='@t6g_mb_lib.t6g(sch_1):page78_i182@pure_quanta.q_cap(chips)';

PART_NAME
 C363 'Q_CAP_0805-47UF,4V,20%,X6S,CH647KMEA00':;

SECTION_NUMBER 1
 '@T6G_MB_LIB.T6G(SCH_1):PAGE78_I153@PURE_QUANTA.Q_CAP(CHIPS)':
 C_PATH='@t6g_mb_lib.t6g(sch_1):page78_i153@pure_quanta.q_cap(chips)';

PART_NAME
 C362 'Q_CAP_0805-47UF,4V,20%,X6S,CH647KMEA00':;

SECTION_NUMBER 1
 '@T6G_MB_LIB.T6G(SCH_1):PAGE78_I190@PURE_QUANTA.Q_CAP(CHIPS)':
 C_PATH='@t6g_mb_lib.t6g(sch_1):page78_i190@pure_quanta.q_cap(chips)';

PART_NAME
 C361 'Q_CAP_0805-47UF,4V,20%,X6S,CH647KMEA00':;

SECTION_NUMBER 1
 '@T6G_MB_LIB.T6G(SCH_1):PAGE78_I188@PURE_QUANTA.Q_CAP(CHIPS)':
 C_PATH='@t6g_mb_lib.t6g(sch_1):page78_i188@pure_quanta.q_cap(chips)';

PART_NAME
 C360 'Q_CAP_0805-47UF,4V,20%,X6S,CH647KMEA00':;

SECTION_NUMBER 1
 '@T6G_MB_LIB.T6G(SCH_1):PAGE78_I162@PURE_QUANTA.Q_CAP(CHIPS)':
 C_PATH='@t6g_mb_lib.t6g(sch_1):page78_i162@pure_quanta.q_cap(chips)';

PART_NAME
 C359 'Q_CAP_0805-47UF,4V,20%,X6S,CH647KMEA00':;

SECTION_NUMBER 1
 '@T6G_MB_LIB.T6G(SCH_1):PAGE78_I191@PURE_QUANTA.Q_CAP(CHIPS)':
 C_PATH='@t6g_mb_lib.t6g(sch_1):page78_i191@pure_quanta.q_cap(chips)';

PART_NAME
 C358 'Q_CAP_0805-47UF,4V,20%,X6S,CH647KMEA00':;

SECTION_NUMBER 1
 '@T6G_MB_LIB.T6G(SCH_1):PAGE78_I189@PURE_QUANTA.Q_CAP(CHIPS)':
 C_PATH='@t6g_mb_lib.t6g(sch_1):page78_i189@pure_quanta.q_cap(chips)';

PART_NAME
 C357 'Q_CAP_0805-47UF,4V,20%,X6S,CH647KMEA00':;

SECTION_NUMBER 1
 '@T6G_MB_LIB.T6G(SCH_1):PAGE78_I178@PURE_QUANTA.Q_CAP(CHIPS)':
 C_PATH='@t6g_mb_lib.t6g(sch_1):page78_i178@pure_quanta.q_cap(chips)';

PART_NAME
 C356 'Q_CAP_0805-47UF,4V,20%,X6S,CH647KMEA00':;

SECTION_NUMBER 1
 '@T6G_MB_LIB.T6G(SCH_1):PAGE78_I195@PURE_QUANTA.Q_CAP(CHIPS)':
 C_PATH='@t6g_mb_lib.t6g(sch_1):page78_i195@pure_quanta.q_cap(chips)';

PART_NAME
 C355 'Q_CAP_0805-47UF,4V,20%,X6S,CH647KMEA00':;

SECTION_NUMBER 1
 '@T6G_MB_LIB.T6G(SCH_1):PAGE78_I193@PURE_QUANTA.Q_CAP(CHIPS)':
 C_PATH='@t6g_mb_lib.t6g(sch_1):page78_i193@pure_quanta.q_cap(chips)';

PART_NAME
 C1404 'Q_CAP_0805-47UF,4V,20%,X6S,CH647KMEA00':;

SECTION_NUMBER 1
 '@T6G_MB_LIB.T6G(SCH_1):PAGE82_I131@PURE_QUANTA.Q_CAP(CHIPS)':
 C_PATH='@t6g_mb_lib.t6g(sch_1):page82_i131@pure_quanta.q_cap(chips)';

PART_NAME
 C1403 'Q_CAP_0805-47UF,4V,20%,X6S,CH647KMEA00':;

SECTION_NUMBER 1
 '@T6G_MB_LIB.T6G(SCH_1):PAGE82_I132@PURE_QUANTA.Q_CAP(CHIPS)':
 C_PATH='@t6g_mb_lib.t6g(sch_1):page82_i132@pure_quanta.q_cap(chips)';

PART_NAME
 C1353 'Q_CAP_C0402-10UF,4V,20%,X6S,CH610KMEB09':;

SECTION_NUMBER 1
 '@T6G_MB_LIB.T6G(SCH_1):PAGE82_I126@PURE_QUANTA.Q_CAP(CHIPS)':
 C_PATH='@t6g_mb_lib.t6g(sch_1):page82_i126@pure_quanta.q_cap(chips)';

PART_NAME
 C487 'Q_CAP_0805-47UF,4V,20%,X6S,CH647KMEA00':;

SECTION_NUMBER 1
 '@T6G_MB_LIB.T6G(SCH_1):PAGE82_I165@PURE_QUANTA.Q_CAP(CHIPS)':
 C_PATH='@t6g_mb_lib.t6g(sch_1):page82_i165@pure_quanta.q_cap(chips)';

PART_NAME
 C486 'Q_CAP_0805-47UF,4V,20%,X6S,CH647KMEA00':;

SECTION_NUMBER 1
 '@T6G_MB_LIB.T6G(SCH_1):PAGE82_I164@PURE_QUANTA.Q_CAP(CHIPS)':
 C_PATH='@t6g_mb_lib.t6g(sch_1):page82_i164@pure_quanta.q_cap(chips)';

PART_NAME
 C485 'Q_CAP_0805-47UF,4V,20%,X6S,CH647KMEA00':;

SECTION_NUMBER 1
 '@T6G_MB_LIB.T6G(SCH_1):PAGE82_I133@PURE_QUANTA.Q_CAP(CHIPS)':
 C_PATH='@t6g_mb_lib.t6g(sch_1):page82_i133@pure_quanta.q_cap(chips)';

PART_NAME
 C484 'Q_CAP_0805-47UF,4V,20%,X6S,CH647KMEA00':;

SECTION_NUMBER 1
 '@T6G_MB_LIB.T6G(SCH_1):PAGE82_I163@PURE_QUANTA.Q_CAP(CHIPS)':
 C_PATH='@t6g_mb_lib.t6g(sch_1):page82_i163@pure_quanta.q_cap(chips)';

PART_NAME
 C482 'Q_CAP_0805-47UF,4V,20%,X6S,CH647KMEA00':;

SECTION_NUMBER 1
 '@T6G_MB_LIB.T6G(SCH_1):PAGE82_I134@PURE_QUANTA.Q_CAP(CHIPS)':
 C_PATH='@t6g_mb_lib.t6g(sch_1):page82_i134@pure_quanta.q_cap(chips)';

PART_NAME
 C481 'Q_CAP_0805-47UF,4V,20%,X6S,CH647KMEA00':;

SECTION_NUMBER 1
 '@T6G_MB_LIB.T6G(SCH_1):PAGE82_I162@PURE_QUANTA.Q_CAP(CHIPS)':
 C_PATH='@t6g_mb_lib.t6g(sch_1):page82_i162@pure_quanta.q_cap(chips)';

PART_NAME
 C479 'Q_CAP_0805-47UF,4V,20%,X6S,CH647KMEA00':;

SECTION_NUMBER 1
 '@T6G_MB_LIB.T6G(SCH_1):PAGE82_I136@PURE_QUANTA.Q_CAP(CHIPS)':
 C_PATH='@t6g_mb_lib.t6g(sch_1):page82_i136@pure_quanta.q_cap(chips)';

PART_NAME
 C477 'Q_CAP_0805-47UF,4V,20%,X6S,CH647KMEA00':;

SECTION_NUMBER 1
 '@T6G_MB_LIB.T6G(SCH_1):PAGE82_I137@PURE_QUANTA.Q_CAP(CHIPS)':
 C_PATH='@t6g_mb_lib.t6g(sch_1):page82_i137@pure_quanta.q_cap(chips)';

PART_NAME
 C476 'Q_CAP_0805-47UF,4V,20%,X6S,CH647KMEA00':;

SECTION_NUMBER 1
 '@T6G_MB_LIB.T6G(SCH_1):PAGE82_I138@PURE_QUANTA.Q_CAP(CHIPS)':
 C_PATH='@t6g_mb_lib.t6g(sch_1):page82_i138@pure_quanta.q_cap(chips)';

PART_NAME
 C475 'Q_CAP_C0603-47UF,2.5V,20%,X6S,CH647LME901':;

SECTION_NUMBER 1
 '@T6G_MB_LIB.T6G(SCH_1):PAGE82_I146@PURE_QUANTA.Q_CAP(CHIPS)':
 C_PATH='@t6g_mb_lib.t6g(sch_1):page82_i146@pure_quanta.q_cap(chips)';

PART_NAME
 C473 'Q_CAP_0805-47UF,4V,20%,X6S,CH647KMEA00':;

SECTION_NUMBER 1
 '@T6G_MB_LIB.T6G(SCH_1):PAGE82_I166@PURE_QUANTA.Q_CAP(CHIPS)':
 C_PATH='@t6g_mb_lib.t6g(sch_1):page82_i166@pure_quanta.q_cap(chips)';

PART_NAME
 C472 'Q_CAP_C0603-47UF,2.5V,20%,X6S,CH647LME901':;

SECTION_NUMBER 1
 '@T6G_MB_LIB.T6G(SCH_1):PAGE82_I148@PURE_QUANTA.Q_CAP(CHIPS)':
 C_PATH='@t6g_mb_lib.t6g(sch_1):page82_i148@pure_quanta.q_cap(chips)';

PART_NAME
 C470 'Q_CAP_0805-47UF,4V,20%,X6S,CH647KMEA00':;

SECTION_NUMBER 1
 '@T6G_MB_LIB.T6G(SCH_1):PAGE82_I167@PURE_QUANTA.Q_CAP(CHIPS)':
 C_PATH='@t6g_mb_lib.t6g(sch_1):page82_i167@pure_quanta.q_cap(chips)';

PART_NAME
 C468 'Q_CAP_0805-47UF,4V,20%,X6S,CH647KMEA00':;

SECTION_NUMBER 1
 '@T6G_MB_LIB.T6G(SCH_1):PAGE82_I149@PURE_QUANTA.Q_CAP(CHIPS)':
 C_PATH='@t6g_mb_lib.t6g(sch_1):page82_i149@pure_quanta.q_cap(chips)';

PART_NAME
 C467 'Q_CAP_0805-47UF,4V,20%,X6S,CH647KMEA00':;

SECTION_NUMBER 1
 '@T6G_MB_LIB.T6G(SCH_1):PAGE82_I144@PURE_QUANTA.Q_CAP(CHIPS)':
 C_PATH='@t6g_mb_lib.t6g(sch_1):page82_i144@pure_quanta.q_cap(chips)';

PART_NAME
 C466 'Q_CAP_0805-47UF,4V,20%,X6S,CH647KMEA00':;

SECTION_NUMBER 1
 '@T6G_MB_LIB.T6G(SCH_1):PAGE82_I168@PURE_QUANTA.Q_CAP(CHIPS)':
 C_PATH='@t6g_mb_lib.t6g(sch_1):page82_i168@pure_quanta.q_cap(chips)';

PART_NAME
 C464 'Q_CAP_0805-47UF,4V,20%,X6S,CH647KMEA00':;

SECTION_NUMBER 1
 '@T6G_MB_LIB.T6G(SCH_1):PAGE82_I158@PURE_QUANTA.Q_CAP(CHIPS)':
 C_PATH='@t6g_mb_lib.t6g(sch_1):page82_i158@pure_quanta.q_cap(chips)';

PART_NAME
 C463 'Q_CAP_0805-47UF,4V,20%,X6S,CH647KMEA00':;

SECTION_NUMBER 1
 '@T6G_MB_LIB.T6G(SCH_1):PAGE82_I154@PURE_QUANTA.Q_CAP(CHIPS)':
 C_PATH='@t6g_mb_lib.t6g(sch_1):page82_i154@pure_quanta.q_cap(chips)';

PART_NAME
 C462 'Q_CAP_0805-47UF,4V,20%,X6S,CH647KMEA00':;

SECTION_NUMBER 1
 '@T6G_MB_LIB.T6G(SCH_1):PAGE82_I170@PURE_QUANTA.Q_CAP(CHIPS)':
 C_PATH='@t6g_mb_lib.t6g(sch_1):page82_i170@pure_quanta.q_cap(chips)';

PART_NAME
 C460 'Q_CAP_0805-47UF,4V,20%,X6S,CH647KMEA00':;

SECTION_NUMBER 1
 '@T6G_MB_LIB.T6G(SCH_1):PAGE82_I159@PURE_QUANTA.Q_CAP(CHIPS)':
 C_PATH='@t6g_mb_lib.t6g(sch_1):page82_i159@pure_quanta.q_cap(chips)';

PART_NAME
 C459 'Q_CAP_0805-47UF,4V,20%,X6S,CH647KMEA00':;

SECTION_NUMBER 1
 '@T6G_MB_LIB.T6G(SCH_1):PAGE82_I155@PURE_QUANTA.Q_CAP(CHIPS)':
 C_PATH='@t6g_mb_lib.t6g(sch_1):page82_i155@pure_quanta.q_cap(chips)';

PART_NAME
 C458 'Q_CAP_0805-47UF,4V,20%,X6S,CH647KMEA00':;

SECTION_NUMBER 1
 '@T6G_MB_LIB.T6G(SCH_1):PAGE82_I171@PURE_QUANTA.Q_CAP(CHIPS)':
 C_PATH='@t6g_mb_lib.t6g(sch_1):page82_i171@pure_quanta.q_cap(chips)';

PART_NAME
 C456 'Q_CAP_0805-47UF,4V,20%,X6S,CH647KMEA00':;

SECTION_NUMBER 1
 '@T6G_MB_LIB.T6G(SCH_1):PAGE82_I160@PURE_QUANTA.Q_CAP(CHIPS)':
 C_PATH='@t6g_mb_lib.t6g(sch_1):page82_i160@pure_quanta.q_cap(chips)';

PART_NAME
 C455 'Q_CAP_0805-47UF,4V,20%,X6S,CH647KMEA00':;

SECTION_NUMBER 1
 '@T6G_MB_LIB.T6G(SCH_1):PAGE82_I156@PURE_QUANTA.Q_CAP(CHIPS)':
 C_PATH='@t6g_mb_lib.t6g(sch_1):page82_i156@pure_quanta.q_cap(chips)';

PART_NAME
 C454 'Q_CAP_0805-47UF,4V,20%,X6S,CH647KMEA00':;

SECTION_NUMBER 1
 '@T6G_MB_LIB.T6G(SCH_1):PAGE82_I172@PURE_QUANTA.Q_CAP(CHIPS)':
 C_PATH='@t6g_mb_lib.t6g(sch_1):page82_i172@pure_quanta.q_cap(chips)';

PART_NAME
 C450 'Q_CAP_0805-47UF,4V,20%,X6S,CH647KMEA00':;

SECTION_NUMBER 1
 '@T6G_MB_LIB.T6G(SCH_1):PAGE82_I174@PURE_QUANTA.Q_CAP(CHIPS)':
 C_PATH='@t6g_mb_lib.t6g(sch_1):page82_i174@pure_quanta.q_cap(chips)';

PART_NAME
 C354 'Q_CAP_0805-47UF,4V,20%,X6S,CH647KMEA00':;

SECTION_NUMBER 1
 '@T6G_MB_LIB.T6G(SCH_1):PAGE82_I140@PURE_QUANTA.Q_CAP(CHIPS)':
 C_PATH='@t6g_mb_lib.t6g(sch_1):page82_i140@pure_quanta.q_cap(chips)';

PART_NAME
 C352 'Q_CAP_0805-47UF,4V,20%,X6S,CH647KMEA00':;

SECTION_NUMBER 1
 '@T6G_MB_LIB.T6G(SCH_1):PAGE82_I141@PURE_QUANTA.Q_CAP(CHIPS)':
 C_PATH='@t6g_mb_lib.t6g(sch_1):page82_i141@pure_quanta.q_cap(chips)';

PART_NAME
 C350 'Q_CAP_0805-47UF,4V,20%,X6S,CH647KMEA00':;

SECTION_NUMBER 1
 '@T6G_MB_LIB.T6G(SCH_1):PAGE82_I142@PURE_QUANTA.Q_CAP(CHIPS)':
 C_PATH='@t6g_mb_lib.t6g(sch_1):page82_i142@pure_quanta.q_cap(chips)';

PART_NAME
 C348 'Q_CAP_0805-47UF,4V,20%,X6S,CH647KMEA00':;

SECTION_NUMBER 1
 '@T6G_MB_LIB.T6G(SCH_1):PAGE82_I143@PURE_QUANTA.Q_CAP(CHIPS)':
 C_PATH='@t6g_mb_lib.t6g(sch_1):page82_i143@pure_quanta.q_cap(chips)';

PART_NAME
 C347 'Q_CAP_0805-47UF,4V,20%,X6S,CH647KMEA00':;

SECTION_NUMBER 1
 '@T6G_MB_LIB.T6G(SCH_1):PAGE82_I120@PURE_QUANTA.Q_CAP(CHIPS)':
 C_PATH='@t6g_mb_lib.t6g(sch_1):page82_i120@pure_quanta.q_cap(chips)';

PART_NAME
 C346 'Q_CAP_0805-47UF,4V,20%,X6S,CH647KMEA00':;

SECTION_NUMBER 1
 '@T6G_MB_LIB.T6G(SCH_1):PAGE82_I150@PURE_QUANTA.Q_CAP(CHIPS)':
 C_PATH='@t6g_mb_lib.t6g(sch_1):page82_i150@pure_quanta.q_cap(chips)';

PART_NAME
 C345 'Q_CAP_0805-47UF,4V,20%,X6S,CH647KMEA00':;

SECTION_NUMBER 1
 '@T6G_MB_LIB.T6G(SCH_1):PAGE82_I122@PURE_QUANTA.Q_CAP(CHIPS)':
 C_PATH='@t6g_mb_lib.t6g(sch_1):page82_i122@pure_quanta.q_cap(chips)';

PART_NAME
 C344 'Q_CAP_0805-47UF,4V,20%,X6S,CH647KMEA00':;

SECTION_NUMBER 1
 '@T6G_MB_LIB.T6G(SCH_1):PAGE82_I151@PURE_QUANTA.Q_CAP(CHIPS)':
 C_PATH='@t6g_mb_lib.t6g(sch_1):page82_i151@pure_quanta.q_cap(chips)';

PART_NAME
 C343 'Q_CAP_0805-47UF,4V,20%,X6S,CH647KMEA00':;

SECTION_NUMBER 1
 '@T6G_MB_LIB.T6G(SCH_1):PAGE82_I123@PURE_QUANTA.Q_CAP(CHIPS)':
 C_PATH='@t6g_mb_lib.t6g(sch_1):page82_i123@pure_quanta.q_cap(chips)';

PART_NAME
 C342 'Q_CAP_0805-47UF,4V,20%,X6S,CH647KMEA00':;

SECTION_NUMBER 1
 '@T6G_MB_LIB.T6G(SCH_1):PAGE82_I152@PURE_QUANTA.Q_CAP(CHIPS)':
 C_PATH='@t6g_mb_lib.t6g(sch_1):page82_i152@pure_quanta.q_cap(chips)';

PART_NAME
 C341 'Q_CAP_0805-47UF,4V,20%,X6S,CH647KMEA00':;

SECTION_NUMBER 1
 '@T6G_MB_LIB.T6G(SCH_1):PAGE82_I124@PURE_QUANTA.Q_CAP(CHIPS)':
 C_PATH='@t6g_mb_lib.t6g(sch_1):page82_i124@pure_quanta.q_cap(chips)';

PART_NAME
 C328 'Q_CAP_0805-47UF,4V,20%,X6S,CH647KMEA00':;

SECTION_NUMBER 1
 '@T6G_MB_LIB.T6G(SCH_1):PAGE82_I125@PURE_QUANTA.Q_CAP(CHIPS)':
 C_PATH='@t6g_mb_lib.t6g(sch_1):page82_i125@pure_quanta.q_cap(chips)';

PART_NAME
 C325 'Q_CAP_0805-47UF,4V,20%,X6S,CH647KMEA00':;

SECTION_NUMBER 1
 '@T6G_MB_LIB.T6G(SCH_1):PAGE82_I128@PURE_QUANTA.Q_CAP(CHIPS)':
 C_PATH='@t6g_mb_lib.t6g(sch_1):page82_i128@pure_quanta.q_cap(chips)';

PART_NAME
 C322 'Q_CAP_0805-47UF,4V,20%,X6S,CH647KMEA00':;

SECTION_NUMBER 1
 '@T6G_MB_LIB.T6G(SCH_1):PAGE82_I129@PURE_QUANTA.Q_CAP(CHIPS)':
 C_PATH='@t6g_mb_lib.t6g(sch_1):page82_i129@pure_quanta.q_cap(chips)';

PART_NAME
 C1393 'Q_CAP_C0603-47UF,2.5V,20%,X6S,CH647LME901':;

SECTION_NUMBER 1
 '@T6G_MB_LIB.T6G(SCH_1):PAGE81_I161@PURE_QUANTA.Q_CAP(CHIPS)':
 C_PATH='@t6g_mb_lib.t6g(sch_1):page81_i161@pure_quanta.q_cap(chips)';

PART_NAME
 C1392 'Q_CAP_0805-47UF,4V,20%,X6S,CH647KMEA00':;

SECTION_NUMBER 1
 '@T6G_MB_LIB.T6G(SCH_1):PAGE81_I163@PURE_QUANTA.Q_CAP(CHIPS)':
 C_PATH='@t6g_mb_lib.t6g(sch_1):page81_i163@pure_quanta.q_cap(chips)';

PART_NAME
 C1391 'Q_CAP_C0603-47UF,2.5V,20%,X6S,CH647LME901':;

SECTION_NUMBER 1
 '@T6G_MB_LIB.T6G(SCH_1):PAGE81_I164@PURE_QUANTA.Q_CAP(CHIPS)':
 C_PATH='@t6g_mb_lib.t6g(sch_1):page81_i164@pure_quanta.q_cap(chips)';

PART_NAME
 C1390 'Q_CAP_0805-47UF,4V,20%,X6S,CH647KMEA00':;

SECTION_NUMBER 1
 '@T6G_MB_LIB.T6G(SCH_1):PAGE81_I168@PURE_QUANTA.Q_CAP(CHIPS)':
 C_PATH='@t6g_mb_lib.t6g(sch_1):page81_i168@pure_quanta.q_cap(chips)';

PART_NAME
 C1389 'Q_CAP_C0603-47UF,2.5V,20%,X6S,CH647LME901':;

SECTION_NUMBER 1
 '@T6G_MB_LIB.T6G(SCH_1):PAGE81_I165@PURE_QUANTA.Q_CAP(CHIPS)':
 C_PATH='@t6g_mb_lib.t6g(sch_1):page81_i165@pure_quanta.q_cap(chips)';

PART_NAME
 C1388 'Q_CAP_0805-47UF,4V,20%,X6S,CH647KMEA00':;

SECTION_NUMBER 1
 '@T6G_MB_LIB.T6G(SCH_1):PAGE81_I170@PURE_QUANTA.Q_CAP(CHIPS)':
 C_PATH='@t6g_mb_lib.t6g(sch_1):page81_i170@pure_quanta.q_cap(chips)';

PART_NAME
 C1387 'Q_CAP_0805-47UF,4V,20%,X6S,CH647KMEA00':;

SECTION_NUMBER 1
 '@T6G_MB_LIB.T6G(SCH_1):PAGE81_I167@PURE_QUANTA.Q_CAP(CHIPS)':
 C_PATH='@t6g_mb_lib.t6g(sch_1):page81_i167@pure_quanta.q_cap(chips)';

PART_NAME
 C490 'Q_CAP_C0402-10UF,4V,20%,X6S,CH610KMEB09':;

SECTION_NUMBER 1
 '@T6G_MB_LIB.T6G(SCH_1):PAGE81_I193@PURE_QUANTA.Q_CAP(CHIPS)':
 C_PATH='@t6g_mb_lib.t6g(sch_1):page81_i193@pure_quanta.q_cap(chips)';

PART_NAME
 C489 'Q_CAP_C0603-47UF,2.5V,20%,X6S,CH647LME901':;

SECTION_NUMBER 1
 '@T6G_MB_LIB.T6G(SCH_1):PAGE81_I197@PURE_QUANTA.Q_CAP(CHIPS)':
 C_PATH='@t6g_mb_lib.t6g(sch_1):page81_i197@pure_quanta.q_cap(chips)';

PART_NAME
 C488 'Q_CAP_C0603-47UF,2.5V,20%,X6S,CH647LME901':;

SECTION_NUMBER 1
 '@T6G_MB_LIB.T6G(SCH_1):PAGE81_I198@PURE_QUANTA.Q_CAP(CHIPS)':
 C_PATH='@t6g_mb_lib.t6g(sch_1):page81_i198@pure_quanta.q_cap(chips)';

PART_NAME
 C483 'Q_CAP_C0603-47UF,2.5V,20%,X6S,CH647LME901':;

SECTION_NUMBER 1
 '@T6G_MB_LIB.T6G(SCH_1):PAGE81_I148@PURE_QUANTA.Q_CAP(CHIPS)':
 C_PATH='@t6g_mb_lib.t6g(sch_1):page81_i148@pure_quanta.q_cap(chips)';

PART_NAME
 C480 'Q_CAP_C0603-47UF,2.5V,20%,X6S,CH647LME901':;

SECTION_NUMBER 1
 '@T6G_MB_LIB.T6G(SCH_1):PAGE81_I149@PURE_QUANTA.Q_CAP(CHIPS)':
 C_PATH='@t6g_mb_lib.t6g(sch_1):page81_i149@pure_quanta.q_cap(chips)';

PART_NAME
 C478 'Q_CAP_0805-47UF,4V,20%,X6S,CH647KMEA00':;

SECTION_NUMBER 1
 '@T6G_MB_LIB.T6G(SCH_1):PAGE81_I208@PURE_QUANTA.Q_CAP(CHIPS)':
 C_PATH='@t6g_mb_lib.t6g(sch_1):page81_i208@pure_quanta.q_cap(chips)';

PART_NAME
 C474 'Q_CAP_C0603-47UF,2.5V,20%,X6S,CH647LME901':;

SECTION_NUMBER 1
 '@T6G_MB_LIB.T6G(SCH_1):PAGE81_I187@PURE_QUANTA.Q_CAP(CHIPS)':
 C_PATH='@t6g_mb_lib.t6g(sch_1):page81_i187@pure_quanta.q_cap(chips)';

PART_NAME
 C471 'Q_CAP_C0603-47UF,2.5V,20%,X6S,CH647LME901':;

SECTION_NUMBER 1
 '@T6G_MB_LIB.T6G(SCH_1):PAGE81_I191@PURE_QUANTA.Q_CAP(CHIPS)':
 C_PATH='@t6g_mb_lib.t6g(sch_1):page81_i191@pure_quanta.q_cap(chips)';

PART_NAME
 C465 'Q_CAP_C0603-47UF,2.5V,20%,X6S,CH647LME901':;

SECTION_NUMBER 1
 '@T6G_MB_LIB.T6G(SCH_1):PAGE81_I209@PURE_QUANTA.Q_CAP(CHIPS)':
 C_PATH='@t6g_mb_lib.t6g(sch_1):page81_i209@pure_quanta.q_cap(chips)';

PART_NAME
 C461 'Q_CAP_0805-47UF,4V,20%,X6S,CH647KMEA00':;

SECTION_NUMBER 1
 '@T6G_MB_LIB.T6G(SCH_1):PAGE81_I211@PURE_QUANTA.Q_CAP(CHIPS)':
 C_PATH='@t6g_mb_lib.t6g(sch_1):page81_i211@pure_quanta.q_cap(chips)';

PART_NAME
 C457 'Q_CAP_0805-47UF,4V,20%,X6S,CH647KMEA00':;

SECTION_NUMBER 1
 '@T6G_MB_LIB.T6G(SCH_1):PAGE81_I212@PURE_QUANTA.Q_CAP(CHIPS)':
 C_PATH='@t6g_mb_lib.t6g(sch_1):page81_i212@pure_quanta.q_cap(chips)';

PART_NAME
 C453 'Q_CAP_0805-47UF,4V,20%,X6S,CH647KMEA00':;

SECTION_NUMBER 1
 '@T6G_MB_LIB.T6G(SCH_1):PAGE81_I213@PURE_QUANTA.Q_CAP(CHIPS)':
 C_PATH='@t6g_mb_lib.t6g(sch_1):page81_i213@pure_quanta.q_cap(chips)';

PART_NAME
 C452 'Q_CAP_0805-47UF,4V,20%,X6S,CH647KMEA00':;

SECTION_NUMBER 1
 '@T6G_MB_LIB.T6G(SCH_1):PAGE81_I195@PURE_QUANTA.Q_CAP(CHIPS)':
 C_PATH='@t6g_mb_lib.t6g(sch_1):page81_i195@pure_quanta.q_cap(chips)';

PART_NAME
 C451 'Q_CAP_0805-47UF,4V,20%,X6S,CH647KMEA00':;

SECTION_NUMBER 1
 '@T6G_MB_LIB.T6G(SCH_1):PAGE81_I192@PURE_QUANTA.Q_CAP(CHIPS)':
 C_PATH='@t6g_mb_lib.t6g(sch_1):page81_i192@pure_quanta.q_cap(chips)';

PART_NAME
 C449 'Q_CAP_0805-47UF,4V,20%,X6S,CH647KMEA00':;

SECTION_NUMBER 1
 '@T6G_MB_LIB.T6G(SCH_1):PAGE81_I215@PURE_QUANTA.Q_CAP(CHIPS)':
 C_PATH='@t6g_mb_lib.t6g(sch_1):page81_i215@pure_quanta.q_cap(chips)';

PART_NAME
 C448 'Q_CAP_0805-47UF,4V,20%,X6S,CH647KMEA00':;

SECTION_NUMBER 1
 '@T6G_MB_LIB.T6G(SCH_1):PAGE81_I206@PURE_QUANTA.Q_CAP(CHIPS)':
 C_PATH='@t6g_mb_lib.t6g(sch_1):page81_i206@pure_quanta.q_cap(chips)';

PART_NAME
 C447 'Q_CAP_0805-47UF,4V,20%,X6S,CH647KMEA00':;

SECTION_NUMBER 1
 '@T6G_MB_LIB.T6G(SCH_1):PAGE81_I204@PURE_QUANTA.Q_CAP(CHIPS)':
 C_PATH='@t6g_mb_lib.t6g(sch_1):page81_i204@pure_quanta.q_cap(chips)';

PART_NAME
 C353 'Q_CAP_0805-47UF,4V,20%,X6S,CH647KMEA00':;

SECTION_NUMBER 1
 '@T6G_MB_LIB.T6G(SCH_1):PAGE81_I153@PURE_QUANTA.Q_CAP(CHIPS)':
 C_PATH='@t6g_mb_lib.t6g(sch_1):page81_i153@pure_quanta.q_cap(chips)';

PART_NAME
 C351 'Q_CAP_0805-47UF,4V,20%,X6S,CH647KMEA00':;

SECTION_NUMBER 1
 '@T6G_MB_LIB.T6G(SCH_1):PAGE81_I154@PURE_QUANTA.Q_CAP(CHIPS)':
 C_PATH='@t6g_mb_lib.t6g(sch_1):page81_i154@pure_quanta.q_cap(chips)';

PART_NAME
 C349 'Q_CAP_0805-47UF,4V,20%,X6S,CH647KMEA00':;

SECTION_NUMBER 1
 '@T6G_MB_LIB.T6G(SCH_1):PAGE81_I155@PURE_QUANTA.Q_CAP(CHIPS)':
 C_PATH='@t6g_mb_lib.t6g(sch_1):page81_i155@pure_quanta.q_cap(chips)';

PART_NAME
 C340 'Q_CAP_C0603-47UF,2.5V,20%,X6S,CH647LME901':;

SECTION_NUMBER 1
 '@T6G_MB_LIB.T6G(SCH_1):PAGE81_I150@PURE_QUANTA.Q_CAP(CHIPS)':
 C_PATH='@t6g_mb_lib.t6g(sch_1):page81_i150@pure_quanta.q_cap(chips)';

PART_NAME
 C339 'Q_CAP_0805-47UF,4V,20%,X6S,CH647KMEA00':;

SECTION_NUMBER 1
 '@T6G_MB_LIB.T6G(SCH_1):PAGE81_I180@PURE_QUANTA.Q_CAP(CHIPS)':
 C_PATH='@t6g_mb_lib.t6g(sch_1):page81_i180@pure_quanta.q_cap(chips)';

PART_NAME
 C338 'Q_CAP_0805-47UF,4V,20%,X6S,CH647KMEA00':;

SECTION_NUMBER 1
 '@T6G_MB_LIB.T6G(SCH_1):PAGE81_I171@PURE_QUANTA.Q_CAP(CHIPS)':
 C_PATH='@t6g_mb_lib.t6g(sch_1):page81_i171@pure_quanta.q_cap(chips)';

PART_NAME
 C337 'Q_CAP_C0603-47UF,2.5V,20%,X6S,CH647LME901':;

SECTION_NUMBER 1
 '@T6G_MB_LIB.T6G(SCH_1):PAGE81_I152@PURE_QUANTA.Q_CAP(CHIPS)':
 C_PATH='@t6g_mb_lib.t6g(sch_1):page81_i152@pure_quanta.q_cap(chips)';

PART_NAME
 C336 'Q_CAP_0805-47UF,4V,20%,X6S,CH647KMEA00':;

SECTION_NUMBER 1
 '@T6G_MB_LIB.T6G(SCH_1):PAGE81_I181@PURE_QUANTA.Q_CAP(CHIPS)':
 C_PATH='@t6g_mb_lib.t6g(sch_1):page81_i181@pure_quanta.q_cap(chips)';

PART_NAME
 C335 'Q_CAP_0805-47UF,4V,20%,X6S,CH647KMEA00':;

SECTION_NUMBER 1
 '@T6G_MB_LIB.T6G(SCH_1):PAGE81_I172@PURE_QUANTA.Q_CAP(CHIPS)':
 C_PATH='@t6g_mb_lib.t6g(sch_1):page81_i172@pure_quanta.q_cap(chips)';

PART_NAME
 C333 'Q_CAP_0805-47UF,4V,20%,X6S,CH647KMEA00':;

SECTION_NUMBER 1
 '@T6G_MB_LIB.T6G(SCH_1):PAGE81_I182@PURE_QUANTA.Q_CAP(CHIPS)':
 C_PATH='@t6g_mb_lib.t6g(sch_1):page81_i182@pure_quanta.q_cap(chips)';

PART_NAME
 C332 'Q_CAP_0805-47UF,4V,20%,X6S,CH647KMEA00':;

SECTION_NUMBER 1
 '@T6G_MB_LIB.T6G(SCH_1):PAGE81_I173@PURE_QUANTA.Q_CAP(CHIPS)':
 C_PATH='@t6g_mb_lib.t6g(sch_1):page81_i173@pure_quanta.q_cap(chips)';

PART_NAME
 C330 'Q_CAP_0805-47UF,4V,20%,X6S,CH647KMEA00':;

SECTION_NUMBER 1
 '@T6G_MB_LIB.T6G(SCH_1):PAGE81_I183@PURE_QUANTA.Q_CAP(CHIPS)':
 C_PATH='@t6g_mb_lib.t6g(sch_1):page81_i183@pure_quanta.q_cap(chips)';

PART_NAME
 C329 'Q_CAP_0805-47UF,4V,20%,X6S,CH647KMEA00':;

SECTION_NUMBER 1
 '@T6G_MB_LIB.T6G(SCH_1):PAGE81_I174@PURE_QUANTA.Q_CAP(CHIPS)':
 C_PATH='@t6g_mb_lib.t6g(sch_1):page81_i174@pure_quanta.q_cap(chips)';

PART_NAME
 C327 'Q_CAP_0805-47UF,4V,20%,X6S,CH647KMEA00':;

SECTION_NUMBER 1
 '@T6G_MB_LIB.T6G(SCH_1):PAGE81_I184@PURE_QUANTA.Q_CAP(CHIPS)':
 C_PATH='@t6g_mb_lib.t6g(sch_1):page81_i184@pure_quanta.q_cap(chips)';

PART_NAME
 C326 'Q_CAP_0805-47UF,4V,20%,X6S,CH647KMEA00':;

SECTION_NUMBER 1
 '@T6G_MB_LIB.T6G(SCH_1):PAGE81_I175@PURE_QUANTA.Q_CAP(CHIPS)':
 C_PATH='@t6g_mb_lib.t6g(sch_1):page81_i175@pure_quanta.q_cap(chips)';

PART_NAME
 C324 'Q_CAP_0805-47UF,4V,20%,X6S,CH647KMEA00':;

SECTION_NUMBER 1
 '@T6G_MB_LIB.T6G(SCH_1):PAGE81_I185@PURE_QUANTA.Q_CAP(CHIPS)':
 C_PATH='@t6g_mb_lib.t6g(sch_1):page81_i185@pure_quanta.q_cap(chips)';

PART_NAME
 C323 'Q_CAP_0805-47UF,4V,20%,X6S,CH647KMEA00':;

SECTION_NUMBER 1
 '@T6G_MB_LIB.T6G(SCH_1):PAGE81_I176@PURE_QUANTA.Q_CAP(CHIPS)':
 C_PATH='@t6g_mb_lib.t6g(sch_1):page81_i176@pure_quanta.q_cap(chips)';

PART_NAME
 C321 'Q_CAP_0805-47UF,4V,20%,X6S,CH647KMEA00':;

SECTION_NUMBER 1
 '@T6G_MB_LIB.T6G(SCH_1):PAGE81_I186@PURE_QUANTA.Q_CAP(CHIPS)':
 C_PATH='@t6g_mb_lib.t6g(sch_1):page81_i186@pure_quanta.q_cap(chips)';

PART_NAME
 C320 'Q_CAP_0805-47UF,4V,20%,X6S,CH647KMEA00':;

SECTION_NUMBER 1
 '@T6G_MB_LIB.T6G(SCH_1):PAGE81_I177@PURE_QUANTA.Q_CAP(CHIPS)':
 C_PATH='@t6g_mb_lib.t6g(sch_1):page81_i177@pure_quanta.q_cap(chips)';

PART_NAME
 C318 'Q_CAP_0805-47UF,4V,20%,X6S,CH647KMEA00':;

SECTION_NUMBER 1
 '@T6G_MB_LIB.T6G(SCH_1):PAGE81_I189@PURE_QUANTA.Q_CAP(CHIPS)':
 C_PATH='@t6g_mb_lib.t6g(sch_1):page81_i189@pure_quanta.q_cap(chips)';

PART_NAME
 C317 'Q_CAP_0805-47UF,4V,20%,X6S,CH647KMEA00':;

SECTION_NUMBER 1
 '@T6G_MB_LIB.T6G(SCH_1):PAGE81_I178@PURE_QUANTA.Q_CAP(CHIPS)':
 C_PATH='@t6g_mb_lib.t6g(sch_1):page81_i178@pure_quanta.q_cap(chips)';

PART_NAME
 C316 'Q_CAP_0805-47UF,4V,20%,X6S,CH647KMEA00':;

SECTION_NUMBER 1
 '@T6G_MB_LIB.T6G(SCH_1):PAGE81_I158@PURE_QUANTA.Q_CAP(CHIPS)':
 C_PATH='@t6g_mb_lib.t6g(sch_1):page81_i158@pure_quanta.q_cap(chips)';

PART_NAME
 C315 'Q_CAP_0805-47UF,4V,20%,X6S,CH647KMEA00':;

SECTION_NUMBER 1
 '@T6G_MB_LIB.T6G(SCH_1):PAGE81_I190@PURE_QUANTA.Q_CAP(CHIPS)':
 C_PATH='@t6g_mb_lib.t6g(sch_1):page81_i190@pure_quanta.q_cap(chips)';

PART_NAME
 C314 'Q_CAP_0805-47UF,4V,20%,X6S,CH647KMEA00':;

SECTION_NUMBER 1
 '@T6G_MB_LIB.T6G(SCH_1):PAGE81_I179@PURE_QUANTA.Q_CAP(CHIPS)':
 C_PATH='@t6g_mb_lib.t6g(sch_1):page81_i179@pure_quanta.q_cap(chips)';

PART_NAME
 C313 'Q_CAP_0805-47UF,4V,20%,X6S,CH647KMEA00':;

SECTION_NUMBER 1
 '@T6G_MB_LIB.T6G(SCH_1):PAGE81_I160@PURE_QUANTA.Q_CAP(CHIPS)':
 C_PATH='@t6g_mb_lib.t6g(sch_1):page81_i160@pure_quanta.q_cap(chips)';

PART_NAME
 C312 'Q_CAP_0805-47UF,4V,20%,X6S,CH647KMEA00':;

SECTION_NUMBER 1
 '@T6G_MB_LIB.T6G(SCH_1):PAGE81_I202@PURE_QUANTA.Q_CAP(CHIPS)':
 C_PATH='@t6g_mb_lib.t6g(sch_1):page81_i202@pure_quanta.q_cap(chips)';

PART_NAME
 C311 'Q_CAP_0805-47UF,4V,20%,X6S,CH647KMEA00':;

SECTION_NUMBER 1
 '@T6G_MB_LIB.T6G(SCH_1):PAGE81_I200@PURE_QUANTA.Q_CAP(CHIPS)':
 C_PATH='@t6g_mb_lib.t6g(sch_1):page81_i200@pure_quanta.q_cap(chips)';

PART_NAME
 C446 'Q_CAP_C0402-10UF,4V,20%,X6S,CH610KMEB09':;

SECTION_NUMBER 1
 '@T6G_MB_LIB.T6G(SCH_1):PAGE80_I301@PURE_QUANTA.Q_CAP(CHIPS)':
 C_PATH='@t6g_mb_lib.t6g(sch_1):page80_i301@pure_quanta.q_cap(chips)';

PART_NAME
 C445 'Q_CAP_C0402-10UF,4V,20%,X6S,CH610KMEB09':;

SECTION_NUMBER 1
 '@T6G_MB_LIB.T6G(SCH_1):PAGE80_I304@PURE_QUANTA.Q_CAP(CHIPS)':
 C_PATH='@t6g_mb_lib.t6g(sch_1):page80_i304@pure_quanta.q_cap(chips)';

PART_NAME
 C444 'Q_CAP_C0402-10UF,4V,20%,X6S,CH610KMEB09':;

SECTION_NUMBER 1
 '@T6G_MB_LIB.T6G(SCH_1):PAGE80_I305@PURE_QUANTA.Q_CAP(CHIPS)':
 C_PATH='@t6g_mb_lib.t6g(sch_1):page80_i305@pure_quanta.q_cap(chips)';

PART_NAME
 C443 'Q_CAP_C0402-10UF,4V,20%,X6S,CH610KMEB09':;

SECTION_NUMBER 1
 '@T6G_MB_LIB.T6G(SCH_1):PAGE80_I347@PURE_QUANTA.Q_CAP(CHIPS)':
 C_PATH='@t6g_mb_lib.t6g(sch_1):page80_i347@pure_quanta.q_cap(chips)';

PART_NAME
 C442 'Q_CAP_C0402-10UF,4V,20%,X6S,CH610KMEB09':;

SECTION_NUMBER 1
 '@T6G_MB_LIB.T6G(SCH_1):PAGE80_I271@PURE_QUANTA.Q_CAP(CHIPS)':
 C_PATH='@t6g_mb_lib.t6g(sch_1):page80_i271@pure_quanta.q_cap(chips)';

PART_NAME
 C441 'Q_CAP_C0402-10UF,4V,20%,X6S,CH610KMEB09':;

SECTION_NUMBER 1
 '@T6G_MB_LIB.T6G(SCH_1):PAGE80_I358@PURE_QUANTA.Q_CAP(CHIPS)':
 C_PATH='@t6g_mb_lib.t6g(sch_1):page80_i358@pure_quanta.q_cap(chips)';

PART_NAME
 C440 'Q_CAP_C0402-10UF,4V,20%,X6S,CH610KMEB09':;

SECTION_NUMBER 1
 '@T6G_MB_LIB.T6G(SCH_1):PAGE80_I353@PURE_QUANTA.Q_CAP(CHIPS)':
 C_PATH='@t6g_mb_lib.t6g(sch_1):page80_i353@pure_quanta.q_cap(chips)';

PART_NAME
 C439 'Q_CAP_C0402-10UF,4V,20%,X6S,CH610KMEB09':;

SECTION_NUMBER 1
 '@T6G_MB_LIB.T6G(SCH_1):PAGE80_I360@PURE_QUANTA.Q_CAP(CHIPS)':
 C_PATH='@t6g_mb_lib.t6g(sch_1):page80_i360@pure_quanta.q_cap(chips)';

PART_NAME
 C438 'Q_CAP_C0402-10UF,4V,20%,X6S,CH610KMEB09':;

SECTION_NUMBER 1
 '@T6G_MB_LIB.T6G(SCH_1):PAGE80_I356@PURE_QUANTA.Q_CAP(CHIPS)':
 C_PATH='@t6g_mb_lib.t6g(sch_1):page80_i356@pure_quanta.q_cap(chips)';

PART_NAME
 C437 'Q_CAP_C0402-10UF,4V,20%,X6S,CH610KMEB09':;

SECTION_NUMBER 1
 '@T6G_MB_LIB.T6G(SCH_1):PAGE80_I373@PURE_QUANTA.Q_CAP(CHIPS)':
 C_PATH='@t6g_mb_lib.t6g(sch_1):page80_i373@pure_quanta.q_cap(chips)';

PART_NAME
 C436 'Q_CAP_C0402-10UF,4V,20%,X6S,CH610KMEB09':;

SECTION_NUMBER 1
 '@T6G_MB_LIB.T6G(SCH_1):PAGE80_I364@PURE_QUANTA.Q_CAP(CHIPS)':
 C_PATH='@t6g_mb_lib.t6g(sch_1):page80_i364@pure_quanta.q_cap(chips)';

PART_NAME
 C435 'Q_CAP_C0402-10UF,4V,20%,X6S,CH610KMEB09':;

SECTION_NUMBER 1
 '@T6G_MB_LIB.T6G(SCH_1):PAGE80_I374@PURE_QUANTA.Q_CAP(CHIPS)':
 C_PATH='@t6g_mb_lib.t6g(sch_1):page80_i374@pure_quanta.q_cap(chips)';

PART_NAME
 C434 'Q_CAP_C0402-10UF,4V,20%,X6S,CH610KMEB09':;

SECTION_NUMBER 1
 '@T6G_MB_LIB.T6G(SCH_1):PAGE80_I366@PURE_QUANTA.Q_CAP(CHIPS)':
 C_PATH='@t6g_mb_lib.t6g(sch_1):page80_i366@pure_quanta.q_cap(chips)';

PART_NAME
 C433 'Q_CAP_C0402-10UF,4V,20%,X6S,CH610KMEB09':;

SECTION_NUMBER 1
 '@T6G_MB_LIB.T6G(SCH_1):PAGE80_I375@PURE_QUANTA.Q_CAP(CHIPS)':
 C_PATH='@t6g_mb_lib.t6g(sch_1):page80_i375@pure_quanta.q_cap(chips)';

PART_NAME
 C432 'Q_CAP_C0402-10UF,4V,20%,X6S,CH610KMEB09':;

SECTION_NUMBER 1
 '@T6G_MB_LIB.T6G(SCH_1):PAGE80_I371@PURE_QUANTA.Q_CAP(CHIPS)':
 C_PATH='@t6g_mb_lib.t6g(sch_1):page80_i371@pure_quanta.q_cap(chips)';

PART_NAME
 C431 'Q_CAP_C0402-10UF,4V,20%,X6S,CH610KMEB09':;

SECTION_NUMBER 1
 '@T6G_MB_LIB.T6G(SCH_1):PAGE80_I376@PURE_QUANTA.Q_CAP(CHIPS)':
 C_PATH='@t6g_mb_lib.t6g(sch_1):page80_i376@pure_quanta.q_cap(chips)';

PART_NAME
 C430 'Q_CAP_C0402-10UF,4V,20%,X6S,CH610KMEB09':;

SECTION_NUMBER 1
 '@T6G_MB_LIB.T6G(SCH_1):PAGE80_I408@PURE_QUANTA.Q_CAP(CHIPS)':
 C_PATH='@t6g_mb_lib.t6g(sch_1):page80_i408@pure_quanta.q_cap(chips)';

PART_NAME
 C429 'Q_CAP_C0402-10UF,4V,20%,X6S,CH610KMEB09':;

SECTION_NUMBER 1
 '@T6G_MB_LIB.T6G(SCH_1):PAGE80_I396@PURE_QUANTA.Q_CAP(CHIPS)':
 C_PATH='@t6g_mb_lib.t6g(sch_1):page80_i396@pure_quanta.q_cap(chips)';

PART_NAME
 C428 'Q_CAP_C0402-10UF,4V,20%,X6S,CH610KMEB09':;

SECTION_NUMBER 1
 '@T6G_MB_LIB.T6G(SCH_1):PAGE80_I409@PURE_QUANTA.Q_CAP(CHIPS)':
 C_PATH='@t6g_mb_lib.t6g(sch_1):page80_i409@pure_quanta.q_cap(chips)';

PART_NAME
 C427 'Q_CAP_C0402-10UF,4V,20%,X6S,CH610KMEB09':;

SECTION_NUMBER 1
 '@T6G_MB_LIB.T6G(SCH_1):PAGE80_I398@PURE_QUANTA.Q_CAP(CHIPS)':
 C_PATH='@t6g_mb_lib.t6g(sch_1):page80_i398@pure_quanta.q_cap(chips)';

PART_NAME
 C426 'Q_CAP_C0402-10UF,4V,20%,X6S,CH610KMEB09':;

SECTION_NUMBER 1
 '@T6G_MB_LIB.T6G(SCH_1):PAGE80_I411@PURE_QUANTA.Q_CAP(CHIPS)':
 C_PATH='@t6g_mb_lib.t6g(sch_1):page80_i411@pure_quanta.q_cap(chips)';

PART_NAME
 C425 'Q_CAP_C0402-10UF,4V,20%,X6S,CH610KMEB09':;

SECTION_NUMBER 1
 '@T6G_MB_LIB.T6G(SCH_1):PAGE80_I405@PURE_QUANTA.Q_CAP(CHIPS)':
 C_PATH='@t6g_mb_lib.t6g(sch_1):page80_i405@pure_quanta.q_cap(chips)';

PART_NAME
 C424 'Q_CAP_C0402-10UF,4V,20%,X6S,CH610KMEB09':;

SECTION_NUMBER 1
 '@T6G_MB_LIB.T6G(SCH_1):PAGE80_I412@PURE_QUANTA.Q_CAP(CHIPS)':
 C_PATH='@t6g_mb_lib.t6g(sch_1):page80_i412@pure_quanta.q_cap(chips)';

PART_NAME
 C423 'Q_CAP_C0402-10UF,4V,20%,X6S,CH610KMEB09':;

SECTION_NUMBER 1
 '@T6G_MB_LIB.T6G(SCH_1):PAGE80_I406@PURE_QUANTA.Q_CAP(CHIPS)':
 C_PATH='@t6g_mb_lib.t6g(sch_1):page80_i406@pure_quanta.q_cap(chips)';

PART_NAME
 C310 'Q_CAP_C0402-10UF,4V,20%,X6S,CH610KMEB09':;

SECTION_NUMBER 1
 '@T6G_MB_LIB.T6G(SCH_1):PAGE80_I344@PURE_QUANTA.Q_CAP(CHIPS)':
 C_PATH='@t6g_mb_lib.t6g(sch_1):page80_i344@pure_quanta.q_cap(chips)';

PART_NAME
 C309 'Q_CAP_C0402-10UF,4V,20%,X6S,CH610KMEB09':;

SECTION_NUMBER 1
 '@T6G_MB_LIB.T6G(SCH_1):PAGE80_I278@PURE_QUANTA.Q_CAP(CHIPS)':
 C_PATH='@t6g_mb_lib.t6g(sch_1):page80_i278@pure_quanta.q_cap(chips)';

PART_NAME
 C308 'Q_CAP_C0402-10UF,4V,20%,X6S,CH610KMEB09':;

SECTION_NUMBER 1
 '@T6G_MB_LIB.T6G(SCH_1):PAGE80_I274@PURE_QUANTA.Q_CAP(CHIPS)':
 C_PATH='@t6g_mb_lib.t6g(sch_1):page80_i274@pure_quanta.q_cap(chips)';

PART_NAME
 C307 'Q_CAP_C0402-10UF,4V,20%,X6S,CH610KMEB09':;

SECTION_NUMBER 1
 '@T6G_MB_LIB.T6G(SCH_1):PAGE80_I272@PURE_QUANTA.Q_CAP(CHIPS)':
 C_PATH='@t6g_mb_lib.t6g(sch_1):page80_i272@pure_quanta.q_cap(chips)';

PART_NAME
 C306 'Q_CAP_C0402-10UF,4V,20%,X6S,CH610KMEB09':;

SECTION_NUMBER 1
 '@T6G_MB_LIB.T6G(SCH_1):PAGE80_I296@PURE_QUANTA.Q_CAP(CHIPS)':
 C_PATH='@t6g_mb_lib.t6g(sch_1):page80_i296@pure_quanta.q_cap(chips)';

PART_NAME
 C305 'Q_CAP_C0402-10UF,4V,20%,X6S,CH610KMEB09':;

SECTION_NUMBER 1
 '@T6G_MB_LIB.T6G(SCH_1):PAGE80_I280@PURE_QUANTA.Q_CAP(CHIPS)':
 C_PATH='@t6g_mb_lib.t6g(sch_1):page80_i280@pure_quanta.q_cap(chips)';

PART_NAME
 C304 'Q_CAP_C0402-10UF,4V,20%,X6S,CH610KMEB09':;

SECTION_NUMBER 1
 '@T6G_MB_LIB.T6G(SCH_1):PAGE80_I276@PURE_QUANTA.Q_CAP(CHIPS)':
 C_PATH='@t6g_mb_lib.t6g(sch_1):page80_i276@pure_quanta.q_cap(chips)';

PART_NAME
 C303 'Q_CAP_C0402-10UF,4V,20%,X6S,CH610KMEB09':;

SECTION_NUMBER 1
 '@T6G_MB_LIB.T6G(SCH_1):PAGE80_I275@PURE_QUANTA.Q_CAP(CHIPS)':
 C_PATH='@t6g_mb_lib.t6g(sch_1):page80_i275@pure_quanta.q_cap(chips)';

PART_NAME
 C302 'Q_CAP_C0402-10UF,4V,20%,X6S,CH610KMEB09':;

SECTION_NUMBER 1
 '@T6G_MB_LIB.T6G(SCH_1):PAGE80_I297@PURE_QUANTA.Q_CAP(CHIPS)':
 C_PATH='@t6g_mb_lib.t6g(sch_1):page80_i297@pure_quanta.q_cap(chips)';

PART_NAME
 C301 'Q_CAP_C0402-10UF,4V,20%,X6S,CH610KMEB09':;

SECTION_NUMBER 1
 '@T6G_MB_LIB.T6G(SCH_1):PAGE80_I281@PURE_QUANTA.Q_CAP(CHIPS)':
 C_PATH='@t6g_mb_lib.t6g(sch_1):page80_i281@pure_quanta.q_cap(chips)';

PART_NAME
 C300 'Q_CAP_C0402-10UF,4V,20%,X6S,CH610KMEB09':;

SECTION_NUMBER 1
 '@T6G_MB_LIB.T6G(SCH_1):PAGE80_I282@PURE_QUANTA.Q_CAP(CHIPS)':
 C_PATH='@t6g_mb_lib.t6g(sch_1):page80_i282@pure_quanta.q_cap(chips)';

PART_NAME
 C299 'Q_CAP_C0402-10UF,4V,20%,X6S,CH610KMEB09':;

SECTION_NUMBER 1
 '@T6G_MB_LIB.T6G(SCH_1):PAGE80_I283@PURE_QUANTA.Q_CAP(CHIPS)':
 C_PATH='@t6g_mb_lib.t6g(sch_1):page80_i283@pure_quanta.q_cap(chips)';

PART_NAME
 C298 'Q_CAP_C0402-10UF,4V,20%,X6S,CH610KMEB09':;

SECTION_NUMBER 1
 '@T6G_MB_LIB.T6G(SCH_1):PAGE80_I299@PURE_QUANTA.Q_CAP(CHIPS)':
 C_PATH='@t6g_mb_lib.t6g(sch_1):page80_i299@pure_quanta.q_cap(chips)';

PART_NAME
 C297 'Q_CAP_C0402-10UF,4V,20%,X6S,CH610KMEB09':;

SECTION_NUMBER 1
 '@T6G_MB_LIB.T6G(SCH_1):PAGE80_I288@PURE_QUANTA.Q_CAP(CHIPS)':
 C_PATH='@t6g_mb_lib.t6g(sch_1):page80_i288@pure_quanta.q_cap(chips)';

PART_NAME
 C296 'Q_CAP_C0402-10UF,4V,20%,X6S,CH610KMEB09':;

SECTION_NUMBER 1
 '@T6G_MB_LIB.T6G(SCH_1):PAGE80_I285@PURE_QUANTA.Q_CAP(CHIPS)':
 C_PATH='@t6g_mb_lib.t6g(sch_1):page80_i285@pure_quanta.q_cap(chips)';

PART_NAME
 C295 'Q_CAP_C0402-10UF,4V,20%,X6S,CH610KMEB09':;

SECTION_NUMBER 1
 '@T6G_MB_LIB.T6G(SCH_1):PAGE80_I284@PURE_QUANTA.Q_CAP(CHIPS)':
 C_PATH='@t6g_mb_lib.t6g(sch_1):page80_i284@pure_quanta.q_cap(chips)';

PART_NAME
 C294 'Q_CAP_C0402-10UF,4V,20%,X6S,CH610KMEB09':;

SECTION_NUMBER 1
 '@T6G_MB_LIB.T6G(SCH_1):PAGE80_I300@PURE_QUANTA.Q_CAP(CHIPS)':
 C_PATH='@t6g_mb_lib.t6g(sch_1):page80_i300@pure_quanta.q_cap(chips)';

PART_NAME
 C293 'Q_CAP_C0402-10UF,4V,20%,X6S,CH610KMEB09':;

SECTION_NUMBER 1
 '@T6G_MB_LIB.T6G(SCH_1):PAGE80_I289@PURE_QUANTA.Q_CAP(CHIPS)':
 C_PATH='@t6g_mb_lib.t6g(sch_1):page80_i289@pure_quanta.q_cap(chips)';

PART_NAME
 C292 'Q_CAP_C0402-10UF,4V,20%,X6S,CH610KMEB09':;

SECTION_NUMBER 1
 '@T6G_MB_LIB.T6G(SCH_1):PAGE80_I287@PURE_QUANTA.Q_CAP(CHIPS)':
 C_PATH='@t6g_mb_lib.t6g(sch_1):page80_i287@pure_quanta.q_cap(chips)';

PART_NAME
 C291 'Q_CAP_C0402-10UF,4V,20%,X6S,CH610KMEB09':;

SECTION_NUMBER 1
 '@T6G_MB_LIB.T6G(SCH_1):PAGE80_I286@PURE_QUANTA.Q_CAP(CHIPS)':
 C_PATH='@t6g_mb_lib.t6g(sch_1):page80_i286@pure_quanta.q_cap(chips)';

PART_NAME
 C290 'Q_CAP_C0402-10UF,4V,20%,X6S,CH610KMEB09':;

SECTION_NUMBER 1
 '@T6G_MB_LIB.T6G(SCH_1):PAGE80_I302@PURE_QUANTA.Q_CAP(CHIPS)':
 C_PATH='@t6g_mb_lib.t6g(sch_1):page80_i302@pure_quanta.q_cap(chips)';

PART_NAME
 C289 'Q_CAP_C0402-10UF,4V,20%,X6S,CH610KMEB09':;

SECTION_NUMBER 1
 '@T6G_MB_LIB.T6G(SCH_1):PAGE80_I294@PURE_QUANTA.Q_CAP(CHIPS)':
 C_PATH='@t6g_mb_lib.t6g(sch_1):page80_i294@pure_quanta.q_cap(chips)';

PART_NAME
 C288 'Q_CAP_C0402-10UF,4V,20%,X6S,CH610KMEB09':;

SECTION_NUMBER 1
 '@T6G_MB_LIB.T6G(SCH_1):PAGE80_I291@PURE_QUANTA.Q_CAP(CHIPS)':
 C_PATH='@t6g_mb_lib.t6g(sch_1):page80_i291@pure_quanta.q_cap(chips)';

PART_NAME
 C287 'Q_CAP_C0402-10UF,4V,20%,X6S,CH610KMEB09':;

SECTION_NUMBER 1
 '@T6G_MB_LIB.T6G(SCH_1):PAGE80_I290@PURE_QUANTA.Q_CAP(CHIPS)':
 C_PATH='@t6g_mb_lib.t6g(sch_1):page80_i290@pure_quanta.q_cap(chips)';

PART_NAME
 C286 'Q_CAP_C0402-10UF,4V,20%,X6S,CH610KMEB09':;

SECTION_NUMBER 1
 '@T6G_MB_LIB.T6G(SCH_1):PAGE80_I303@PURE_QUANTA.Q_CAP(CHIPS)':
 C_PATH='@t6g_mb_lib.t6g(sch_1):page80_i303@pure_quanta.q_cap(chips)';

PART_NAME
 C285 'Q_CAP_C0402-10UF,4V,20%,X6S,CH610KMEB09':;

SECTION_NUMBER 1
 '@T6G_MB_LIB.T6G(SCH_1):PAGE80_I295@PURE_QUANTA.Q_CAP(CHIPS)':
 C_PATH='@t6g_mb_lib.t6g(sch_1):page80_i295@pure_quanta.q_cap(chips)';

PART_NAME
 C284 'Q_CAP_C0402-10UF,4V,20%,X6S,CH610KMEB09':;

SECTION_NUMBER 1
 '@T6G_MB_LIB.T6G(SCH_1):PAGE80_I293@PURE_QUANTA.Q_CAP(CHIPS)':
 C_PATH='@t6g_mb_lib.t6g(sch_1):page80_i293@pure_quanta.q_cap(chips)';

PART_NAME
 C283 'Q_CAP_C0402-10UF,4V,20%,X6S,CH610KMEB09':;

SECTION_NUMBER 1
 '@T6G_MB_LIB.T6G(SCH_1):PAGE80_I292@PURE_QUANTA.Q_CAP(CHIPS)':
 C_PATH='@t6g_mb_lib.t6g(sch_1):page80_i292@pure_quanta.q_cap(chips)';

PART_NAME
 C282 'Q_CAP_C0402-10UF,4V,20%,X6S,CH610KMEB09':;

SECTION_NUMBER 1
 '@T6G_MB_LIB.T6G(SCH_1):PAGE80_I341@PURE_QUANTA.Q_CAP(CHIPS)':
 C_PATH='@t6g_mb_lib.t6g(sch_1):page80_i341@pure_quanta.q_cap(chips)';

PART_NAME
 C281 'Q_CAP_C0402-10UF,4V,20%,X6S,CH610KMEB09':;

SECTION_NUMBER 1
 '@T6G_MB_LIB.T6G(SCH_1):PAGE80_I312@PURE_QUANTA.Q_CAP(CHIPS)':
 C_PATH='@t6g_mb_lib.t6g(sch_1):page80_i312@pure_quanta.q_cap(chips)';

PART_NAME
 C280 'Q_CAP_C0402-10UF,4V,20%,X6S,CH610KMEB09':;

SECTION_NUMBER 1
 '@T6G_MB_LIB.T6G(SCH_1):PAGE80_I309@PURE_QUANTA.Q_CAP(CHIPS)':
 C_PATH='@t6g_mb_lib.t6g(sch_1):page80_i309@pure_quanta.q_cap(chips)';

PART_NAME
 C279 'Q_CAP_C0402-10UF,4V,20%,X6S,CH610KMEB09':;

SECTION_NUMBER 1
 '@T6G_MB_LIB.T6G(SCH_1):PAGE80_I308@PURE_QUANTA.Q_CAP(CHIPS)':
 C_PATH='@t6g_mb_lib.t6g(sch_1):page80_i308@pure_quanta.q_cap(chips)';

PART_NAME
 C278 'Q_CAP_C0402-10UF,4V,20%,X6S,CH610KMEB09':;

SECTION_NUMBER 1
 '@T6G_MB_LIB.T6G(SCH_1):PAGE80_I343@PURE_QUANTA.Q_CAP(CHIPS)':
 C_PATH='@t6g_mb_lib.t6g(sch_1):page80_i343@pure_quanta.q_cap(chips)';

PART_NAME
 C277 'Q_CAP_C0402-10UF,4V,20%,X6S,CH610KMEB09':;

SECTION_NUMBER 1
 '@T6G_MB_LIB.T6G(SCH_1):PAGE80_I313@PURE_QUANTA.Q_CAP(CHIPS)':
 C_PATH='@t6g_mb_lib.t6g(sch_1):page80_i313@pure_quanta.q_cap(chips)';

PART_NAME
 C276 'Q_CAP_C0402-10UF,4V,20%,X6S,CH610KMEB09':;

SECTION_NUMBER 1
 '@T6G_MB_LIB.T6G(SCH_1):PAGE80_I311@PURE_QUANTA.Q_CAP(CHIPS)':
 C_PATH='@t6g_mb_lib.t6g(sch_1):page80_i311@pure_quanta.q_cap(chips)';

PART_NAME
 C275 'Q_CAP_C0402-10UF,4V,20%,X6S,CH610KMEB09':;

SECTION_NUMBER 1
 '@T6G_MB_LIB.T6G(SCH_1):PAGE80_I310@PURE_QUANTA.Q_CAP(CHIPS)':
 C_PATH='@t6g_mb_lib.t6g(sch_1):page80_i310@pure_quanta.q_cap(chips)';

PART_NAME
 C274 'Q_CAP_C0402-10UF,4V,20%,X6S,CH610KMEB09':;

SECTION_NUMBER 1
 '@T6G_MB_LIB.T6G(SCH_1):PAGE80_I348@PURE_QUANTA.Q_CAP(CHIPS)':
 C_PATH='@t6g_mb_lib.t6g(sch_1):page80_i348@pure_quanta.q_cap(chips)';

PART_NAME
 C273 'Q_CAP_C0402-10UF,4V,20%,X6S,CH610KMEB09':;

SECTION_NUMBER 1
 '@T6G_MB_LIB.T6G(SCH_1):PAGE80_I323@PURE_QUANTA.Q_CAP(CHIPS)':
 C_PATH='@t6g_mb_lib.t6g(sch_1):page80_i323@pure_quanta.q_cap(chips)';

PART_NAME
 C272 'Q_CAP_C0402-10UF,4V,20%,X6S,CH610KMEB09':;

SECTION_NUMBER 1
 '@T6G_MB_LIB.T6G(SCH_1):PAGE80_I316@PURE_QUANTA.Q_CAP(CHIPS)':
 C_PATH='@t6g_mb_lib.t6g(sch_1):page80_i316@pure_quanta.q_cap(chips)';

PART_NAME
 C271 'Q_CAP_C0402-10UF,4V,20%,X6S,CH610KMEB09':;

SECTION_NUMBER 1
 '@T6G_MB_LIB.T6G(SCH_1):PAGE80_I314@PURE_QUANTA.Q_CAP(CHIPS)':
 C_PATH='@t6g_mb_lib.t6g(sch_1):page80_i314@pure_quanta.q_cap(chips)';

PART_NAME
 C270 'Q_CAP_0805-47UF,4V,20%,X6S,CH647KMEA00':;

SECTION_NUMBER 1
 '@T6G_MB_LIB.T6G(SCH_1):PAGE80_I352@PURE_QUANTA.Q_CAP(CHIPS)':
 C_PATH='@t6g_mb_lib.t6g(sch_1):page80_i352@pure_quanta.q_cap(chips)';

PART_NAME
 C269 'Q_CAP_C0402-10UF,4V,20%,X6S,CH610KMEB09':;

SECTION_NUMBER 1
 '@T6G_MB_LIB.T6G(SCH_1):PAGE80_I350@PURE_QUANTA.Q_CAP(CHIPS)':
 C_PATH='@t6g_mb_lib.t6g(sch_1):page80_i350@pure_quanta.q_cap(chips)';

PART_NAME
 C268 'Q_CAP_C0402-10UF,4V,20%,X6S,CH610KMEB09':;

SECTION_NUMBER 1
 '@T6G_MB_LIB.T6G(SCH_1):PAGE80_I326@PURE_QUANTA.Q_CAP(CHIPS)':
 C_PATH='@t6g_mb_lib.t6g(sch_1):page80_i326@pure_quanta.q_cap(chips)';

PART_NAME
 C267 'Q_CAP_C0402-10UF,4V,20%,X6S,CH610KMEB09':;

SECTION_NUMBER 1
 '@T6G_MB_LIB.T6G(SCH_1):PAGE80_I320@PURE_QUANTA.Q_CAP(CHIPS)':
 C_PATH='@t6g_mb_lib.t6g(sch_1):page80_i320@pure_quanta.q_cap(chips)';

PART_NAME
 C266 'Q_CAP_C0402-10UF,4V,20%,X6S,CH610KMEB09':;

SECTION_NUMBER 1
 '@T6G_MB_LIB.T6G(SCH_1):PAGE80_I317@PURE_QUANTA.Q_CAP(CHIPS)':
 C_PATH='@t6g_mb_lib.t6g(sch_1):page80_i317@pure_quanta.q_cap(chips)';

PART_NAME
 C265 'Q_CAP_0805-47UF,4V,20%,X6S,CH647KMEA00':;

SECTION_NUMBER 1
 '@T6G_MB_LIB.T6G(SCH_1):PAGE80_I355@PURE_QUANTA.Q_CAP(CHIPS)':
 C_PATH='@t6g_mb_lib.t6g(sch_1):page80_i355@pure_quanta.q_cap(chips)';

PART_NAME
 C264 'Q_CAP_C0402-10UF,4V,20%,X6S,CH610KMEB09':;

SECTION_NUMBER 1
 '@T6G_MB_LIB.T6G(SCH_1):PAGE80_I351@PURE_QUANTA.Q_CAP(CHIPS)':
 C_PATH='@t6g_mb_lib.t6g(sch_1):page80_i351@pure_quanta.q_cap(chips)';

PART_NAME
 C263 'Q_CAP_C0402-10UF,4V,20%,X6S,CH610KMEB09':;

SECTION_NUMBER 1
 '@T6G_MB_LIB.T6G(SCH_1):PAGE80_I328@PURE_QUANTA.Q_CAP(CHIPS)':
 C_PATH='@t6g_mb_lib.t6g(sch_1):page80_i328@pure_quanta.q_cap(chips)';

PART_NAME
 C262 'Q_CAP_C0402-10UF,4V,20%,X6S,CH610KMEB09':;

SECTION_NUMBER 1
 '@T6G_MB_LIB.T6G(SCH_1):PAGE80_I321@PURE_QUANTA.Q_CAP(CHIPS)':
 C_PATH='@t6g_mb_lib.t6g(sch_1):page80_i321@pure_quanta.q_cap(chips)';

PART_NAME
 C261 'Q_CAP_C0402-10UF,4V,20%,X6S,CH610KMEB09':;

SECTION_NUMBER 1
 '@T6G_MB_LIB.T6G(SCH_1):PAGE80_I319@PURE_QUANTA.Q_CAP(CHIPS)':
 C_PATH='@t6g_mb_lib.t6g(sch_1):page80_i319@pure_quanta.q_cap(chips)';

PART_NAME
 C260 'Q_CAP_0805-47UF,4V,20%,X6S,CH647KMEA00':;

SECTION_NUMBER 1
 '@T6G_MB_LIB.T6G(SCH_1):PAGE80_I363@PURE_QUANTA.Q_CAP(CHIPS)':
 C_PATH='@t6g_mb_lib.t6g(sch_1):page80_i363@pure_quanta.q_cap(chips)';

PART_NAME
 C259 'Q_CAP_C0402-10UF,4V,20%,X6S,CH610KMEB09':;

SECTION_NUMBER 1
 '@T6G_MB_LIB.T6G(SCH_1):PAGE80_I361@PURE_QUANTA.Q_CAP(CHIPS)':
 C_PATH='@t6g_mb_lib.t6g(sch_1):page80_i361@pure_quanta.q_cap(chips)';

PART_NAME
 C258 'Q_CAP_C0402-10UF,4V,20%,X6S,CH610KMEB09':;

SECTION_NUMBER 1
 '@T6G_MB_LIB.T6G(SCH_1):PAGE80_I333@PURE_QUANTA.Q_CAP(CHIPS)':
 C_PATH='@t6g_mb_lib.t6g(sch_1):page80_i333@pure_quanta.q_cap(chips)';

PART_NAME
 C257 'Q_CAP_C0402-10UF,4V,20%,X6S,CH610KMEB09':;

SECTION_NUMBER 1
 '@T6G_MB_LIB.T6G(SCH_1):PAGE80_I330@PURE_QUANTA.Q_CAP(CHIPS)':
 C_PATH='@t6g_mb_lib.t6g(sch_1):page80_i330@pure_quanta.q_cap(chips)';

PART_NAME
 C256 'Q_CAP_C0402-10UF,4V,20%,X6S,CH610KMEB09':;

SECTION_NUMBER 1
 '@T6G_MB_LIB.T6G(SCH_1):PAGE80_I329@PURE_QUANTA.Q_CAP(CHIPS)':
 C_PATH='@t6g_mb_lib.t6g(sch_1):page80_i329@pure_quanta.q_cap(chips)';

PART_NAME
 C255 'Q_CAP_0805-47UF,4V,20%,X6S,CH647KMEA00':;

SECTION_NUMBER 1
 '@T6G_MB_LIB.T6G(SCH_1):PAGE80_I365@PURE_QUANTA.Q_CAP(CHIPS)':
 C_PATH='@t6g_mb_lib.t6g(sch_1):page80_i365@pure_quanta.q_cap(chips)';

PART_NAME
 C254 'Q_CAP_C0402-10UF,4V,20%,X6S,CH610KMEB09':;

SECTION_NUMBER 1
 '@T6G_MB_LIB.T6G(SCH_1):PAGE80_I362@PURE_QUANTA.Q_CAP(CHIPS)':
 C_PATH='@t6g_mb_lib.t6g(sch_1):page80_i362@pure_quanta.q_cap(chips)';

PART_NAME
 C253 'Q_CAP_C0402-10UF,4V,20%,X6S,CH610KMEB09':;

SECTION_NUMBER 1
 '@T6G_MB_LIB.T6G(SCH_1):PAGE80_I334@PURE_QUANTA.Q_CAP(CHIPS)':
 C_PATH='@t6g_mb_lib.t6g(sch_1):page80_i334@pure_quanta.q_cap(chips)';

PART_NAME
 C252 'Q_CAP_C0402-10UF,4V,20%,X6S,CH610KMEB09':;

SECTION_NUMBER 1
 '@T6G_MB_LIB.T6G(SCH_1):PAGE80_I332@PURE_QUANTA.Q_CAP(CHIPS)':
 C_PATH='@t6g_mb_lib.t6g(sch_1):page80_i332@pure_quanta.q_cap(chips)';

PART_NAME
 C251 'Q_CAP_C0402-10UF,4V,20%,X6S,CH610KMEB09':;

SECTION_NUMBER 1
 '@T6G_MB_LIB.T6G(SCH_1):PAGE80_I331@PURE_QUANTA.Q_CAP(CHIPS)':
 C_PATH='@t6g_mb_lib.t6g(sch_1):page80_i331@pure_quanta.q_cap(chips)';

PART_NAME
 C250 'Q_CAP_0805-47UF,4V,20%,X6S,CH647KMEA00':;

SECTION_NUMBER 1
 '@T6G_MB_LIB.T6G(SCH_1):PAGE80_I369@PURE_QUANTA.Q_CAP(CHIPS)':
 C_PATH='@t6g_mb_lib.t6g(sch_1):page80_i369@pure_quanta.q_cap(chips)';

PART_NAME
 C249 'Q_CAP_C0402-10UF,4V,20%,X6S,CH610KMEB09':;

SECTION_NUMBER 1
 '@T6G_MB_LIB.T6G(SCH_1):PAGE80_I367@PURE_QUANTA.Q_CAP(CHIPS)':
 C_PATH='@t6g_mb_lib.t6g(sch_1):page80_i367@pure_quanta.q_cap(chips)';

PART_NAME
 C248 'Q_CAP_C0402-10UF,4V,20%,X6S,CH610KMEB09':;

SECTION_NUMBER 1
 '@T6G_MB_LIB.T6G(SCH_1):PAGE80_I339@PURE_QUANTA.Q_CAP(CHIPS)':
 C_PATH='@t6g_mb_lib.t6g(sch_1):page80_i339@pure_quanta.q_cap(chips)';

PART_NAME
 C247 'Q_CAP_C0402-10UF,4V,20%,X6S,CH610KMEB09':;

SECTION_NUMBER 1
 '@T6G_MB_LIB.T6G(SCH_1):PAGE80_I336@PURE_QUANTA.Q_CAP(CHIPS)':
 C_PATH='@t6g_mb_lib.t6g(sch_1):page80_i336@pure_quanta.q_cap(chips)';

PART_NAME
 C246 'Q_CAP_C0402-10UF,4V,20%,X6S,CH610KMEB09':;

SECTION_NUMBER 1
 '@T6G_MB_LIB.T6G(SCH_1):PAGE80_I335@PURE_QUANTA.Q_CAP(CHIPS)':
 C_PATH='@t6g_mb_lib.t6g(sch_1):page80_i335@pure_quanta.q_cap(chips)';

PART_NAME
 C245 'Q_CAP_0805-47UF,4V,20%,X6S,CH647KMEA00':;

SECTION_NUMBER 1
 '@T6G_MB_LIB.T6G(SCH_1):PAGE80_I372@PURE_QUANTA.Q_CAP(CHIPS)':
 C_PATH='@t6g_mb_lib.t6g(sch_1):page80_i372@pure_quanta.q_cap(chips)';

PART_NAME
 C244 'Q_CAP_C0402-10UF,4V,20%,X6S,CH610KMEB09':;

SECTION_NUMBER 1
 '@T6G_MB_LIB.T6G(SCH_1):PAGE80_I368@PURE_QUANTA.Q_CAP(CHIPS)':
 C_PATH='@t6g_mb_lib.t6g(sch_1):page80_i368@pure_quanta.q_cap(chips)';

PART_NAME
 C243 'Q_CAP_C0402-10UF,4V,20%,X6S,CH610KMEB09':;

SECTION_NUMBER 1
 '@T6G_MB_LIB.T6G(SCH_1):PAGE80_I340@PURE_QUANTA.Q_CAP(CHIPS)':
 C_PATH='@t6g_mb_lib.t6g(sch_1):page80_i340@pure_quanta.q_cap(chips)';

PART_NAME
 C242 'Q_CAP_C0402-10UF,4V,20%,X6S,CH610KMEB09':;

SECTION_NUMBER 1
 '@T6G_MB_LIB.T6G(SCH_1):PAGE80_I338@PURE_QUANTA.Q_CAP(CHIPS)':
 C_PATH='@t6g_mb_lib.t6g(sch_1):page80_i338@pure_quanta.q_cap(chips)';

PART_NAME
 C241 'Q_CAP_C0402-10UF,4V,20%,X6S,CH610KMEB09':;

SECTION_NUMBER 1
 '@T6G_MB_LIB.T6G(SCH_1):PAGE80_I337@PURE_QUANTA.Q_CAP(CHIPS)':
 C_PATH='@t6g_mb_lib.t6g(sch_1):page80_i337@pure_quanta.q_cap(chips)';

PART_NAME
 C240 'Q_CAP_0805-47UF,4V,20%,X6S,CH647KMEA00':;

SECTION_NUMBER 1
 '@T6G_MB_LIB.T6G(SCH_1):PAGE80_I395@PURE_QUANTA.Q_CAP(CHIPS)':
 C_PATH='@t6g_mb_lib.t6g(sch_1):page80_i395@pure_quanta.q_cap(chips)';

PART_NAME
 C239 'Q_CAP_C0402-10UF,4V,20%,X6S,CH610KMEB09':;

SECTION_NUMBER 1
 '@T6G_MB_LIB.T6G(SCH_1):PAGE80_I393@PURE_QUANTA.Q_CAP(CHIPS)':
 C_PATH='@t6g_mb_lib.t6g(sch_1):page80_i393@pure_quanta.q_cap(chips)';

PART_NAME
 C238 'Q_CAP_C0402-10UF,4V,20%,X6S,CH610KMEB09':;

SECTION_NUMBER 1
 '@T6G_MB_LIB.T6G(SCH_1):PAGE80_I382@PURE_QUANTA.Q_CAP(CHIPS)':
 C_PATH='@t6g_mb_lib.t6g(sch_1):page80_i382@pure_quanta.q_cap(chips)';

PART_NAME
 C237 'Q_CAP_C0402-10UF,4V,20%,X6S,CH610KMEB09':;

SECTION_NUMBER 1
 '@T6G_MB_LIB.T6G(SCH_1):PAGE80_I379@PURE_QUANTA.Q_CAP(CHIPS)':
 C_PATH='@t6g_mb_lib.t6g(sch_1):page80_i379@pure_quanta.q_cap(chips)';

PART_NAME
 C236 'Q_CAP_C0402-10UF,4V,20%,X6S,CH610KMEB09':;

SECTION_NUMBER 1
 '@T6G_MB_LIB.T6G(SCH_1):PAGE80_I378@PURE_QUANTA.Q_CAP(CHIPS)':
 C_PATH='@t6g_mb_lib.t6g(sch_1):page80_i378@pure_quanta.q_cap(chips)';

PART_NAME
 C235 'Q_CAP_0805-47UF,4V,20%,X6S,CH647KMEA00':;

SECTION_NUMBER 1
 '@T6G_MB_LIB.T6G(SCH_1):PAGE80_I397@PURE_QUANTA.Q_CAP(CHIPS)':
 C_PATH='@t6g_mb_lib.t6g(sch_1):page80_i397@pure_quanta.q_cap(chips)';

PART_NAME
 C234 'Q_CAP_C0402-10UF,4V,20%,X6S,CH610KMEB09':;

SECTION_NUMBER 1
 '@T6G_MB_LIB.T6G(SCH_1):PAGE80_I394@PURE_QUANTA.Q_CAP(CHIPS)':
 C_PATH='@t6g_mb_lib.t6g(sch_1):page80_i394@pure_quanta.q_cap(chips)';

PART_NAME
 C233 'Q_CAP_C0402-10UF,4V,20%,X6S,CH610KMEB09':;

SECTION_NUMBER 1
 '@T6G_MB_LIB.T6G(SCH_1):PAGE80_I383@PURE_QUANTA.Q_CAP(CHIPS)':
 C_PATH='@t6g_mb_lib.t6g(sch_1):page80_i383@pure_quanta.q_cap(chips)';

PART_NAME
 C232 'Q_CAP_C0402-10UF,4V,20%,X6S,CH610KMEB09':;

SECTION_NUMBER 1
 '@T6G_MB_LIB.T6G(SCH_1):PAGE80_I381@PURE_QUANTA.Q_CAP(CHIPS)':
 C_PATH='@t6g_mb_lib.t6g(sch_1):page80_i381@pure_quanta.q_cap(chips)';

PART_NAME
 C231 'Q_CAP_C0402-10UF,4V,20%,X6S,CH610KMEB09':;

SECTION_NUMBER 1
 '@T6G_MB_LIB.T6G(SCH_1):PAGE80_I380@PURE_QUANTA.Q_CAP(CHIPS)':
 C_PATH='@t6g_mb_lib.t6g(sch_1):page80_i380@pure_quanta.q_cap(chips)';

PART_NAME
 C230 'Q_CAP_0805-47UF,4V,20%,X6S,CH647KMEA00':;

SECTION_NUMBER 1
 '@T6G_MB_LIB.T6G(SCH_1):PAGE80_I402@PURE_QUANTA.Q_CAP(CHIPS)':
 C_PATH='@t6g_mb_lib.t6g(sch_1):page80_i402@pure_quanta.q_cap(chips)';

PART_NAME
 C229 'Q_CAP_C0402-10UF,4V,20%,X6S,CH610KMEB09':;

SECTION_NUMBER 1
 '@T6G_MB_LIB.T6G(SCH_1):PAGE80_I399@PURE_QUANTA.Q_CAP(CHIPS)':
 C_PATH='@t6g_mb_lib.t6g(sch_1):page80_i399@pure_quanta.q_cap(chips)';

PART_NAME
 C228 'Q_CAP_C0402-10UF,4V,20%,X6S,CH610KMEB09':;

SECTION_NUMBER 1
 '@T6G_MB_LIB.T6G(SCH_1):PAGE80_I390@PURE_QUANTA.Q_CAP(CHIPS)':
 C_PATH='@t6g_mb_lib.t6g(sch_1):page80_i390@pure_quanta.q_cap(chips)';

PART_NAME
 C227 'Q_CAP_C0402-10UF,4V,20%,X6S,CH610KMEB09':;

SECTION_NUMBER 1
 '@T6G_MB_LIB.T6G(SCH_1):PAGE80_I387@PURE_QUANTA.Q_CAP(CHIPS)':
 C_PATH='@t6g_mb_lib.t6g(sch_1):page80_i387@pure_quanta.q_cap(chips)';

PART_NAME
 C226 'Q_CAP_C0402-10UF,4V,20%,X6S,CH610KMEB09':;

SECTION_NUMBER 1
 '@T6G_MB_LIB.T6G(SCH_1):PAGE80_I384@PURE_QUANTA.Q_CAP(CHIPS)':
 C_PATH='@t6g_mb_lib.t6g(sch_1):page80_i384@pure_quanta.q_cap(chips)';

PART_NAME
 C225 'Q_CAP_0805-47UF,4V,20%,X6S,CH647KMEA00':;

SECTION_NUMBER 1
 '@T6G_MB_LIB.T6G(SCH_1):PAGE80_I403@PURE_QUANTA.Q_CAP(CHIPS)':
 C_PATH='@t6g_mb_lib.t6g(sch_1):page80_i403@pure_quanta.q_cap(chips)';

PART_NAME
 C224 'Q_CAP_C0402-10UF,4V,20%,X6S,CH610KMEB09':;

SECTION_NUMBER 1
 '@T6G_MB_LIB.T6G(SCH_1):PAGE80_I400@PURE_QUANTA.Q_CAP(CHIPS)':
 C_PATH='@t6g_mb_lib.t6g(sch_1):page80_i400@pure_quanta.q_cap(chips)';

PART_NAME
 C223 'Q_CAP_C0402-10UF,4V,20%,X6S,CH610KMEB09':;

SECTION_NUMBER 1
 '@T6G_MB_LIB.T6G(SCH_1):PAGE80_I391@PURE_QUANTA.Q_CAP(CHIPS)':
 C_PATH='@t6g_mb_lib.t6g(sch_1):page80_i391@pure_quanta.q_cap(chips)';

PART_NAME
 C222 'Q_CAP_C0402-10UF,4V,20%,X6S,CH610KMEB09':;

SECTION_NUMBER 1
 '@T6G_MB_LIB.T6G(SCH_1):PAGE80_I388@PURE_QUANTA.Q_CAP(CHIPS)':
 C_PATH='@t6g_mb_lib.t6g(sch_1):page80_i388@pure_quanta.q_cap(chips)';

PART_NAME
 C221 'Q_CAP_C0402-10UF,4V,20%,X6S,CH610KMEB09':;

SECTION_NUMBER 1
 '@T6G_MB_LIB.T6G(SCH_1):PAGE80_I385@PURE_QUANTA.Q_CAP(CHIPS)':
 C_PATH='@t6g_mb_lib.t6g(sch_1):page80_i385@pure_quanta.q_cap(chips)';

PART_NAME
 C2556 'Q_CAP_DIFFBUS_C0201-DIFF BUS_0.22UF,6.3V,20%,X6S,SP_CH4221MEE01':;

SECTION_NUMBER 1
 '@T6G_MB_LIB.T6G(SCH_1):PAGE164_I73@PURE_QUANTA.Q_CAP_DIFFBUS(CHIPS)':
 C_PATH='@t6g_mb_lib.t6g(sch_1):page164_i73@pure_quanta.q_cap_diffbus(chips)';

PART_NAME
 C2543 'Q_CAP_DIFFBUS_C0201-DIFF BUS_0.22UF,6.3V,20%,X6S,SP_CH4221MEE01':;

SECTION_NUMBER 1
 '@T6G_MB_LIB.T6G(SCH_1):PAGE164_I23@PURE_QUANTA.Q_CAP_DIFFBUS(CHIPS)':
 C_PATH='@t6g_mb_lib.t6g(sch_1):page164_i23@pure_quanta.q_cap_diffbus(chips)';

PART_NAME
 C2507 'Q_CAP_DIFFBUS_C0201-DIFF BUS_0.22UF,6.3V,20%,X6S,SP_CH4221MEE01':;

SECTION_NUMBER 1
 '@T6G_MB_LIB.T6G(SCH_1):PAGE164_I74@PURE_QUANTA.Q_CAP_DIFFBUS(CHIPS)':
 C_PATH='@t6g_mb_lib.t6g(sch_1):page164_i74@pure_quanta.q_cap_diffbus(chips)';

PART_NAME
 C2506 'Q_CAP_DIFFBUS_C0201-DIFF BUS_0.22UF,6.3V,20%,X6S,SP_CH4221MEE01':;

SECTION_NUMBER 1
 '@T6G_MB_LIB.T6G(SCH_1):PAGE164_I75@PURE_QUANTA.Q_CAP_DIFFBUS(CHIPS)':
 C_PATH='@t6g_mb_lib.t6g(sch_1):page164_i75@pure_quanta.q_cap_diffbus(chips)';

PART_NAME
 C2505 'Q_CAP_DIFFBUS_C0201-DIFF BUS_0.22UF,6.3V,20%,X6S,SP_CH4221MEE01':;

SECTION_NUMBER 1
 '@T6G_MB_LIB.T6G(SCH_1):PAGE164_I81@PURE_QUANTA.Q_CAP_DIFFBUS(CHIPS)':
 C_PATH='@t6g_mb_lib.t6g(sch_1):page164_i81@pure_quanta.q_cap_diffbus(chips)';

PART_NAME
 C2504 'Q_CAP_DIFFBUS_C0201-DIFF BUS_0.22UF,6.3V,20%,X6S,SP_CH4221MEE01':;

SECTION_NUMBER 1
 '@T6G_MB_LIB.T6G(SCH_1):PAGE164_I82@PURE_QUANTA.Q_CAP_DIFFBUS(CHIPS)':
 C_PATH='@t6g_mb_lib.t6g(sch_1):page164_i82@pure_quanta.q_cap_diffbus(chips)';

PART_NAME
 C2503 'Q_CAP_DIFFBUS_C0201-DIFF BUS_0.22UF,6.3V,20%,X6S,SP_CH4221MEE01':;

SECTION_NUMBER 1
 '@T6G_MB_LIB.T6G(SCH_1):PAGE164_I88@PURE_QUANTA.Q_CAP_DIFFBUS(CHIPS)':
 C_PATH='@t6g_mb_lib.t6g(sch_1):page164_i88@pure_quanta.q_cap_diffbus(chips)';

PART_NAME
 C2502 'Q_CAP_DIFFBUS_C0201-DIFF BUS_0.22UF,6.3V,20%,X6S,SP_CH4221MEE01':;

SECTION_NUMBER 1
 '@T6G_MB_LIB.T6G(SCH_1):PAGE164_I89@PURE_QUANTA.Q_CAP_DIFFBUS(CHIPS)':
 C_PATH='@t6g_mb_lib.t6g(sch_1):page164_i89@pure_quanta.q_cap_diffbus(chips)';

PART_NAME
 C2501 'Q_CAP_DIFFBUS_C0201-DIFF BUS_0.22UF,6.3V,20%,X6S,SP_CH4221MEE01':;

SECTION_NUMBER 1
 '@T6G_MB_LIB.T6G(SCH_1):PAGE164_I55@PURE_QUANTA.Q_CAP_DIFFBUS(CHIPS)':
 C_PATH='@t6g_mb_lib.t6g(sch_1):page164_i55@pure_quanta.q_cap_diffbus(chips)';

PART_NAME
 C2500 'Q_CAP_DIFFBUS_C0201-DIFF BUS_0.22UF,6.3V,20%,X6S,SP_CH4221MEE01':;

SECTION_NUMBER 1
 '@T6G_MB_LIB.T6G(SCH_1):PAGE164_I57@PURE_QUANTA.Q_CAP_DIFFBUS(CHIPS)':
 C_PATH='@t6g_mb_lib.t6g(sch_1):page164_i57@pure_quanta.q_cap_diffbus(chips)';

PART_NAME
 C2499 'Q_CAP_DIFFBUS_C0201-DIFF BUS_0.22UF,6.3V,20%,X6S,SP_CH4221MEE01':;

SECTION_NUMBER 1
 '@T6G_MB_LIB.T6G(SCH_1):PAGE164_I64@PURE_QUANTA.Q_CAP_DIFFBUS(CHIPS)':
 C_PATH='@t6g_mb_lib.t6g(sch_1):page164_i64@pure_quanta.q_cap_diffbus(chips)';

PART_NAME
 C2498 'Q_CAP_DIFFBUS_C0201-DIFF BUS_0.22UF,6.3V,20%,X6S,SP_CH4221MEE01':;

SECTION_NUMBER 1
 '@T6G_MB_LIB.T6G(SCH_1):PAGE164_I65@PURE_QUANTA.Q_CAP_DIFFBUS(CHIPS)':
 C_PATH='@t6g_mb_lib.t6g(sch_1):page164_i65@pure_quanta.q_cap_diffbus(chips)';

PART_NAME
 C2497 'Q_CAP_DIFFBUS_C0201-DIFF BUS_0.22UF,6.3V,20%,X6S,SP_CH4221MEE01':;

SECTION_NUMBER 1
 '@T6G_MB_LIB.T6G(SCH_1):PAGE164_I71@PURE_QUANTA.Q_CAP_DIFFBUS(CHIPS)':
 C_PATH='@t6g_mb_lib.t6g(sch_1):page164_i71@pure_quanta.q_cap_diffbus(chips)';

PART_NAME
 C2496 'Q_CAP_DIFFBUS_C0201-DIFF BUS_0.22UF,6.3V,20%,X6S,SP_CH4221MEE01':;

SECTION_NUMBER 1
 '@T6G_MB_LIB.T6G(SCH_1):PAGE164_I72@PURE_QUANTA.Q_CAP_DIFFBUS(CHIPS)':
 C_PATH='@t6g_mb_lib.t6g(sch_1):page164_i72@pure_quanta.q_cap_diffbus(chips)';

PART_NAME
 C2495 'Q_CAP_DIFFBUS_C0201-DIFF BUS_0.22UF,6.3V,20%,X6S,SP_CH4221MEE01':;

SECTION_NUMBER 1
 '@T6G_MB_LIB.T6G(SCH_1):PAGE164_I98@PURE_QUANTA.Q_CAP_DIFFBUS(CHIPS)':
 C_PATH='@t6g_mb_lib.t6g(sch_1):page164_i98@pure_quanta.q_cap_diffbus(chips)';

PART_NAME
 C2494 'Q_CAP_DIFFBUS_C0201-DIFF BUS_0.22UF,6.3V,20%,X6S,SP_CH4221MEE01':;

SECTION_NUMBER 1
 '@T6G_MB_LIB.T6G(SCH_1):PAGE164_I24@PURE_QUANTA.Q_CAP_DIFFBUS(CHIPS)':
 C_PATH='@t6g_mb_lib.t6g(sch_1):page164_i24@pure_quanta.q_cap_diffbus(chips)';

PART_NAME
 C2493 'Q_CAP_DIFFBUS_C0201-DIFF BUS_0.22UF,6.3V,20%,X6S,SP_CH4221MEE01':;

SECTION_NUMBER 1
 '@T6G_MB_LIB.T6G(SCH_1):PAGE164_I25@PURE_QUANTA.Q_CAP_DIFFBUS(CHIPS)':
 C_PATH='@t6g_mb_lib.t6g(sch_1):page164_i25@pure_quanta.q_cap_diffbus(chips)';

PART_NAME
 C2492 'Q_CAP_DIFFBUS_C0201-DIFF BUS_0.22UF,6.3V,20%,X6S,SP_CH4221MEE01':;

SECTION_NUMBER 1
 '@T6G_MB_LIB.T6G(SCH_1):PAGE164_I31@PURE_QUANTA.Q_CAP_DIFFBUS(CHIPS)':
 C_PATH='@t6g_mb_lib.t6g(sch_1):page164_i31@pure_quanta.q_cap_diffbus(chips)';

PART_NAME
 C2491 'Q_CAP_DIFFBUS_C0201-DIFF BUS_0.22UF,6.3V,20%,X6S,SP_CH4221MEE01':;

SECTION_NUMBER 1
 '@T6G_MB_LIB.T6G(SCH_1):PAGE164_I32@PURE_QUANTA.Q_CAP_DIFFBUS(CHIPS)':
 C_PATH='@t6g_mb_lib.t6g(sch_1):page164_i32@pure_quanta.q_cap_diffbus(chips)';

PART_NAME
 C2490 'Q_CAP_DIFFBUS_C0201-DIFF BUS_0.22UF,6.3V,20%,X6S,SP_CH4221MEE01':;

SECTION_NUMBER 1
 '@T6G_MB_LIB.T6G(SCH_1):PAGE164_I38@PURE_QUANTA.Q_CAP_DIFFBUS(CHIPS)':
 C_PATH='@t6g_mb_lib.t6g(sch_1):page164_i38@pure_quanta.q_cap_diffbus(chips)';

PART_NAME
 C2489 'Q_CAP_DIFFBUS_C0201-DIFF BUS_0.22UF,6.3V,20%,X6S,SP_CH4221MEE01':;

SECTION_NUMBER 1
 '@T6G_MB_LIB.T6G(SCH_1):PAGE164_I39@PURE_QUANTA.Q_CAP_DIFFBUS(CHIPS)':
 C_PATH='@t6g_mb_lib.t6g(sch_1):page164_i39@pure_quanta.q_cap_diffbus(chips)';

PART_NAME
 C2488 'Q_CAP_DIFFBUS_C0201-DIFF BUS_0.22UF,6.3V,20%,X6S,SP_CH4221MEE01':;

SECTION_NUMBER 1
 '@T6G_MB_LIB.T6G(SCH_1):PAGE164_I40@PURE_QUANTA.Q_CAP_DIFFBUS(CHIPS)':
 C_PATH='@t6g_mb_lib.t6g(sch_1):page164_i40@pure_quanta.q_cap_diffbus(chips)';

PART_NAME
 C2487 'Q_CAP_DIFFBUS_C0201-DIFF BUS_0.22UF,6.3V,20%,X6S,SP_CH4221MEE01':;

SECTION_NUMBER 1
 '@T6G_MB_LIB.T6G(SCH_1):PAGE164_I3@PURE_QUANTA.Q_CAP_DIFFBUS(CHIPS)':
 C_PATH='@t6g_mb_lib.t6g(sch_1):page164_i3@pure_quanta.q_cap_diffbus(chips)';

PART_NAME
 C2486 'Q_CAP_DIFFBUS_C0201-DIFF BUS_0.22UF,6.3V,20%,X6S,SP_CH4221MEE01':;

SECTION_NUMBER 1
 '@T6G_MB_LIB.T6G(SCH_1):PAGE164_I7@PURE_QUANTA.Q_CAP_DIFFBUS(CHIPS)':
 C_PATH='@t6g_mb_lib.t6g(sch_1):page164_i7@pure_quanta.q_cap_diffbus(chips)';

PART_NAME
 C2485 'Q_CAP_DIFFBUS_C0201-DIFF BUS_0.22UF,6.3V,20%,X6S,SP_CH4221MEE01':;

SECTION_NUMBER 1
 '@T6G_MB_LIB.T6G(SCH_1):PAGE164_I10@PURE_QUANTA.Q_CAP_DIFFBUS(CHIPS)':
 C_PATH='@t6g_mb_lib.t6g(sch_1):page164_i10@pure_quanta.q_cap_diffbus(chips)';

PART_NAME
 C2484 'Q_CAP_DIFFBUS_C0201-DIFF BUS_0.22UF,6.3V,20%,X6S,SP_CH4221MEE01':;

SECTION_NUMBER 1
 '@T6G_MB_LIB.T6G(SCH_1):PAGE164_I14@PURE_QUANTA.Q_CAP_DIFFBUS(CHIPS)':
 C_PATH='@t6g_mb_lib.t6g(sch_1):page164_i14@pure_quanta.q_cap_diffbus(chips)';

PART_NAME
 C2483 'Q_CAP_DIFFBUS_C0201-DIFF BUS_0.22UF,6.3V,20%,X6S,SP_CH4221MEE01':;

SECTION_NUMBER 1
 '@T6G_MB_LIB.T6G(SCH_1):PAGE164_I15@PURE_QUANTA.Q_CAP_DIFFBUS(CHIPS)':
 C_PATH='@t6g_mb_lib.t6g(sch_1):page164_i15@pure_quanta.q_cap_diffbus(chips)';

PART_NAME
 C705 'Q_CAP_DIFFBUS_C0201-DIFF BUS_0.22UF,6.3V,20%,X6S,SP_CH4221MEE01':;

SECTION_NUMBER 1
 '@T6G_MB_LIB.T6G(SCH_1):PAGE164_I22@PURE_QUANTA.Q_CAP_DIFFBUS(CHIPS)':
 C_PATH='@t6g_mb_lib.t6g(sch_1):page164_i22@pure_quanta.q_cap_diffbus(chips)';

PART_NAME
 C378 'Q_CAP_DIFFBUS_C0201-DIFF BUS_0.22UF,6.3V,20%,X6S,SP_CH4221MEE01':;

SECTION_NUMBER 1
 '@T6G_MB_LIB.T6G(SCH_1):PAGE164_I90@PURE_QUANTA.Q_CAP_DIFFBUS(CHIPS)':
 C_PATH='@t6g_mb_lib.t6g(sch_1):page164_i90@pure_quanta.q_cap_diffbus(chips)';

PART_NAME
 C375 'Q_CAP_DIFFBUS_C0201-DIFF BUS_0.22UF,6.3V,20%,X6S,SP_CH4221MEE01':;

SECTION_NUMBER 1
 '@T6G_MB_LIB.T6G(SCH_1):PAGE164_I63@PURE_QUANTA.Q_CAP_DIFFBUS(CHIPS)':
 C_PATH='@t6g_mb_lib.t6g(sch_1):page164_i63@pure_quanta.q_cap_diffbus(chips)';

PART_NAME
 C200 'Q_CAP_DIFFBUS_C0201-DIFF BUS_0.22UF,6.3V,20%,X6S,SP_CH4221MEE01':;

SECTION_NUMBER 1
 '@T6G_MB_LIB.T6G(SCH_1):PAGE164_I18@PURE_QUANTA.Q_CAP_DIFFBUS(CHIPS)':
 C_PATH='@t6g_mb_lib.t6g(sch_1):page164_i18@pure_quanta.q_cap_diffbus(chips)';

PART_NAME
 C198 'Q_CAP_DIFFBUS_C0201-DIFF BUS_0.22UF,6.3V,20%,X6S,SP_CH4221MEE01':;

SECTION_NUMBER 1
 '@T6G_MB_LIB.T6G(SCH_1):PAGE164_I48@PURE_QUANTA.Q_CAP_DIFFBUS(CHIPS)':
 C_PATH='@t6g_mb_lib.t6g(sch_1):page164_i48@pure_quanta.q_cap_diffbus(chips)';

PART_NAME
 U76 'SN74LVC1G32DBVR-SN74LVC1G32DBVR,SMLF,IC,AL001G32015':;

SECTION_NUMBER 1
 '@T6G_MB_LIB.T6G(SCH_1):PAGE279_I35@PURE_QUANTA.SN74LVC1G32DBVR(CHIPS)':
 C_PATH='@t6g_mb_lib.t6g(sch_1):page279_i35@pure_quanta.sn74lvc1g32dbvr(chips)';

PART_NAME
 U42 'SN74LVC1G08DBVR_SMLF-SN74LVC1G08DBVR,IC,AL1G0008012':;

SECTION_NUMBER 1
 '@T6G_MB_LIB.T6G(SCH_1):PAGE279_I28@PURE_QUANTA.SN74LVC1G08DBVR(CHIPS)':
 C_PATH='@t6g_mb_lib.t6g(sch_1):page279_i28@pure_quanta.sn74lvc1g08dbvr(chips)';

PART_NAME
 U41 'SN74LVC1G32DBVR-SN74LVC1G32DBVR,SMLF,IC,AL001G32015':;

SECTION_NUMBER 1
 '@T6G_MB_LIB.T6G(SCH_1):PAGE279_I43@PURE_QUANTA.SN74LVC1G32DBVR(CHIPS)':
 C_PATH='@t6g_mb_lib.t6g(sch_1):page279_i43@pure_quanta.sn74lvc1g32dbvr(chips)';

PART_NAME
 U40 'SN74LVC1G08DBVR_SMLF-SN74LVC1G08DBVR,IC,AL1G0008012':;

SECTION_NUMBER 1
 '@T6G_MB_LIB.T6G(SCH_1):PAGE279_I49@PURE_QUANTA.SN74LVC1G08DBVR(CHIPS)':
 C_PATH='@t6g_mb_lib.t6g(sch_1):page279_i49@pure_quanta.sn74lvc1g08dbvr(chips)';

PART_NAME
 U39 'SN74LVC1G08DBVR_SMLF-SN74LVC1G08DBVR,IC,AL1G0008012':;

SECTION_NUMBER 1
 '@T6G_MB_LIB.T6G(SCH_1):PAGE279_I48@PURE_QUANTA.SN74LVC1G08DBVR(CHIPS)':
 C_PATH='@t6g_mb_lib.t6g(sch_1):page279_i48@pure_quanta.sn74lvc1g08dbvr(chips)';

PART_NAME
 R3585 'Q_RES_0402LF-0,5%,1/16W,EMPTY,CS00002JB38':;

SECTION_NUMBER 1
 '@T6G_MB_LIB.T6G(SCH_1):PAGE279_I52@PURE_QUANTA.Q_RES(CHIPS)':
 C_PATH='@t6g_mb_lib.t6g(sch_1):page279_i52@pure_quanta.q_res(chips)';

PART_NAME
 R3584 'Q_RES_0402LF-0,5%,1/16W,EMPTY,CS00002JB38':;

SECTION_NUMBER 1
 '@T6G_MB_LIB.T6G(SCH_1):PAGE279_I53@PURE_QUANTA.Q_RES(CHIPS)':
 C_PATH='@t6g_mb_lib.t6g(sch_1):page279_i53@pure_quanta.q_res(chips)';

PART_NAME
 R1073 'Q_RES_0402LF-0,5%,1/16W,CHIP,CS00002JB38':;

SECTION_NUMBER 1
 '@T6G_MB_LIB.T6G(SCH_1):PAGE279_I11@PURE_QUANTA.Q_RES(CHIPS)':
 C_PATH='@t6g_mb_lib.t6g(sch_1):page279_i11@pure_quanta.q_res(chips)';

PART_NAME
 R1072 'Q_RES_0402LF-0,5%,1/16W,CHIP,CS00002JB38':;

SECTION_NUMBER 1
 '@T6G_MB_LIB.T6G(SCH_1):PAGE279_I7@PURE_QUANTA.Q_RES(CHIPS)':
 C_PATH='@t6g_mb_lib.t6g(sch_1):page279_i7@pure_quanta.q_res(chips)';

PART_NAME
 R1071 'Q_RES_0402LF-0,5%,1/16W,CHIP,CS00002JB38':;

SECTION_NUMBER 1
 '@T6G_MB_LIB.T6G(SCH_1):PAGE279_I8@PURE_QUANTA.Q_RES(CHIPS)':
 C_PATH='@t6g_mb_lib.t6g(sch_1):page279_i8@pure_quanta.q_res(chips)';

PART_NAME
 R1070 'Q_RES_0402LF-0,5%,1/16W,CHIP,CS00002JB38':;

SECTION_NUMBER 1
 '@T6G_MB_LIB.T6G(SCH_1):PAGE279_I19@PURE_QUANTA.Q_RES(CHIPS)':
 C_PATH='@t6g_mb_lib.t6g(sch_1):page279_i19@pure_quanta.q_res(chips)';

PART_NAME
 R1069 'Q_RES_0402LF-0,5%,1/16W,CHIP,CS00002JB38':;

SECTION_NUMBER 1
 '@T6G_MB_LIB.T6G(SCH_1):PAGE279_I20@PURE_QUANTA.Q_RES(CHIPS)':
 C_PATH='@t6g_mb_lib.t6g(sch_1):page279_i20@pure_quanta.q_res(chips)';

PART_NAME
 R1068 'Q_RES_0402LF-10K,5%,1/16W,CHIP,TMP_QCS31002JB28':;

SECTION_NUMBER 1
 '@T6G_MB_LIB.T6G(SCH_1):PAGE279_I24@PURE_QUANTA.Q_RES(CHIPS)':
 C_PATH='@t6g_mb_lib.t6g(sch_1):page279_i24@pure_quanta.q_res(chips)';

PART_NAME
 R1067 'Q_RES_0402LF-10K,5%,1/16W,CHIP,TMP_QCS31002JB28':;

SECTION_NUMBER 1
 '@T6G_MB_LIB.T6G(SCH_1):PAGE279_I22@PURE_QUANTA.Q_RES(CHIPS)':
 C_PATH='@t6g_mb_lib.t6g(sch_1):page279_i22@pure_quanta.q_res(chips)';

PART_NAME
 R892 'Q_RES_0402LF-0,5%,1/16W,CHIP,CS00002JB38':;

SECTION_NUMBER 1
 '@T6G_MB_LIB.T6G(SCH_1):PAGE279_I10@PURE_QUANTA.Q_RES(CHIPS)':
 C_PATH='@t6g_mb_lib.t6g(sch_1):page279_i10@pure_quanta.q_res(chips)';

PART_NAME
 Q20 'MOSFET_DUAL_6P-2N7002KDW,SMLF,IC,BAM70020047':;

SECTION_NUMBER 1
 '@T6G_MB_LIB.T6G(SCH_1):PAGE279_I21@PURE_QUANTA.MOSFET_DUAL_6P(CHIPS)':
 C_PATH='@t6g_mb_lib.t6g(sch_1):page279_i21@pure_quanta.mosfet_dual_6p(chips)';

PART_NAME
 D79 'Q_DIODE_SMLF-SDMK0340L-7-F,IC,BC000340033':;

SECTION_NUMBER 1
 '@T6G_MB_LIB.T6G(SCH_1):PAGE279_I56@PURE_QUANTA.Q_DIODE(CHIPS)':
 C_PATH='@t6g_mb_lib.t6g(sch_1):page279_i56@pure_quanta.q_diode(chips)';

PART_NAME
 D76 'Q_DIODE_SMLF-SDMK0340L-7-F,IC,BC000340033':;

SECTION_NUMBER 1
 '@T6G_MB_LIB.T6G(SCH_1):PAGE279_I50@PURE_QUANTA.Q_DIODE(CHIPS)':
 C_PATH='@t6g_mb_lib.t6g(sch_1):page279_i50@pure_quanta.q_diode(chips)';

PART_NAME
 C708 'Q_CAP_0402-0.1UF,25V,10%,X7R,CH4104K1B00':;

SECTION_NUMBER 1
 '@T6G_MB_LIB.T6G(SCH_1):PAGE279_I45@PURE_QUANTA.Q_CAP(CHIPS)':
 C_PATH='@t6g_mb_lib.t6g(sch_1):page279_i45@pure_quanta.q_cap(chips)';

PART_NAME
 C707 'Q_CAP_0402-0.1UF,25V,10%,X7R,CH4104K1B00':;

SECTION_NUMBER 1
 '@T6G_MB_LIB.T6G(SCH_1):PAGE279_I39@PURE_QUANTA.Q_CAP(CHIPS)':
 C_PATH='@t6g_mb_lib.t6g(sch_1):page279_i39@pure_quanta.q_cap(chips)';

PART_NAME
 C706 'Q_CAP_0402-0.1UF,25V,10%,X7R,CH4104K1B00':;

SECTION_NUMBER 1
 '@T6G_MB_LIB.T6G(SCH_1):PAGE279_I33@PURE_QUANTA.Q_CAP(CHIPS)':
 C_PATH='@t6g_mb_lib.t6g(sch_1):page279_i33@pure_quanta.q_cap(chips)';

PART_NAME
 C199 'Q_CAP_0402-0.1UF,25V,10%,X7R,CH4104K1B00':;

SECTION_NUMBER 1
 '@T6G_MB_LIB.T6G(SCH_1):PAGE279_I41@PURE_QUANTA.Q_CAP(CHIPS)':
 C_PATH='@t6g_mb_lib.t6g(sch_1):page279_i41@pure_quanta.q_cap(chips)';

PART_NAME
 C184 'Q_CAP_0402-0.1UF,25V,10%,X7R,CH4104K1B00':;

SECTION_NUMBER 1
 '@T6G_MB_LIB.T6G(SCH_1):PAGE279_I31@PURE_QUANTA.Q_CAP(CHIPS)':
 C_PATH='@t6g_mb_lib.t6g(sch_1):page279_i31@pure_quanta.q_cap(chips)';

PART_NAME
 C2561 'Q_CAP_DIFFBUS_C0201-DIFF BUS_0.22UF,6.3V,20%,X6S,SP_CH4221MEE01':;

SECTION_NUMBER 1
 '@T6G_MB_LIB.T6G(SCH_1):PAGE172_I17@PURE_QUANTA.Q_CAP_DIFFBUS(CHIPS)':
 C_PATH='@t6g_mb_lib.t6g(sch_1):page172_i17@pure_quanta.q_cap_diffbus(chips)';

PART_NAME
 C2560 'Q_CAP_DIFFBUS_C0201-DIFF BUS_0.22UF,6.3V,20%,X6S,SP_CH4221MEE01':;

SECTION_NUMBER 1
 '@T6G_MB_LIB.T6G(SCH_1):PAGE172_I19@PURE_QUANTA.Q_CAP_DIFFBUS(CHIPS)':
 C_PATH='@t6g_mb_lib.t6g(sch_1):page172_i19@pure_quanta.q_cap_diffbus(chips)';

PART_NAME
 C2559 'Q_CAP_DIFFBUS_C0201-DIFF BUS_0.22UF,6.3V,20%,X6S,SP_CH4221MEE01':;

SECTION_NUMBER 1
 '@T6G_MB_LIB.T6G(SCH_1):PAGE172_I69@PURE_QUANTA.Q_CAP_DIFFBUS(CHIPS)':
 C_PATH='@t6g_mb_lib.t6g(sch_1):page172_i69@pure_quanta.q_cap_diffbus(chips)';

PART_NAME
 C2558 'Q_CAP_DIFFBUS_C0201-DIFF BUS_0.22UF,6.3V,20%,X6S,SP_CH4221MEE01':;

SECTION_NUMBER 1
 '@T6G_MB_LIB.T6G(SCH_1):PAGE172_I71@PURE_QUANTA.Q_CAP_DIFFBUS(CHIPS)':
 C_PATH='@t6g_mb_lib.t6g(sch_1):page172_i71@pure_quanta.q_cap_diffbus(chips)';

PART_NAME
 C2557 'Q_CAP_DIFFBUS_C0201-DIFF BUS_0.22UF,6.3V,20%,X6S,SP_CH4221MEE01':;

SECTION_NUMBER 1
 '@T6G_MB_LIB.T6G(SCH_1):PAGE172_I73@PURE_QUANTA.Q_CAP_DIFFBUS(CHIPS)':
 C_PATH='@t6g_mb_lib.t6g(sch_1):page172_i73@pure_quanta.q_cap_diffbus(chips)';

PART_NAME
 C704 'Q_CAP_DIFFBUS_C0201-DIFF BUS_0.22UF,6.3V,20%,X6S,SP_CH4221MEE01':;

SECTION_NUMBER 1
 '@T6G_MB_LIB.T6G(SCH_1):PAGE172_I88@PURE_QUANTA.Q_CAP_DIFFBUS(CHIPS)':
 C_PATH='@t6g_mb_lib.t6g(sch_1):page172_i88@pure_quanta.q_cap_diffbus(chips)';

PART_NAME
 C197 'Q_CAP_DIFFBUS_C0201-DIFF BUS_0.22UF,6.3V,20%,X6S,SP_CH4221MEE01':;

SECTION_NUMBER 1
 '@T6G_MB_LIB.T6G(SCH_1):PAGE172_I37@PURE_QUANTA.Q_CAP_DIFFBUS(CHIPS)':
 C_PATH='@t6g_mb_lib.t6g(sch_1):page172_i37@pure_quanta.q_cap_diffbus(chips)';

PART_NAME
 C196 'Q_CAP_DIFFBUS_C0201-DIFF BUS_0.22UF,6.3V,20%,X6S,SP_CH4221MEE01':;

SECTION_NUMBER 1
 '@T6G_MB_LIB.T6G(SCH_1):PAGE172_I38@PURE_QUANTA.Q_CAP_DIFFBUS(CHIPS)':
 C_PATH='@t6g_mb_lib.t6g(sch_1):page172_i38@pure_quanta.q_cap_diffbus(chips)';

PART_NAME
 C195 'Q_CAP_DIFFBUS_C0201-DIFF BUS_0.22UF,6.3V,20%,X6S,SP_CH4221MEE01':;

SECTION_NUMBER 1
 '@T6G_MB_LIB.T6G(SCH_1):PAGE172_I40@PURE_QUANTA.Q_CAP_DIFFBUS(CHIPS)':
 C_PATH='@t6g_mb_lib.t6g(sch_1):page172_i40@pure_quanta.q_cap_diffbus(chips)';

PART_NAME
 C194 'Q_CAP_DIFFBUS_C0201-DIFF BUS_0.22UF,6.3V,20%,X6S,SP_CH4221MEE01':;

SECTION_NUMBER 1
 '@T6G_MB_LIB.T6G(SCH_1):PAGE172_I48@PURE_QUANTA.Q_CAP_DIFFBUS(CHIPS)':
 C_PATH='@t6g_mb_lib.t6g(sch_1):page172_i48@pure_quanta.q_cap_diffbus(chips)';

PART_NAME
 C193 'Q_CAP_DIFFBUS_C0201-DIFF BUS_0.22UF,6.3V,20%,X6S,SP_CH4221MEE01':;

SECTION_NUMBER 1
 '@T6G_MB_LIB.T6G(SCH_1):PAGE172_I50@PURE_QUANTA.Q_CAP_DIFFBUS(CHIPS)':
 C_PATH='@t6g_mb_lib.t6g(sch_1):page172_i50@pure_quanta.q_cap_diffbus(chips)';

PART_NAME
 C192 'Q_CAP_DIFFBUS_C0201-DIFF BUS_0.22UF,6.3V,20%,X6S,SP_CH4221MEE01':;

SECTION_NUMBER 1
 '@T6G_MB_LIB.T6G(SCH_1):PAGE172_I61@PURE_QUANTA.Q_CAP_DIFFBUS(CHIPS)':
 C_PATH='@t6g_mb_lib.t6g(sch_1):page172_i61@pure_quanta.q_cap_diffbus(chips)';

PART_NAME
 C191 'Q_CAP_DIFFBUS_C0201-DIFF BUS_0.22UF,6.3V,20%,X6S,SP_CH4221MEE01':;

SECTION_NUMBER 1
 '@T6G_MB_LIB.T6G(SCH_1):PAGE172_I89@PURE_QUANTA.Q_CAP_DIFFBUS(CHIPS)':
 C_PATH='@t6g_mb_lib.t6g(sch_1):page172_i89@pure_quanta.q_cap_diffbus(chips)';

PART_NAME
 C190 'Q_CAP_DIFFBUS_C0201-DIFF BUS_0.22UF,6.3V,20%,X6S,SP_CH4221MEE01':;

SECTION_NUMBER 1
 '@T6G_MB_LIB.T6G(SCH_1):PAGE172_I91@PURE_QUANTA.Q_CAP_DIFFBUS(CHIPS)':
 C_PATH='@t6g_mb_lib.t6g(sch_1):page172_i91@pure_quanta.q_cap_diffbus(chips)';

PART_NAME
 C189 'Q_CAP_DIFFBUS_C0201-DIFF BUS_0.22UF,6.3V,20%,X6S,SP_CH4221MEE01':;

SECTION_NUMBER 1
 '@T6G_MB_LIB.T6G(SCH_1):PAGE172_I36@PURE_QUANTA.Q_CAP_DIFFBUS(CHIPS)':
 C_PATH='@t6g_mb_lib.t6g(sch_1):page172_i36@pure_quanta.q_cap_diffbus(chips)';

PART_NAME
 C188 'Q_CAP_DIFFBUS_C0201-DIFF BUS_0.22UF,6.3V,20%,X6S,SP_CH4221MEE01':;

SECTION_NUMBER 1
 '@T6G_MB_LIB.T6G(SCH_1):PAGE172_I39@PURE_QUANTA.Q_CAP_DIFFBUS(CHIPS)':
 C_PATH='@t6g_mb_lib.t6g(sch_1):page172_i39@pure_quanta.q_cap_diffbus(chips)';

PART_NAME
 C187 'Q_CAP_DIFFBUS_C0201-DIFF BUS_0.22UF,6.3V,20%,X6S,SP_CH4221MEE01':;

SECTION_NUMBER 1
 '@T6G_MB_LIB.T6G(SCH_1):PAGE172_I46@PURE_QUANTA.Q_CAP_DIFFBUS(CHIPS)':
 C_PATH='@t6g_mb_lib.t6g(sch_1):page172_i46@pure_quanta.q_cap_diffbus(chips)';

PART_NAME
 C186 'Q_CAP_DIFFBUS_C0201-DIFF BUS_0.22UF,6.3V,20%,X6S,SP_CH4221MEE01':;

SECTION_NUMBER 1
 '@T6G_MB_LIB.T6G(SCH_1):PAGE172_I47@PURE_QUANTA.Q_CAP_DIFFBUS(CHIPS)':
 C_PATH='@t6g_mb_lib.t6g(sch_1):page172_i47@pure_quanta.q_cap_diffbus(chips)';

PART_NAME
 C185 'Q_CAP_DIFFBUS_C0201-DIFF BUS_0.22UF,6.3V,20%,X6S,SP_CH4221MEE01':;

SECTION_NUMBER 1
 '@T6G_MB_LIB.T6G(SCH_1):PAGE172_I49@PURE_QUANTA.Q_CAP_DIFFBUS(CHIPS)':
 C_PATH='@t6g_mb_lib.t6g(sch_1):page172_i49@pure_quanta.q_cap_diffbus(chips)';

PART_NAME
 C183 'Q_CAP_DIFFBUS_C0201-DIFF BUS_0.22UF,6.3V,20%,X6S,SP_CH4221MEE01':;

SECTION_NUMBER 1
 '@T6G_MB_LIB.T6G(SCH_1):PAGE172_I90@PURE_QUANTA.Q_CAP_DIFFBUS(CHIPS)':
 C_PATH='@t6g_mb_lib.t6g(sch_1):page172_i90@pure_quanta.q_cap_diffbus(chips)';

PART_NAME
 C182 'Q_CAP_DIFFBUS_C0201-DIFF BUS_0.22UF,6.3V,20%,X6S,SP_CH4221MEE01':;

SECTION_NUMBER 1
 '@T6G_MB_LIB.T6G(SCH_1):PAGE172_I92@PURE_QUANTA.Q_CAP_DIFFBUS(CHIPS)':
 C_PATH='@t6g_mb_lib.t6g(sch_1):page172_i92@pure_quanta.q_cap_diffbus(chips)';

PART_NAME
 C181 'Q_CAP_DIFFBUS_C0201-DIFF BUS_0.22UF,6.3V,20%,X6S,SP_CH4221MEE01':;

SECTION_NUMBER 1
 '@T6G_MB_LIB.T6G(SCH_1):PAGE172_I7@PURE_QUANTA.Q_CAP_DIFFBUS(CHIPS)':
 C_PATH='@t6g_mb_lib.t6g(sch_1):page172_i7@pure_quanta.q_cap_diffbus(chips)';

PART_NAME
 C180 'Q_CAP_DIFFBUS_C0201-DIFF BUS_0.22UF,6.3V,20%,X6S,SP_CH4221MEE01':;

SECTION_NUMBER 1
 '@T6G_MB_LIB.T6G(SCH_1):PAGE172_I8@PURE_QUANTA.Q_CAP_DIFFBUS(CHIPS)':
 C_PATH='@t6g_mb_lib.t6g(sch_1):page172_i8@pure_quanta.q_cap_diffbus(chips)';

PART_NAME
 C179 'Q_CAP_DIFFBUS_C0201-DIFF BUS_0.22UF,6.3V,20%,X6S,SP_CH4221MEE01':;

SECTION_NUMBER 1
 '@T6G_MB_LIB.T6G(SCH_1):PAGE172_I10@PURE_QUANTA.Q_CAP_DIFFBUS(CHIPS)':
 C_PATH='@t6g_mb_lib.t6g(sch_1):page172_i10@pure_quanta.q_cap_diffbus(chips)';

PART_NAME
 C178 'Q_CAP_DIFFBUS_C0201-DIFF BUS_0.22UF,6.3V,20%,X6S,SP_CH4221MEE01':;

SECTION_NUMBER 1
 '@T6G_MB_LIB.T6G(SCH_1):PAGE172_I18@PURE_QUANTA.Q_CAP_DIFFBUS(CHIPS)':
 C_PATH='@t6g_mb_lib.t6g(sch_1):page172_i18@pure_quanta.q_cap_diffbus(chips)';

PART_NAME
 C177 'Q_CAP_DIFFBUS_C0201-DIFF BUS_0.22UF,6.3V,20%,X6S,SP_CH4221MEE01':;

SECTION_NUMBER 1
 '@T6G_MB_LIB.T6G(SCH_1):PAGE172_I20@PURE_QUANTA.Q_CAP_DIFFBUS(CHIPS)':
 C_PATH='@t6g_mb_lib.t6g(sch_1):page172_i20@pure_quanta.q_cap_diffbus(chips)';

PART_NAME
 C176 'Q_CAP_DIFFBUS_C0201-DIFF BUS_0.22UF,6.3V,20%,X6S,SP_CH4221MEE01':;

SECTION_NUMBER 1
 '@T6G_MB_LIB.T6G(SCH_1):PAGE172_I62@PURE_QUANTA.Q_CAP_DIFFBUS(CHIPS)':
 C_PATH='@t6g_mb_lib.t6g(sch_1):page172_i62@pure_quanta.q_cap_diffbus(chips)';

PART_NAME
 C175 'Q_CAP_DIFFBUS_C0201-DIFF BUS_0.22UF,6.3V,20%,X6S,SP_CH4221MEE01':;

SECTION_NUMBER 1
 '@T6G_MB_LIB.T6G(SCH_1):PAGE172_I70@PURE_QUANTA.Q_CAP_DIFFBUS(CHIPS)':
 C_PATH='@t6g_mb_lib.t6g(sch_1):page172_i70@pure_quanta.q_cap_diffbus(chips)';

PART_NAME
 C174 'Q_CAP_DIFFBUS_C0201-DIFF BUS_0.22UF,6.3V,20%,X6S,SP_CH4221MEE01':;

SECTION_NUMBER 1
 '@T6G_MB_LIB.T6G(SCH_1):PAGE172_I72@PURE_QUANTA.Q_CAP_DIFFBUS(CHIPS)':
 C_PATH='@t6g_mb_lib.t6g(sch_1):page172_i72@pure_quanta.q_cap_diffbus(chips)';

PART_NAME
 C173 'Q_CAP_DIFFBUS_C0201-DIFF BUS_0.22UF,6.3V,20%,X6S,SP_CH4221MEE01':;

SECTION_NUMBER 1
 '@T6G_MB_LIB.T6G(SCH_1):PAGE172_I6@PURE_QUANTA.Q_CAP_DIFFBUS(CHIPS)':
 C_PATH='@t6g_mb_lib.t6g(sch_1):page172_i6@pure_quanta.q_cap_diffbus(chips)';

PART_NAME
 C172 'Q_CAP_DIFFBUS_C0201-DIFF BUS_0.22UF,6.3V,20%,X6S,SP_CH4221MEE01':;

SECTION_NUMBER 1
 '@T6G_MB_LIB.T6G(SCH_1):PAGE172_I9@PURE_QUANTA.Q_CAP_DIFFBUS(CHIPS)':
 C_PATH='@t6g_mb_lib.t6g(sch_1):page172_i9@pure_quanta.q_cap_diffbus(chips)';

PART_NAME
 C171 'Q_CAP_DIFFBUS_C0201-DIFF BUS_0.22UF,6.3V,20%,X6S,SP_CH4221MEE01':;

SECTION_NUMBER 1
 '@T6G_MB_LIB.T6G(SCH_1):PAGE172_I16@PURE_QUANTA.Q_CAP_DIFFBUS(CHIPS)':
 C_PATH='@t6g_mb_lib.t6g(sch_1):page172_i16@pure_quanta.q_cap_diffbus(chips)';

PART_NAME
 C170 'Q_CAP_DIFFBUS_C0201-DIFF BUS_0.22UF,6.3V,20%,X6S,SP_CH4221MEE01':;

SECTION_NUMBER 1
 '@T6G_MB_LIB.T6G(SCH_1):PAGE84_I196@PURE_QUANTA.Q_CAP_DIFFBUS(CHIPS)':
 C_PATH='@t6g_mb_lib.t6g(sch_1):page84_i196@pure_quanta.q_cap_diffbus(chips)';

PART_NAME
 C169 'Q_CAP_DIFFBUS_C0201-DIFF BUS_0.22UF,6.3V,20%,X6S,SP_CH4221MEE01':;

SECTION_NUMBER 1
 '@T6G_MB_LIB.T6G(SCH_1):PAGE84_I197@PURE_QUANTA.Q_CAP_DIFFBUS(CHIPS)':
 C_PATH='@t6g_mb_lib.t6g(sch_1):page84_i197@pure_quanta.q_cap_diffbus(chips)';

PART_NAME
 C168 'Q_CAP_DIFFBUS_C0201-DIFF BUS_0.22UF,6.3V,20%,X6S,SP_CH4221MEE01':;

SECTION_NUMBER 1
 '@T6G_MB_LIB.T6G(SCH_1):PAGE84_I195@PURE_QUANTA.Q_CAP_DIFFBUS(CHIPS)':
 C_PATH='@t6g_mb_lib.t6g(sch_1):page84_i195@pure_quanta.q_cap_diffbus(chips)';

PART_NAME
 C167 'Q_CAP_DIFFBUS_C0201-DIFF BUS_0.22UF,6.3V,20%,X6S,SP_CH4221MEE01':;

SECTION_NUMBER 1
 '@T6G_MB_LIB.T6G(SCH_1):PAGE84_I194@PURE_QUANTA.Q_CAP_DIFFBUS(CHIPS)':
 C_PATH='@t6g_mb_lib.t6g(sch_1):page84_i194@pure_quanta.q_cap_diffbus(chips)';

PART_NAME
 C166 'Q_CAP_DIFFBUS_C0201-DIFF BUS_0.22UF,6.3V,20%,X6S,SP_CH4221MEE01':;

SECTION_NUMBER 1
 '@T6G_MB_LIB.T6G(SCH_1):PAGE84_I192@PURE_QUANTA.Q_CAP_DIFFBUS(CHIPS)':
 C_PATH='@t6g_mb_lib.t6g(sch_1):page84_i192@pure_quanta.q_cap_diffbus(chips)';

PART_NAME
 C165 'Q_CAP_DIFFBUS_C0201-DIFF BUS_0.22UF,6.3V,20%,X6S,SP_CH4221MEE01':;

SECTION_NUMBER 1
 '@T6G_MB_LIB.T6G(SCH_1):PAGE84_I193@PURE_QUANTA.Q_CAP_DIFFBUS(CHIPS)':
 C_PATH='@t6g_mb_lib.t6g(sch_1):page84_i193@pure_quanta.q_cap_diffbus(chips)';

PART_NAME
 C164 'Q_CAP_DIFFBUS_C0201-DIFF BUS_0.22UF,6.3V,20%,X6S,SP_CH4221MEE01':;

SECTION_NUMBER 1
 '@T6G_MB_LIB.T6G(SCH_1):PAGE84_I105@PURE_QUANTA.Q_CAP_DIFFBUS(CHIPS)':
 C_PATH='@t6g_mb_lib.t6g(sch_1):page84_i105@pure_quanta.q_cap_diffbus(chips)';

PART_NAME
 C163 'Q_CAP_DIFFBUS_C0201-DIFF BUS_0.22UF,6.3V,20%,X6S,SP_CH4221MEE01':;

SECTION_NUMBER 1
 '@T6G_MB_LIB.T6G(SCH_1):PAGE84_I190@PURE_QUANTA.Q_CAP_DIFFBUS(CHIPS)':
 C_PATH='@t6g_mb_lib.t6g(sch_1):page84_i190@pure_quanta.q_cap_diffbus(chips)';

PART_NAME
 C162 'Q_CAP_DIFFBUS_C0201-DIFF BUS_0.22UF,6.3V,20%,X6S,SP_CH4221MEE01':;

SECTION_NUMBER 1
 '@T6G_MB_LIB.T6G(SCH_1):PAGE84_I191@PURE_QUANTA.Q_CAP_DIFFBUS(CHIPS)':
 C_PATH='@t6g_mb_lib.t6g(sch_1):page84_i191@pure_quanta.q_cap_diffbus(chips)';

PART_NAME
 C161 'Q_CAP_DIFFBUS_C0201-DIFF BUS_0.22UF,6.3V,20%,X6S,SP_CH4221MEE01':;

SECTION_NUMBER 1
 '@T6G_MB_LIB.T6G(SCH_1):PAGE84_I181@PURE_QUANTA.Q_CAP_DIFFBUS(CHIPS)':
 C_PATH='@t6g_mb_lib.t6g(sch_1):page84_i181@pure_quanta.q_cap_diffbus(chips)';

PART_NAME
 C160 'Q_CAP_DIFFBUS_C0201-DIFF BUS_0.22UF,6.3V,20%,X6S,SP_CH4221MEE01':;

SECTION_NUMBER 1
 '@T6G_MB_LIB.T6G(SCH_1):PAGE84_I172@PURE_QUANTA.Q_CAP_DIFFBUS(CHIPS)':
 C_PATH='@t6g_mb_lib.t6g(sch_1):page84_i172@pure_quanta.q_cap_diffbus(chips)';

PART_NAME
 C159 'Q_CAP_DIFFBUS_C0201-DIFF BUS_0.22UF,6.3V,20%,X6S,SP_CH4221MEE01':;

SECTION_NUMBER 1
 '@T6G_MB_LIB.T6G(SCH_1):PAGE84_I173@PURE_QUANTA.Q_CAP_DIFFBUS(CHIPS)':
 C_PATH='@t6g_mb_lib.t6g(sch_1):page84_i173@pure_quanta.q_cap_diffbus(chips)';

PART_NAME
 C158 'Q_CAP_DIFFBUS_C0201-DIFF BUS_0.22UF,6.3V,20%,X6S,SP_CH4221MEE01':;

SECTION_NUMBER 1
 '@T6G_MB_LIB.T6G(SCH_1):PAGE84_I170@PURE_QUANTA.Q_CAP_DIFFBUS(CHIPS)':
 C_PATH='@t6g_mb_lib.t6g(sch_1):page84_i170@pure_quanta.q_cap_diffbus(chips)';

PART_NAME
 C157 'Q_CAP_DIFFBUS_C0201-DIFF BUS_0.22UF,6.3V,20%,X6S,SP_CH4221MEE01':;

SECTION_NUMBER 1
 '@T6G_MB_LIB.T6G(SCH_1):PAGE84_I171@PURE_QUANTA.Q_CAP_DIFFBUS(CHIPS)':
 C_PATH='@t6g_mb_lib.t6g(sch_1):page84_i171@pure_quanta.q_cap_diffbus(chips)';

PART_NAME
 C156 'Q_CAP_DIFFBUS_C0201-DIFF BUS_0.22UF,6.3V,20%,X6S,SP_CH4221MEE01':;

SECTION_NUMBER 1
 '@T6G_MB_LIB.T6G(SCH_1):PAGE84_I169@PURE_QUANTA.Q_CAP_DIFFBUS(CHIPS)':
 C_PATH='@t6g_mb_lib.t6g(sch_1):page84_i169@pure_quanta.q_cap_diffbus(chips)';

PART_NAME
 C155 'Q_CAP_DIFFBUS_C0201-DIFF BUS_0.22UF,6.3V,20%,X6S,SP_CH4221MEE01':;

SECTION_NUMBER 1
 '@T6G_MB_LIB.T6G(SCH_1):PAGE84_I168@PURE_QUANTA.Q_CAP_DIFFBUS(CHIPS)':
 C_PATH='@t6g_mb_lib.t6g(sch_1):page84_i168@pure_quanta.q_cap_diffbus(chips)';

PART_NAME
 C154 'Q_CAP_DIFFBUS_C0201-DIFF BUS_0.22UF,6.3V,20%,X6S,SP_CH4221MEE01':;

SECTION_NUMBER 1
 '@T6G_MB_LIB.T6G(SCH_1):PAGE84_I141@PURE_QUANTA.Q_CAP_DIFFBUS(CHIPS)':
 C_PATH='@t6g_mb_lib.t6g(sch_1):page84_i141@pure_quanta.q_cap_diffbus(chips)';

PART_NAME
 C153 'Q_CAP_DIFFBUS_C0201-DIFF BUS_0.22UF,6.3V,20%,X6S,SP_CH4221MEE01':;

SECTION_NUMBER 1
 '@T6G_MB_LIB.T6G(SCH_1):PAGE84_I142@PURE_QUANTA.Q_CAP_DIFFBUS(CHIPS)':
 C_PATH='@t6g_mb_lib.t6g(sch_1):page84_i142@pure_quanta.q_cap_diffbus(chips)';

PART_NAME
 C152 'Q_CAP_DIFFBUS_C0201-DIFF BUS_0.22UF,6.3V,20%,X6S,SP_CH4221MEE01':;

SECTION_NUMBER 1
 '@T6G_MB_LIB.T6G(SCH_1):PAGE84_I140@PURE_QUANTA.Q_CAP_DIFFBUS(CHIPS)':
 C_PATH='@t6g_mb_lib.t6g(sch_1):page84_i140@pure_quanta.q_cap_diffbus(chips)';

PART_NAME
 C151 'Q_CAP_DIFFBUS_C0201-DIFF BUS_0.22UF,6.3V,20%,X6S,SP_CH4221MEE01':;

SECTION_NUMBER 1
 '@T6G_MB_LIB.T6G(SCH_1):PAGE84_I139@PURE_QUANTA.Q_CAP_DIFFBUS(CHIPS)':
 C_PATH='@t6g_mb_lib.t6g(sch_1):page84_i139@pure_quanta.q_cap_diffbus(chips)';

PART_NAME
 C150 'Q_CAP_DIFFBUS_C0201-DIFF BUS_0.22UF,6.3V,20%,X6S,SP_CH4221MEE01':;

SECTION_NUMBER 1
 '@T6G_MB_LIB.T6G(SCH_1):PAGE84_I138@PURE_QUANTA.Q_CAP_DIFFBUS(CHIPS)':
 C_PATH='@t6g_mb_lib.t6g(sch_1):page84_i138@pure_quanta.q_cap_diffbus(chips)';

PART_NAME
 C149 'Q_CAP_DIFFBUS_C0201-DIFF BUS_0.22UF,6.3V,20%,X6S,SP_CH4221MEE01':;

SECTION_NUMBER 1
 '@T6G_MB_LIB.T6G(SCH_1):PAGE84_I137@PURE_QUANTA.Q_CAP_DIFFBUS(CHIPS)':
 C_PATH='@t6g_mb_lib.t6g(sch_1):page84_i137@pure_quanta.q_cap_diffbus(chips)';

PART_NAME
 C148 'Q_CAP_DIFFBUS_C0201-DIFF BUS_0.22UF,6.3V,20%,X6S,SP_CH4221MEE01':;

SECTION_NUMBER 1
 '@T6G_MB_LIB.T6G(SCH_1):PAGE84_I136@PURE_QUANTA.Q_CAP_DIFFBUS(CHIPS)':
 C_PATH='@t6g_mb_lib.t6g(sch_1):page84_i136@pure_quanta.q_cap_diffbus(chips)';

PART_NAME
 C147 'Q_CAP_DIFFBUS_C0201-DIFF BUS_0.22UF,6.3V,20%,X6S,SP_CH4221MEE01':;

SECTION_NUMBER 1
 '@T6G_MB_LIB.T6G(SCH_1):PAGE84_I133@PURE_QUANTA.Q_CAP_DIFFBUS(CHIPS)':
 C_PATH='@t6g_mb_lib.t6g(sch_1):page84_i133@pure_quanta.q_cap_diffbus(chips)';

PART_NAME
 C146 'Q_CAP_DIFFBUS_C0201-DIFF BUS_0.22UF,6.3V,20%,X6S,SP_CH4221MEE01':;

SECTION_NUMBER 1
 '@T6G_MB_LIB.T6G(SCH_1):PAGE84_I134@PURE_QUANTA.Q_CAP_DIFFBUS(CHIPS)':
 C_PATH='@t6g_mb_lib.t6g(sch_1):page84_i134@pure_quanta.q_cap_diffbus(chips)';

PART_NAME
 C145 'Q_CAP_DIFFBUS_C0201-DIFF BUS_0.22UF,6.3V,20%,X6S,SP_CH4221MEE01':;

SECTION_NUMBER 1
 '@T6G_MB_LIB.T6G(SCH_1):PAGE84_I135@PURE_QUANTA.Q_CAP_DIFFBUS(CHIPS)':
 C_PATH='@t6g_mb_lib.t6g(sch_1):page84_i135@pure_quanta.q_cap_diffbus(chips)';

PART_NAME
 C144 'Q_CAP_DIFFBUS_C0201-DIFF BUS_0.22UF,6.3V,20%,X6S,SP_CH4221MEE01':;

SECTION_NUMBER 1
 '@T6G_MB_LIB.T6G(SCH_1):PAGE84_I122@PURE_QUANTA.Q_CAP_DIFFBUS(CHIPS)':
 C_PATH='@t6g_mb_lib.t6g(sch_1):page84_i122@pure_quanta.q_cap_diffbus(chips)';

PART_NAME
 C143 'Q_CAP_DIFFBUS_C0201-DIFF BUS_0.22UF,6.3V,20%,X6S,SP_CH4221MEE01':;

SECTION_NUMBER 1
 '@T6G_MB_LIB.T6G(SCH_1):PAGE84_I121@PURE_QUANTA.Q_CAP_DIFFBUS(CHIPS)':
 C_PATH='@t6g_mb_lib.t6g(sch_1):page84_i121@pure_quanta.q_cap_diffbus(chips)';

PART_NAME
 C142 'Q_CAP_DIFFBUS_C0201-DIFF BUS_0.22UF,6.3V,20%,X6S,SP_CH4221MEE01':;

SECTION_NUMBER 1
 '@T6G_MB_LIB.T6G(SCH_1):PAGE84_I120@PURE_QUANTA.Q_CAP_DIFFBUS(CHIPS)':
 C_PATH='@t6g_mb_lib.t6g(sch_1):page84_i120@pure_quanta.q_cap_diffbus(chips)';

PART_NAME
 C141 'Q_CAP_DIFFBUS_C0201-DIFF BUS_0.22UF,6.3V,20%,X6S,SP_CH4221MEE01':;

SECTION_NUMBER 1
 '@T6G_MB_LIB.T6G(SCH_1):PAGE84_I119@PURE_QUANTA.Q_CAP_DIFFBUS(CHIPS)':
 C_PATH='@t6g_mb_lib.t6g(sch_1):page84_i119@pure_quanta.q_cap_diffbus(chips)';

PART_NAME
 C140 'Q_CAP_DIFFBUS_C0201-DIFF BUS_0.22UF,6.3V,20%,X6S,SP_CH4221MEE01':;

SECTION_NUMBER 1
 '@T6G_MB_LIB.T6G(SCH_1):PAGE84_I118@PURE_QUANTA.Q_CAP_DIFFBUS(CHIPS)':
 C_PATH='@t6g_mb_lib.t6g(sch_1):page84_i118@pure_quanta.q_cap_diffbus(chips)';

PART_NAME
 C139 'Q_CAP_DIFFBUS_C0201-DIFF BUS_0.22UF,6.3V,20%,X6S,SP_CH4221MEE01':;

SECTION_NUMBER 1
 '@T6G_MB_LIB.T6G(SCH_1):PAGE84_I117@PURE_QUANTA.Q_CAP_DIFFBUS(CHIPS)':
 C_PATH='@t6g_mb_lib.t6g(sch_1):page84_i117@pure_quanta.q_cap_diffbus(chips)';

PART_NAME
 C605 'Q_CAP_DIFFBUS_C0201-DIFF BUS_0.22UF,6.3V,20%,X6S,SP_CH4221MEE01':;

SECTION_NUMBER 1
 '@T6G_MB_LIB.T6G(SCH_1):PAGE168_I164@PURE_QUANTA.Q_CAP_DIFFBUS(CHIPS)':
 C_PATH='@t6g_mb_lib.t6g(sch_1):page168_i164@pure_quanta.q_cap_diffbus(chips)';

PART_NAME
 C604 'Q_CAP_DIFFBUS_C0201-DIFF BUS_0.22UF,6.3V,20%,X6S,SP_CH4221MEE01':;

SECTION_NUMBER 1
 '@T6G_MB_LIB.T6G(SCH_1):PAGE168_I157@PURE_QUANTA.Q_CAP_DIFFBUS(CHIPS)':
 C_PATH='@t6g_mb_lib.t6g(sch_1):page168_i157@pure_quanta.q_cap_diffbus(chips)';

PART_NAME
 C603 'Q_CAP_DIFFBUS_C0201-DIFF BUS_0.22UF,6.3V,20%,X6S,SP_CH4221MEE01':;

SECTION_NUMBER 1
 '@T6G_MB_LIB.T6G(SCH_1):PAGE168_I156@PURE_QUANTA.Q_CAP_DIFFBUS(CHIPS)':
 C_PATH='@t6g_mb_lib.t6g(sch_1):page168_i156@pure_quanta.q_cap_diffbus(chips)';

PART_NAME
 C602 'Q_CAP_DIFFBUS_C0201-DIFF BUS_0.22UF,6.3V,20%,X6S,SP_CH4221MEE01':;

SECTION_NUMBER 1
 '@T6G_MB_LIB.T6G(SCH_1):PAGE168_I155@PURE_QUANTA.Q_CAP_DIFFBUS(CHIPS)':
 C_PATH='@t6g_mb_lib.t6g(sch_1):page168_i155@pure_quanta.q_cap_diffbus(chips)';

PART_NAME
 C601 'Q_CAP_DIFFBUS_C0201-DIFF BUS_0.22UF,6.3V,20%,X6S,SP_CH4221MEE01':;

SECTION_NUMBER 1
 '@T6G_MB_LIB.T6G(SCH_1):PAGE168_I154@PURE_QUANTA.Q_CAP_DIFFBUS(CHIPS)':
 C_PATH='@t6g_mb_lib.t6g(sch_1):page168_i154@pure_quanta.q_cap_diffbus(chips)';

PART_NAME
 C600 'Q_CAP_DIFFBUS_C0201-DIFF BUS_0.22UF,6.3V,20%,X6S,SP_CH4221MEE01':;

SECTION_NUMBER 1
 '@T6G_MB_LIB.T6G(SCH_1):PAGE168_I153@PURE_QUANTA.Q_CAP_DIFFBUS(CHIPS)':
 C_PATH='@t6g_mb_lib.t6g(sch_1):page168_i153@pure_quanta.q_cap_diffbus(chips)';

PART_NAME
 C599 'Q_CAP_DIFFBUS_C0201-DIFF BUS_0.22UF,6.3V,20%,X6S,SP_CH4221MEE01':;

SECTION_NUMBER 1
 '@T6G_MB_LIB.T6G(SCH_1):PAGE168_I150@PURE_QUANTA.Q_CAP_DIFFBUS(CHIPS)':
 C_PATH='@t6g_mb_lib.t6g(sch_1):page168_i150@pure_quanta.q_cap_diffbus(chips)';

PART_NAME
 C598 'Q_CAP_DIFFBUS_C0201-DIFF BUS_0.22UF,6.3V,20%,X6S,SP_CH4221MEE01':;

SECTION_NUMBER 1
 '@T6G_MB_LIB.T6G(SCH_1):PAGE168_I149@PURE_QUANTA.Q_CAP_DIFFBUS(CHIPS)':
 C_PATH='@t6g_mb_lib.t6g(sch_1):page168_i149@pure_quanta.q_cap_diffbus(chips)';

PART_NAME
 C597 'Q_CAP_DIFFBUS_C0201-DIFF BUS_0.22UF,6.3V,20%,X6S,SP_CH4221MEE01':;

SECTION_NUMBER 1
 '@T6G_MB_LIB.T6G(SCH_1):PAGE168_I163@PURE_QUANTA.Q_CAP_DIFFBUS(CHIPS)':
 C_PATH='@t6g_mb_lib.t6g(sch_1):page168_i163@pure_quanta.q_cap_diffbus(chips)';

PART_NAME
 C596 'Q_CAP_DIFFBUS_C0201-DIFF BUS_0.22UF,6.3V,20%,X6S,SP_CH4221MEE01':;

SECTION_NUMBER 1
 '@T6G_MB_LIB.T6G(SCH_1):PAGE168_I162@PURE_QUANTA.Q_CAP_DIFFBUS(CHIPS)':
 C_PATH='@t6g_mb_lib.t6g(sch_1):page168_i162@pure_quanta.q_cap_diffbus(chips)';

PART_NAME
 C331 'Q_CAP_DIFFBUS_C0201-DIFF BUS_0.22UF,6.3V,20%,X6S,SP_CH4221MEE01':;

SECTION_NUMBER 1
 '@T6G_MB_LIB.T6G(SCH_1):PAGE168_I161@PURE_QUANTA.Q_CAP_DIFFBUS(CHIPS)':
 C_PATH='@t6g_mb_lib.t6g(sch_1):page168_i161@pure_quanta.q_cap_diffbus(chips)';

PART_NAME
 C319 'Q_CAP_DIFFBUS_C0201-DIFF BUS_0.22UF,6.3V,20%,X6S,SP_CH4221MEE01':;

SECTION_NUMBER 1
 '@T6G_MB_LIB.T6G(SCH_1):PAGE168_I160@PURE_QUANTA.Q_CAP_DIFFBUS(CHIPS)':
 C_PATH='@t6g_mb_lib.t6g(sch_1):page168_i160@pure_quanta.q_cap_diffbus(chips)';

PART_NAME
 C211 'Q_CAP_DIFFBUS_C0201-DIFF BUS_0.22UF,6.3V,20%,X6S,SP_CH4221MEE01':;

SECTION_NUMBER 1
 '@T6G_MB_LIB.T6G(SCH_1):PAGE168_I159@PURE_QUANTA.Q_CAP_DIFFBUS(CHIPS)':
 C_PATH='@t6g_mb_lib.t6g(sch_1):page168_i159@pure_quanta.q_cap_diffbus(chips)';

PART_NAME
 C210 'Q_CAP_DIFFBUS_C0201-DIFF BUS_0.22UF,6.3V,20%,X6S,SP_CH4221MEE01':;

SECTION_NUMBER 1
 '@T6G_MB_LIB.T6G(SCH_1):PAGE168_I158@PURE_QUANTA.Q_CAP_DIFFBUS(CHIPS)':
 C_PATH='@t6g_mb_lib.t6g(sch_1):page168_i158@pure_quanta.q_cap_diffbus(chips)';

PART_NAME
 C209 'Q_CAP_DIFFBUS_C0201-DIFF BUS_0.22UF,6.3V,20%,X6S,SP_CH4221MEE01':;

SECTION_NUMBER 1
 '@T6G_MB_LIB.T6G(SCH_1):PAGE168_I152@PURE_QUANTA.Q_CAP_DIFFBUS(CHIPS)':
 C_PATH='@t6g_mb_lib.t6g(sch_1):page168_i152@pure_quanta.q_cap_diffbus(chips)';

PART_NAME
 C208 'Q_CAP_DIFFBUS_C0201-DIFF BUS_0.22UF,6.3V,20%,X6S,SP_CH4221MEE01':;

SECTION_NUMBER 1
 '@T6G_MB_LIB.T6G(SCH_1):PAGE168_I151@PURE_QUANTA.Q_CAP_DIFFBUS(CHIPS)':
 C_PATH='@t6g_mb_lib.t6g(sch_1):page168_i151@pure_quanta.q_cap_diffbus(chips)';

PART_NAME
 C207 'Q_CAP_DIFFBUS_C0201-DIFF BUS_0.22UF,6.3V,20%,X6S,SP_CH4221MEE01':;

SECTION_NUMBER 1
 '@T6G_MB_LIB.T6G(SCH_1):PAGE168_I135@PURE_QUANTA.Q_CAP_DIFFBUS(CHIPS)':
 C_PATH='@t6g_mb_lib.t6g(sch_1):page168_i135@pure_quanta.q_cap_diffbus(chips)';

PART_NAME
 C206 'Q_CAP_DIFFBUS_C0201-DIFF BUS_0.22UF,6.3V,20%,X6S,SP_CH4221MEE01':;

SECTION_NUMBER 1
 '@T6G_MB_LIB.T6G(SCH_1):PAGE168_I140@PURE_QUANTA.Q_CAP_DIFFBUS(CHIPS)':
 C_PATH='@t6g_mb_lib.t6g(sch_1):page168_i140@pure_quanta.q_cap_diffbus(chips)';

PART_NAME
 C205 'Q_CAP_DIFFBUS_C0201-DIFF BUS_0.22UF,6.3V,20%,X6S,SP_CH4221MEE01':;

SECTION_NUMBER 1
 '@T6G_MB_LIB.T6G(SCH_1):PAGE168_I141@PURE_QUANTA.Q_CAP_DIFFBUS(CHIPS)':
 C_PATH='@t6g_mb_lib.t6g(sch_1):page168_i141@pure_quanta.q_cap_diffbus(chips)';

PART_NAME
 C204 'Q_CAP_DIFFBUS_C0201-DIFF BUS_0.22UF,6.3V,20%,X6S,SP_CH4221MEE01':;

SECTION_NUMBER 1
 '@T6G_MB_LIB.T6G(SCH_1):PAGE168_I142@PURE_QUANTA.Q_CAP_DIFFBUS(CHIPS)':
 C_PATH='@t6g_mb_lib.t6g(sch_1):page168_i142@pure_quanta.q_cap_diffbus(chips)';

PART_NAME
 C203 'Q_CAP_DIFFBUS_C0201-DIFF BUS_0.22UF,6.3V,20%,X6S,SP_CH4221MEE01':;

SECTION_NUMBER 1
 '@T6G_MB_LIB.T6G(SCH_1):PAGE168_I148@PURE_QUANTA.Q_CAP_DIFFBUS(CHIPS)':
 C_PATH='@t6g_mb_lib.t6g(sch_1):page168_i148@pure_quanta.q_cap_diffbus(chips)';

PART_NAME
 C202 'Q_CAP_DIFFBUS_C0201-DIFF BUS_0.22UF,6.3V,20%,X6S,SP_CH4221MEE01':;

SECTION_NUMBER 1
 '@T6G_MB_LIB.T6G(SCH_1):PAGE168_I143@PURE_QUANTA.Q_CAP_DIFFBUS(CHIPS)':
 C_PATH='@t6g_mb_lib.t6g(sch_1):page168_i143@pure_quanta.q_cap_diffbus(chips)';

PART_NAME
 C201 'Q_CAP_DIFFBUS_C0201-DIFF BUS_0.22UF,6.3V,20%,X6S,SP_CH4221MEE01':;

SECTION_NUMBER 1
 '@T6G_MB_LIB.T6G(SCH_1):PAGE168_I133@PURE_QUANTA.Q_CAP_DIFFBUS(CHIPS)':
 C_PATH='@t6g_mb_lib.t6g(sch_1):page168_i133@pure_quanta.q_cap_diffbus(chips)';

PART_NAME
 C138 'Q_CAP_DIFFBUS_C0201-DIFF BUS_0.22UF,6.3V,20%,X6S,SP_CH4221MEE01':;

SECTION_NUMBER 1
 '@T6G_MB_LIB.T6G(SCH_1):PAGE168_I147@PURE_QUANTA.Q_CAP_DIFFBUS(CHIPS)':
 C_PATH='@t6g_mb_lib.t6g(sch_1):page168_i147@pure_quanta.q_cap_diffbus(chips)';

PART_NAME
 C137 'Q_CAP_DIFFBUS_C0201-DIFF BUS_0.22UF,6.3V,20%,X6S,SP_CH4221MEE01':;

SECTION_NUMBER 1
 '@T6G_MB_LIB.T6G(SCH_1):PAGE168_I136@PURE_QUANTA.Q_CAP_DIFFBUS(CHIPS)':
 C_PATH='@t6g_mb_lib.t6g(sch_1):page168_i136@pure_quanta.q_cap_diffbus(chips)';

PART_NAME
 C136 'Q_CAP_DIFFBUS_C0201-DIFF BUS_0.22UF,6.3V,20%,X6S,SP_CH4221MEE01':;

SECTION_NUMBER 1
 '@T6G_MB_LIB.T6G(SCH_1):PAGE168_I137@PURE_QUANTA.Q_CAP_DIFFBUS(CHIPS)':
 C_PATH='@t6g_mb_lib.t6g(sch_1):page168_i137@pure_quanta.q_cap_diffbus(chips)';

PART_NAME
 C135 'Q_CAP_DIFFBUS_C0201-DIFF BUS_0.22UF,6.3V,20%,X6S,SP_CH4221MEE01':;

SECTION_NUMBER 1
 '@T6G_MB_LIB.T6G(SCH_1):PAGE168_I138@PURE_QUANTA.Q_CAP_DIFFBUS(CHIPS)':
 C_PATH='@t6g_mb_lib.t6g(sch_1):page168_i138@pure_quanta.q_cap_diffbus(chips)';

PART_NAME
 C134 'Q_CAP_DIFFBUS_C0201-DIFF BUS_0.22UF,6.3V,20%,X6S,SP_CH4221MEE01':;

SECTION_NUMBER 1
 '@T6G_MB_LIB.T6G(SCH_1):PAGE168_I139@PURE_QUANTA.Q_CAP_DIFFBUS(CHIPS)':
 C_PATH='@t6g_mb_lib.t6g(sch_1):page168_i139@pure_quanta.q_cap_diffbus(chips)';

PART_NAME
 C133 'Q_CAP_DIFFBUS_C0201-DIFF BUS_0.22UF,6.3V,20%,X6S,SP_CH4221MEE01':;

SECTION_NUMBER 1
 '@T6G_MB_LIB.T6G(SCH_1):PAGE168_I134@PURE_QUANTA.Q_CAP_DIFFBUS(CHIPS)':
 C_PATH='@t6g_mb_lib.t6g(sch_1):page168_i134@pure_quanta.q_cap_diffbus(chips)';

PART_NAME
 C132 'Q_CAP_DIFFBUS_C0201-DIFF BUS_0.22UF,6.3V,20%,X6S,SP_CH4221MEE01':;

SECTION_NUMBER 1
 '@T6G_MB_LIB.T6G(SCH_1):PAGE168_I144@PURE_QUANTA.Q_CAP_DIFFBUS(CHIPS)':
 C_PATH='@t6g_mb_lib.t6g(sch_1):page168_i144@pure_quanta.q_cap_diffbus(chips)';

PART_NAME
 C131 'Q_CAP_DIFFBUS_C0201-DIFF BUS_0.22UF,6.3V,20%,X6S,SP_CH4221MEE01':;

SECTION_NUMBER 1
 '@T6G_MB_LIB.T6G(SCH_1):PAGE168_I145@PURE_QUANTA.Q_CAP_DIFFBUS(CHIPS)':
 C_PATH='@t6g_mb_lib.t6g(sch_1):page168_i145@pure_quanta.q_cap_diffbus(chips)';

PART_NAME
 C130 'Q_CAP_DIFFBUS_C0201-DIFF BUS_0.22UF,6.3V,20%,X6S,SP_CH4221MEE01':;

SECTION_NUMBER 1
 '@T6G_MB_LIB.T6G(SCH_1):PAGE168_I146@PURE_QUANTA.Q_CAP_DIFFBUS(CHIPS)':
 C_PATH='@t6g_mb_lib.t6g(sch_1):page168_i146@pure_quanta.q_cap_diffbus(chips)';

PART_NAME
 U212 'SN74LVC1G14DBVR_SMLF-SN74LVC1G14DBVR,IC,AL001G14009':;

SECTION_NUMBER 1
 '@T6G_MB_LIB.T6G(SCH_1):PAGE194_I58@PURE_QUANTA.SN74LVC1G14DBVR(CHIPS)':
 C_PATH='@t6g_mb_lib.t6g(sch_1):page194_i58@pure_quanta.sn74lvc1g14dbvr(chips)';

PART_NAME
 U211 'SN74LVC1G14DBVR_SMLF-SN74LVC1G14DBVR,IC,AL001G14009':;

SECTION_NUMBER 1
 '@T6G_MB_LIB.T6G(SCH_1):PAGE194_I45@PURE_QUANTA.SN74LVC1G14DBVR(CHIPS)':
 C_PATH='@t6g_mb_lib.t6g(sch_1):page194_i45@pure_quanta.sn74lvc1g14dbvr(chips)';

PART_NAME
 U65 'SN74HC595BRWN-SN74HC595BRWN,SMLF,IC,AL000595002':;

SECTION_NUMBER 1
 '@T6G_MB_LIB.T6G(SCH_1):PAGE194_I39@PURE_QUANTA.SN74HC595BRWN(CHIPS)':
 C_PATH='@t6g_mb_lib.t6g(sch_1):page194_i39@pure_quanta.sn74hc595brwn(chips)';

PART_NAME
 U47 'SN74HC595BRWN-SN74HC595BRWN,SMLF,IC,AL000595002':;

SECTION_NUMBER 1
 '@T6G_MB_LIB.T6G(SCH_1):PAGE194_I23@PURE_QUANTA.SN74HC595BRWN(CHIPS)':
 C_PATH='@t6g_mb_lib.t6g(sch_1):page194_i23@pure_quanta.sn74hc595brwn(chips)';

PART_NAME
 R3675 'Q_RES_0402LF-49.9     ,1%  ,1/16W,CHIP,CS04992FB31':;

SECTION_NUMBER 1
 '@T6G_MB_LIB.T6G(SCH_1):PAGE194_I82@PURE_QUANTA.Q_RES(CHIPS)':
 C_PATH='@t6g_mb_lib.t6g(sch_1):page194_i82@pure_quanta.q_res(chips)';

PART_NAME
 R3665 'Q_RES_0402LF-49.9     ,1%  ,1/16W,CHIP,CS04992FB31':;

SECTION_NUMBER 1
 '@T6G_MB_LIB.T6G(SCH_1):PAGE194_I80@PURE_QUANTA.Q_RES(CHIPS)':
 C_PATH='@t6g_mb_lib.t6g(sch_1):page194_i80@pure_quanta.q_res(chips)';

PART_NAME
 R2173 'Q_RES_0402LF-49.9     ,1%  ,1/16W,EMPTY,CS04992FB31':;

SECTION_NUMBER 1
 '@T6G_MB_LIB.T6G(SCH_1):PAGE194_I71@PURE_QUANTA.Q_RES(CHIPS)':
 C_PATH='@t6g_mb_lib.t6g(sch_1):page194_i71@pure_quanta.q_res(chips)';

PART_NAME
 R2172 'Q_RES_0402LF-49.9     ,1%  ,1/16W,EMPTY,CS04992FB31':;

SECTION_NUMBER 1
 '@T6G_MB_LIB.T6G(SCH_1):PAGE194_I79@PURE_QUANTA.Q_RES(CHIPS)':
 C_PATH='@t6g_mb_lib.t6g(sch_1):page194_i79@pure_quanta.q_res(chips)';

PART_NAME
 R1712 'Q_RES_0402LF-2K,1%,1/16W,CHIP,TMP_QCS22002FB19':;

SECTION_NUMBER 1
 '@T6G_MB_LIB.T6G(SCH_1):PAGE194_I54@PURE_QUANTA.Q_RES(CHIPS)':
 C_PATH='@t6g_mb_lib.t6g(sch_1):page194_i54@pure_quanta.q_res(chips)';

PART_NAME
 R807 'Q_RES_0402LF-0,5%,1/16W,EMPTY,CS00002JB38':;

SECTION_NUMBER 1
 '@T6G_MB_LIB.T6G(SCH_1):PAGE194_I46@PURE_QUANTA.Q_RES(CHIPS)':
 C_PATH='@t6g_mb_lib.t6g(sch_1):page194_i46@pure_quanta.q_res(chips)';

PART_NAME
 R649 'Q_RES_0402LF-0,5%,1/16W,EMPTY,CS00002JB38':;

SECTION_NUMBER 1
 '@T6G_MB_LIB.T6G(SCH_1):PAGE194_I59@PURE_QUANTA.Q_RES(CHIPS)':
 C_PATH='@t6g_mb_lib.t6g(sch_1):page194_i59@pure_quanta.q_res(chips)';

PART_NAME
 C2715 'Q_CAP_0402-0.1UF,25V,10%,X7R,CH4104K1B00':;

SECTION_NUMBER 1
 '@T6G_MB_LIB.T6G(SCH_1):PAGE194_I61@PURE_QUANTA.Q_CAP(CHIPS)':
 C_PATH='@t6g_mb_lib.t6g(sch_1):page194_i61@pure_quanta.q_cap(chips)';

PART_NAME
 C2714 'Q_CAP_0402-0.1UF,25V,10%,X7R,CH4104K1B00':;

SECTION_NUMBER 1
 '@T6G_MB_LIB.T6G(SCH_1):PAGE194_I48@PURE_QUANTA.Q_CAP(CHIPS)':
 C_PATH='@t6g_mb_lib.t6g(sch_1):page194_i48@pure_quanta.q_cap(chips)';

PART_NAME
 C1176 'Q_CAP_0402-0.1UF,25V,10%,X7R,CH4104K1B00':;

SECTION_NUMBER 1
 '@T6G_MB_LIB.T6G(SCH_1):PAGE194_I37@PURE_QUANTA.Q_CAP(CHIPS)':
 C_PATH='@t6g_mb_lib.t6g(sch_1):page194_i37@pure_quanta.q_cap(chips)';

PART_NAME
 C334 'Q_CAP_0402-22PF,50V,5%,NPO,TMP_QCH02206JB08':;

SECTION_NUMBER 1
 '@T6G_MB_LIB.T6G(SCH_1):PAGE194_I73@PURE_QUANTA.Q_CAP(CHIPS)':
 C_PATH='@t6g_mb_lib.t6g(sch_1):page194_i73@pure_quanta.q_cap(chips)';

PART_NAME
 C124 'Q_CAP_0402-22PF,50V,5%,NPO,TMP_QCH02206JB08':;

SECTION_NUMBER 1
 '@T6G_MB_LIB.T6G(SCH_1):PAGE194_I76@PURE_QUANTA.Q_CAP(CHIPS)':
 C_PATH='@t6g_mb_lib.t6g(sch_1):page194_i76@pure_quanta.q_cap(chips)';

PART_NAME
 C121 'Q_CAP_0402-0.1UF,25V,10%,X7R,CH4104K1B00':;

SECTION_NUMBER 1
 '@T6G_MB_LIB.T6G(SCH_1):PAGE194_I52@PURE_QUANTA.Q_CAP(CHIPS)':
 C_PATH='@t6g_mb_lib.t6g(sch_1):page194_i52@pure_quanta.q_cap(chips)';

PART_NAME
 U105 '9QXL2001BNHGI8-9QXL2001BNHGI8,SMLF,IC,AJ020010003':;

SECTION_NUMBER 1
 '@T6G_MB_LIB.T6G(SCH_1):PAGE206_I570@PURE_QUANTA.9QXL2001BNHGI8(CHIPS)':
 C_PATH='@s6q_mb_lib.s6q(sch_1):page206_i570@pure_quanta.\9qxl2001bnhgi8\(chips)~
';

PART_NAME
 R3749 'Q_RES_0402LF-2K,5%,1/16W,CHIP,TMP_QCS22002JB29':;

SECTION_NUMBER 1
 '@T6G_MB_LIB.T6G(SCH_1):PAGE206_I598@PURE_QUANTA.Q_RES(CHIPS)':
 C_PATH='@t6g_mb_lib.t6g(sch_1):page206_i598@pure_quanta.q_res(chips)';

PART_NAME
 R3714 'Q_RES_0402LF-4.7K,5%,1/16W,CHIP,TMP_QCS24702JB38':;

SECTION_NUMBER 1
 '@T6G_MB_LIB.T6G(SCH_1):PAGE206_I596@PURE_QUANTA.Q_RES(CHIPS)':
 C_PATH='@t6g_mb_lib.t6g(sch_1):page206_i596@pure_quanta.q_res(chips)';

PART_NAME
 R3713 'Q_RES_0402LF-4.7K,5%,1/16W,CHIP,TMP_QCS24702JB38':;

SECTION_NUMBER 1
 '@T6G_MB_LIB.T6G(SCH_1):PAGE206_I594@PURE_QUANTA.Q_RES(CHIPS)':
 C_PATH='@t6g_mb_lib.t6g(sch_1):page206_i594@pure_quanta.q_res(chips)';

PART_NAME
 R467 'Q_RES_0402LF-49.9,1%,1/16W,CHIP,CS04992FB07':
;

SECTION_NUMBER 1
 '@T6G_MB_LIB.T6G(SCH_1):PAGE206_I580@PURE_QUANTA.Q_RES(CHIPS)':
 C_PATH='@t6g_mb_lib.t6g(sch_1):page206_i580@pure_quanta.q_res(chips)';

PART_NAME
 R466 'Q_RES_0603LF-2.2,1%,1/10W,CHIP,CS-2203F902':
;

SECTION_NUMBER 1
 '@T6G_MB_LIB.T6G(SCH_1):PAGE206_I471@PURE_QUANTA.Q_RES(CHIPS)':
 C_PATH='@t6g_mb_lib.t6g(sch_1):page206_i471@pure_quanta.q_res(chips)';

PART_NAME
 R465 'Q_RES_0603LF-2.2,1%,1/10W,CHIP,CS-2203F902':
;

SECTION_NUMBER 1
 '@T6G_MB_LIB.T6G(SCH_1):PAGE206_I470@PURE_QUANTA.Q_RES(CHIPS)':
 C_PATH='@t6g_mb_lib.t6g(sch_1):page206_i470@pure_quanta.q_res(chips)';

PART_NAME
 R464 'Q_RES_0402LF-4.7K,5%,1/16W,EMPTY,TMP_QCS24702JB38':
;

SECTION_NUMBER 1
 '@T6G_MB_LIB.T6G(SCH_1):PAGE206_I444@PURE_QUANTA.Q_RES(CHIPS)':
 C_PATH='@t6g_mb_lib.t6g(sch_1):page206_i444@pure_quanta.q_res(chips)';

PART_NAME
 R463 'Q_RES_0402LF-4.7K,5%,1/16W,CHIP,TMP_QCS24702JB38':
;

SECTION_NUMBER 1
 '@T6G_MB_LIB.T6G(SCH_1):PAGE206_I441@PURE_QUANTA.Q_RES(CHIPS)':
 C_PATH='@t6g_mb_lib.t6g(sch_1):page206_i441@pure_quanta.q_res(chips)';

PART_NAME
 R455 'Q_RES_0402LF-4.7K,5%,1/16W,CHIP,TMP_QCS24702JB38':
;

SECTION_NUMBER 1
 '@T6G_MB_LIB.T6G(SCH_1):PAGE206_I447@PURE_QUANTA.Q_RES(CHIPS)':
 C_PATH='@t6g_mb_lib.t6g(sch_1):page206_i447@pure_quanta.q_res(chips)';

PART_NAME
 R202 'Q_RES_0402LF-4.7K,5%,1/16W,CHIP,TMP_QCS24702JB38':
;

SECTION_NUMBER 1
 '@T6G_MB_LIB.T6G(SCH_1):PAGE206_I442@PURE_QUANTA.Q_RES(CHIPS)':
 C_PATH='@t6g_mb_lib.t6g(sch_1):page206_i442@pure_quanta.q_res(chips)';

PART_NAME
 R172 'Q_RES_0402LF-4.7K,5%,1/16W,EMPTY,TMP_QCS24702JB38':
;

SECTION_NUMBER 1
 '@T6G_MB_LIB.T6G(SCH_1):PAGE206_I443@PURE_QUANTA.Q_RES(CHIPS)':
 C_PATH='@t6g_mb_lib.t6g(sch_1):page206_i443@pure_quanta.q_res(chips)';

PART_NAME
 R112 'Q_RES_0402LF-4.7K,5%,1/16W,EMPTY,TMP_QCS24702JB38':
;

SECTION_NUMBER 1
 '@T6G_MB_LIB.T6G(SCH_1):PAGE206_I448@PURE_QUANTA.Q_RES(CHIPS)':
 C_PATH='@t6g_mb_lib.t6g(sch_1):page206_i448@pure_quanta.q_res(chips)';

PART_NAME
 L88 'Q_INDUCTOR_SMLF-BLM21PG331SN1D,IND,CX1PG331001':;

SECTION_NUMBER 1
 '@T6G_MB_LIB.T6G(SCH_1):PAGE206_I453@PURE_QUANTA.Q_INDUCTOR(CHIPS)':
 C_PATH='@t6g_mb_lib.t6g(sch_1):page206_i453@pure_quanta.q_inductor(chips)';

PART_NAME
 L87 'Q_INDUCTOR_SMLF-BLM21PG331SN1D,IND,CX1PG331001':;

SECTION_NUMBER 1
 '@T6G_MB_LIB.T6G(SCH_1):PAGE206_I451@PURE_QUANTA.Q_INDUCTOR(CHIPS)':
 C_PATH='@t6g_mb_lib.t6g(sch_1):page206_i451@pure_quanta.q_inductor(chips)';

PART_NAME
 C129 'Q_CAP_0402-0.1UF,25V,10%,X7R,CH4104K1B00':
;

SECTION_NUMBER 1
 '@T6G_MB_LIB.T6G(SCH_1):PAGE206_I481@PURE_QUANTA.Q_CAP(CHIPS)':
 C_PATH='@t6g_mb_lib.t6g(sch_1):page206_i481@pure_quanta.q_cap(chips)';

PART_NAME
 C128 'Q_CAP_0402-0.1UF,25V,10%,X7R,CH4104K1B00':
;

SECTION_NUMBER 1
 '@T6G_MB_LIB.T6G(SCH_1):PAGE206_I479@PURE_QUANTA.Q_CAP(CHIPS)':
 C_PATH='@t6g_mb_lib.t6g(sch_1):page206_i479@pure_quanta.q_cap(chips)';

PART_NAME
 C127 'Q_CAP_0402-0.1UF,25V,10%,X7R,CH4104K1B00':
;

SECTION_NUMBER 1
 '@T6G_MB_LIB.T6G(SCH_1):PAGE206_I477@PURE_QUANTA.Q_CAP(CHIPS)':
 C_PATH='@t6g_mb_lib.t6g(sch_1):page206_i477@pure_quanta.q_cap(chips)';

PART_NAME
 C126 'Q_CAP_0402-0.1UF,25V,10%,X7R,CH4104K1B00':
;

SECTION_NUMBER 1
 '@T6G_MB_LIB.T6G(SCH_1):PAGE206_I459@PURE_QUANTA.Q_CAP(CHIPS)':
 C_PATH='@t6g_mb_lib.t6g(sch_1):page206_i459@pure_quanta.q_cap(chips)';

PART_NAME
 C125 'Q_CAP_0402-0.1UF,25V,10%,X7R,CH4104K1B00':
;

SECTION_NUMBER 1
 '@T6G_MB_LIB.T6G(SCH_1):PAGE206_I475@PURE_QUANTA.Q_CAP(CHIPS)':
 C_PATH='@t6g_mb_lib.t6g(sch_1):page206_i475@pure_quanta.q_cap(chips)';

PART_NAME
 C123 'Q_CAP_0402-0.1UF,25V,10%,X7R,CH4104K1B00':
;

SECTION_NUMBER 1
 '@T6G_MB_LIB.T6G(SCH_1):PAGE206_I529@PURE_QUANTA.Q_CAP(CHIPS)':
 C_PATH='@t6g_mb_lib.t6g(sch_1):page206_i529@pure_quanta.q_cap(chips)';

PART_NAME
 C122 'Q_CAP_C0603-10UF,6.3V,20%,X6S,CH6101ME900':
;

SECTION_NUMBER 1
 '@T6G_MB_LIB.T6G(SCH_1):PAGE206_I457@PURE_QUANTA.Q_CAP(CHIPS)':
 C_PATH='@t6g_mb_lib.t6g(sch_1):page206_i457@pure_quanta.q_cap(chips)';

PART_NAME
 C120 'Q_CAP_C0603-10UF,6.3V,20%,X6S,CH6101ME900':
;

SECTION_NUMBER 1
 '@T6G_MB_LIB.T6G(SCH_1):PAGE206_I472@PURE_QUANTA.Q_CAP(CHIPS)':
 C_PATH='@t6g_mb_lib.t6g(sch_1):page206_i472@pure_quanta.q_cap(chips)';

PART_NAME
 C119 'Q_CAP_C0603-10UF,6.3V,20%,X6S,CH6101ME900':
;

SECTION_NUMBER 1
 '@T6G_MB_LIB.T6G(SCH_1):PAGE206_I476@PURE_QUANTA.Q_CAP(CHIPS)':
 C_PATH='@t6g_mb_lib.t6g(sch_1):page206_i476@pure_quanta.q_cap(chips)';

PART_NAME
 U103 '9ZXL0851EKILFT-9ZXL0851EKILFT,SMLF,IC,AL000851006':;

SECTION_NUMBER 1
 '@T6G_MB_LIB.T6G(SCH_1):PAGE208_I246@PURE_QUANTA.9ZXL0851EKILFT(CHIPS)':
 C_PATH='@s6q_mb_lib.s6q(sch_1):page208_i246@pure_quanta.\9zxl0851ekilft\(chips)~
';

PART_NAME
 U102 '9ZXL0851EKILFT-9ZXL0851EKILFT,SMLF,IC,AL000851006':;

SECTION_NUMBER 1
 '@T6G_MB_LIB.T6G(SCH_1):PAGE208_I225@PURE_QUANTA.9ZXL0851EKILFT(CHIPS)':
 C_PATH='@s6q_mb_lib.s6q(sch_1):page208_i225@pure_quanta.\9zxl0851ekilft\(chips)~
';

PART_NAME
 R3710 'Q_RES_0402LF-4.7K,5%,1/16W,CHIP,TMP_QCS24702JB38':
;

SECTION_NUMBER 1
 '@T6G_MB_LIB.T6G(SCH_1):PAGE208_I343@PURE_QUANTA.Q_RES(CHIPS)':
 C_PATH='@t6g_mb_lib.t6g(sch_1):page208_i343@pure_quanta.q_res(chips)';

PART_NAME
 R3703 'Q_RES_0402LF-4.7K,5%,1/16W,CHIP,TMP_QCS24702JB38':
;

SECTION_NUMBER 1
 '@T6G_MB_LIB.T6G(SCH_1):PAGE208_I341@PURE_QUANTA.Q_RES(CHIPS)':
 C_PATH='@t6g_mb_lib.t6g(sch_1):page208_i341@pure_quanta.q_res(chips)';

PART_NAME
 R1163 'Q_RES_0402LF-49.9,1%,1/16W,CHIP,CS04992FB07':
;

SECTION_NUMBER 1
 '@T6G_MB_LIB.T6G(SCH_1):PAGE208_I218@PURE_QUANTA.Q_RES(CHIPS)':
 C_PATH='@t6g_mb_lib.t6g(sch_1):page208_i218@pure_quanta.q_res(chips)';

PART_NAME
 R1162 'Q_RES_0402LF-49.9,1%,1/16W,CHIP,CS04992FB07':
;

SECTION_NUMBER 1
 '@T6G_MB_LIB.T6G(SCH_1):PAGE208_I171@PURE_QUANTA.Q_RES(CHIPS)':
 C_PATH='@t6g_mb_lib.t6g(sch_1):page208_i171@pure_quanta.q_res(chips)';

PART_NAME
 R565 'Q_RES_0402LF-4.7K,5%,1/16W,CHIP,TMP_QCS24702JB38':;

SECTION_NUMBER 1
 '@T6G_MB_LIB.T6G(SCH_1):PAGE208_I170@PURE_QUANTA.Q_RES(CHIPS)':
 C_PATH='@t6g_mb_lib.t6g(sch_1):page208_i170@pure_quanta.q_res(chips)';

PART_NAME
 R564 'Q_RES_0402LF-4.7K,5%,1/16W,CHIP,TMP_QCS24702JB38':;

SECTION_NUMBER 1
 '@T6G_MB_LIB.T6G(SCH_1):PAGE208_I221@PURE_QUANTA.Q_RES(CHIPS)':
 C_PATH='@t6g_mb_lib.t6g(sch_1):page208_i221@pure_quanta.q_res(chips)';

PART_NAME
 R554 'Q_RES_0402LF-4.7K,5%,1/16W,CHIP,TMP_QCS24702JB38':;

SECTION_NUMBER 1
 '@T6G_MB_LIB.T6G(SCH_1):PAGE208_I169@PURE_QUANTA.Q_RES(CHIPS)':
 C_PATH='@t6g_mb_lib.t6g(sch_1):page208_i169@pure_quanta.q_res(chips)';

PART_NAME
 R553 'Q_RES_0402LF-4.7K,5%,1/16W,CHIP,TMP_QCS24702JB38':;

SECTION_NUMBER 1
 '@T6G_MB_LIB.T6G(SCH_1):PAGE208_I219@PURE_QUANTA.Q_RES(CHIPS)':
 C_PATH='@t6g_mb_lib.t6g(sch_1):page208_i219@pure_quanta.q_res(chips)';

PART_NAME
 R382 'Q_RES_0402LF-10K,5%,1/16W,CHIP,TMP_QCS31002JB28':
;

SECTION_NUMBER 1
 '@T6G_MB_LIB.T6G(SCH_1):PAGE208_I163@PURE_QUANTA.Q_RES(CHIPS)':
 C_PATH='@t6g_mb_lib.t6g(sch_1):page208_i163@pure_quanta.q_res(chips)';

PART_NAME
 R381 'Q_RES_0402LF-10K,5%,1/16W,CHIP,TMP_QCS31002JB28':
;

SECTION_NUMBER 1
 '@T6G_MB_LIB.T6G(SCH_1):PAGE208_I164@PURE_QUANTA.Q_RES(CHIPS)':
 C_PATH='@t6g_mb_lib.t6g(sch_1):page208_i164@pure_quanta.q_res(chips)';

PART_NAME
 R380 'Q_RES_0402LF-10K,5%,1/16W,CHIP,TMP_QCS31002JB28':
;

SECTION_NUMBER 1
 '@T6G_MB_LIB.T6G(SCH_1):PAGE208_I205@PURE_QUANTA.Q_RES(CHIPS)':
 C_PATH='@t6g_mb_lib.t6g(sch_1):page208_i205@pure_quanta.q_res(chips)';

PART_NAME
 R379 'Q_RES_0402LF-10K,5%,1/16W,CHIP,TMP_QCS31002JB28':
;

SECTION_NUMBER 1
 '@T6G_MB_LIB.T6G(SCH_1):PAGE208_I206@PURE_QUANTA.Q_RES(CHIPS)':
 C_PATH='@t6g_mb_lib.t6g(sch_1):page208_i206@pure_quanta.q_res(chips)';

PART_NAME
 R86 'Q_RES_0603LF-1,5%,1/10W,CHIP,TMP_QCS-1003J913':;

SECTION_NUMBER 1
 '@T6G_MB_LIB.T6G(SCH_1):PAGE208_I201@PURE_QUANTA.Q_RES(CHIPS)':
 C_PATH='@t6g_mb_lib.t6g(sch_1):page208_i201@pure_quanta.q_res(chips)';

PART_NAME
 R85 'Q_RES_0603LF-1,5%,1/10W,CHIP,TMP_QCS-1003J913':;

SECTION_NUMBER 1
 '@T6G_MB_LIB.T6G(SCH_1):PAGE208_I157@PURE_QUANTA.Q_RES(CHIPS)':
 C_PATH='@t6g_mb_lib.t6g(sch_1):page208_i157@pure_quanta.q_res(chips)';

PART_NAME
 L94 'Q_INDUCTOR_SMLF-GMLB-201209-0330P-N8(330/3A),IND,CX090330000':;

SECTION_NUMBER 1
 '@T6G_MB_LIB.T6G(SCH_1):PAGE208_I137@PURE_QUANTA.Q_INDUCTOR(CHIPS)':
 C_PATH='@t6g_mb_lib.t6g(sch_1):page208_i137@pure_quanta.q_inductor(chips)';

PART_NAME
 L93 'Q_INDUCTOR_SMLF-GMLB-201209-0330P-N8(330/3A),IND,CX090330000':;

SECTION_NUMBER 1
 '@T6G_MB_LIB.T6G(SCH_1):PAGE208_I141@PURE_QUANTA.Q_INDUCTOR(CHIPS)':
 C_PATH='@t6g_mb_lib.t6g(sch_1):page208_i141@pure_quanta.q_inductor(chips)';

PART_NAME
 C806 'Q_CAP_C0402-0.1UF,16V,10%,X7R,CH4103K1B08':;

SECTION_NUMBER 1
 '@T6G_MB_LIB.T6G(SCH_1):PAGE208_I193@PURE_QUANTA.Q_CAP(CHIPS)':
 C_PATH='@t6g_mb_lib.t6g(sch_1):page208_i193@pure_quanta.q_cap(chips)';

PART_NAME
 C805 'Q_CAP_C0402-0.1UF,16V,10%,X7R,CH4103K1B08':;

SECTION_NUMBER 1
 '@T6G_MB_LIB.T6G(SCH_1):PAGE208_I149@PURE_QUANTA.Q_CAP(CHIPS)':
 C_PATH='@t6g_mb_lib.t6g(sch_1):page208_i149@pure_quanta.q_cap(chips)';

PART_NAME
 C802 'Q_CAP_C0402-0.1UF,16V,10%,X7R,CH4103K1B08':;

SECTION_NUMBER 1
 '@T6G_MB_LIB.T6G(SCH_1):PAGE208_I213@PURE_QUANTA.Q_CAP(CHIPS)':
 C_PATH='@t6g_mb_lib.t6g(sch_1):page208_i213@pure_quanta.q_cap(chips)';

PART_NAME
 C757 'Q_CAP_C0402-0.1UF,16V,10%,X7R,CH4103K1B08':;

SECTION_NUMBER 1
 '@T6G_MB_LIB.T6G(SCH_1):PAGE208_I177@PURE_QUANTA.Q_CAP(CHIPS)':
 C_PATH='@t6g_mb_lib.t6g(sch_1):page208_i177@pure_quanta.q_cap(chips)';

PART_NAME
 C756 'Q_CAP_C0402-0.1UF,16V,10%,X7R,CH4103K1B08':;

SECTION_NUMBER 1
 '@T6G_MB_LIB.T6G(SCH_1):PAGE208_I211@PURE_QUANTA.Q_CAP(CHIPS)':
 C_PATH='@t6g_mb_lib.t6g(sch_1):page208_i211@pure_quanta.q_cap(chips)';

PART_NAME
 C755 'Q_CAP_C0402-0.1UF,16V,10%,X7R,CH4103K1B08':;

SECTION_NUMBER 1
 '@T6G_MB_LIB.T6G(SCH_1):PAGE208_I175@PURE_QUANTA.Q_CAP(CHIPS)':
 C_PATH='@t6g_mb_lib.t6g(sch_1):page208_i175@pure_quanta.q_cap(chips)';

PART_NAME
 C754 'Q_CAP_C0402-1UF,25V,10%,X6S,CH5104KEB02':;

SECTION_NUMBER 1
 '@T6G_MB_LIB.T6G(SCH_1):PAGE208_I203@PURE_QUANTA.Q_CAP(CHIPS)':
 C_PATH='@t6g_mb_lib.t6g(sch_1):page208_i203@pure_quanta.q_cap(chips)';

PART_NAME
 C753 'Q_CAP_C0402-1UF,25V,10%,X6S,CH5104KEB02':;

SECTION_NUMBER 1
 '@T6G_MB_LIB.T6G(SCH_1):PAGE208_I161@PURE_QUANTA.Q_CAP(CHIPS)':
 C_PATH='@t6g_mb_lib.t6g(sch_1):page208_i161@pure_quanta.q_cap(chips)';

PART_NAME
 C752 'Q_CAP_C0402-0.1UF,16V,10%,X7R,CH4103K1B08':;

SECTION_NUMBER 1
 '@T6G_MB_LIB.T6G(SCH_1):PAGE208_I200@PURE_QUANTA.Q_CAP(CHIPS)':
 C_PATH='@t6g_mb_lib.t6g(sch_1):page208_i200@pure_quanta.q_cap(chips)';

PART_NAME
 C751 'Q_CAP_C0402-0.1UF,16V,10%,X7R,CH4103K1B08':;

SECTION_NUMBER 1
 '@T6G_MB_LIB.T6G(SCH_1):PAGE208_I159@PURE_QUANTA.Q_CAP(CHIPS)':
 C_PATH='@t6g_mb_lib.t6g(sch_1):page208_i159@pure_quanta.q_cap(chips)';

PART_NAME
 C750 'Q_CAP_C0402-0.1UF,16V,10%,X7R,CH4103K1B08':;

SECTION_NUMBER 1
 '@T6G_MB_LIB.T6G(SCH_1):PAGE208_I197@PURE_QUANTA.Q_CAP(CHIPS)':
 C_PATH='@t6g_mb_lib.t6g(sch_1):page208_i197@pure_quanta.q_cap(chips)';

PART_NAME
 C749 'Q_CAP_C0402-0.1UF,16V,10%,X7R,CH4103K1B08':;

SECTION_NUMBER 1
 '@T6G_MB_LIB.T6G(SCH_1):PAGE208_I154@PURE_QUANTA.Q_CAP(CHIPS)':
 C_PATH='@t6g_mb_lib.t6g(sch_1):page208_i154@pure_quanta.q_cap(chips)';

PART_NAME
 C748 'Q_CAP_C0402-0.1UF,16V,10%,X7R,CH4103K1B08':;

SECTION_NUMBER 1
 '@T6G_MB_LIB.T6G(SCH_1):PAGE208_I189@PURE_QUANTA.Q_CAP(CHIPS)':
 C_PATH='@t6g_mb_lib.t6g(sch_1):page208_i189@pure_quanta.q_cap(chips)';

PART_NAME
 C747 'Q_CAP_C0402-0.1UF,16V,10%,X7R,CH4103K1B08':;

SECTION_NUMBER 1
 '@T6G_MB_LIB.T6G(SCH_1):PAGE208_I153@PURE_QUANTA.Q_CAP(CHIPS)':
 C_PATH='@t6g_mb_lib.t6g(sch_1):page208_i153@pure_quanta.q_cap(chips)';

PART_NAME
 C746 'Q_CAP_C0402-0.1UF,16V,10%,X7R,CH4103K1B08':;

SECTION_NUMBER 1
 '@T6G_MB_LIB.T6G(SCH_1):PAGE208_I187@PURE_QUANTA.Q_CAP(CHIPS)':
 C_PATH='@t6g_mb_lib.t6g(sch_1):page208_i187@pure_quanta.q_cap(chips)';

PART_NAME
 C745 'Q_CAP_C0402-0.1UF,16V,10%,X7R,CH4103K1B08':;

SECTION_NUMBER 1
 '@T6G_MB_LIB.T6G(SCH_1):PAGE208_I146@PURE_QUANTA.Q_CAP(CHIPS)':
 C_PATH='@t6g_mb_lib.t6g(sch_1):page208_i146@pure_quanta.q_cap(chips)';

PART_NAME
 C744 'Q_CAP_C0402-0.1UF,16V,10%,X7R,CH4103K1B08':;

SECTION_NUMBER 1
 '@T6G_MB_LIB.T6G(SCH_1):PAGE208_I195@PURE_QUANTA.Q_CAP(CHIPS)':
 C_PATH='@t6g_mb_lib.t6g(sch_1):page208_i195@pure_quanta.q_cap(chips)';

PART_NAME
 C743 'Q_CAP_C0402-0.1UF,16V,10%,X7R,CH4103K1B08':;

SECTION_NUMBER 1
 '@T6G_MB_LIB.T6G(SCH_1):PAGE208_I151@PURE_QUANTA.Q_CAP(CHIPS)':
 C_PATH='@t6g_mb_lib.t6g(sch_1):page208_i151@pure_quanta.q_cap(chips)';

PART_NAME
 C679 'Q_CAP_C0402-0.1UF,16V,10%,X7R,CH4103K1B08':;

SECTION_NUMBER 1
 '@T6G_MB_LIB.T6G(SCH_1):PAGE208_I185@PURE_QUANTA.Q_CAP(CHIPS)':
 C_PATH='@t6g_mb_lib.t6g(sch_1):page208_i185@pure_quanta.q_cap(chips)';

PART_NAME
 C595 'Q_CAP_C0402-0.1UF,16V,10%,X7R,CH4103K1B08':;

SECTION_NUMBER 1
 '@T6G_MB_LIB.T6G(SCH_1):PAGE208_I145@PURE_QUANTA.Q_CAP(CHIPS)':
 C_PATH='@t6g_mb_lib.t6g(sch_1):page208_i145@pure_quanta.q_cap(chips)';

PART_NAME
 C594 'Q_CAP_C0402-0.1UF,16V,10%,X7R,CH4103K1B08':;

SECTION_NUMBER 1
 '@T6G_MB_LIB.T6G(SCH_1):PAGE208_I183@PURE_QUANTA.Q_CAP(CHIPS)':
 C_PATH='@t6g_mb_lib.t6g(sch_1):page208_i183@pure_quanta.q_cap(chips)';

PART_NAME
 C591 'Q_CAP_C0402-0.1UF,16V,10%,X7R,CH4103K1B08':;

SECTION_NUMBER 1
 '@T6G_MB_LIB.T6G(SCH_1):PAGE208_I191@PURE_QUANTA.Q_CAP(CHIPS)':
 C_PATH='@t6g_mb_lib.t6g(sch_1):page208_i191@pure_quanta.q_cap(chips)';

PART_NAME
 C589 'Q_CAP_C0402-0.1UF,16V,10%,X7R,CH4103K1B08':;

SECTION_NUMBER 1
 '@T6G_MB_LIB.T6G(SCH_1):PAGE208_I131@PURE_QUANTA.Q_CAP(CHIPS)':
 C_PATH='@t6g_mb_lib.t6g(sch_1):page208_i131@pure_quanta.q_cap(chips)';

PART_NAME
 C588 'Q_CAP_C0402-0.1UF,16V,10%,X7R,CH4103K1B08':;

SECTION_NUMBER 1
 '@T6G_MB_LIB.T6G(SCH_1):PAGE208_I135@PURE_QUANTA.Q_CAP(CHIPS)':
 C_PATH='@t6g_mb_lib.t6g(sch_1):page208_i135@pure_quanta.q_cap(chips)';

PART_NAME
 C587 'Q_CAP_C0402-10UF,4V,20%,X6S,CH610KMEB09':;

SECTION_NUMBER 1
 '@T6G_MB_LIB.T6G(SCH_1):PAGE208_I143@PURE_QUANTA.Q_CAP(CHIPS)':
 C_PATH='@t6g_mb_lib.t6g(sch_1):page208_i143@pure_quanta.q_cap(chips)';

PART_NAME
 C586 'Q_CAP_C0402-10UF,4V,20%,X6S,CH610KMEB09':;

SECTION_NUMBER 1
 '@T6G_MB_LIB.T6G(SCH_1):PAGE208_I134@PURE_QUANTA.Q_CAP(CHIPS)':
 C_PATH='@t6g_mb_lib.t6g(sch_1):page208_i134@pure_quanta.q_cap(chips)';

PART_NAME
 C585 'Q_CAP_C0402-1UF,25V,10%,X6S,CH5104KEB02':;

SECTION_NUMBER 1
 '@T6G_MB_LIB.T6G(SCH_1):PAGE208_I139@PURE_QUANTA.Q_CAP(CHIPS)':
 C_PATH='@t6g_mb_lib.t6g(sch_1):page208_i139@pure_quanta.q_cap(chips)';

PART_NAME
 C118 'Q_CAP_C0402-1UF,25V,10%,X6S,CH5104KEB02':;

SECTION_NUMBER 1
 '@T6G_MB_LIB.T6G(SCH_1):PAGE208_I129@PURE_QUANTA.Q_CAP(CHIPS)':
 C_PATH='@t6g_mb_lib.t6g(sch_1):page208_i129@pure_quanta.q_cap(chips)';

PART_NAME
 U12 'PCA9546APWR-PCA9546APWR,SMLF,IC,AL09546AK01':;

SECTION_NUMBER 1
 '@T6G_MB_LIB.T6G(SCH_1):PAGE207_I617@PURE_QUANTA.PCA9546APWR(CHIPS)':
 C_PATH='@t6g_mb_lib.t6g(sch_1):page207_i617@pure_quanta.pca9546apwr(chips)';

PART_NAME
 R3751 'Q_RES_0402LF-10K,1%,1/16W,CHIP,TMP_QCS31002FB26':;

SECTION_NUMBER 1
 '@T6G_MB_LIB.T6G(SCH_1):PAGE207_I647@PURE_QUANTA.Q_RES(CHIPS)':
 C_PATH='@t6g_mb_lib.t6g(sch_1):page207_i647@pure_quanta.q_res(chips)';

PART_NAME
 R3750 'Q_RES_0402LF-10K,1%,1/16W,CHIP,TMP_QCS31002FB26':;

SECTION_NUMBER 1
 '@T6G_MB_LIB.T6G(SCH_1):PAGE207_I652@PURE_QUANTA.Q_RES(CHIPS)':
 C_PATH='@t6g_mb_lib.t6g(sch_1):page207_i652@pure_quanta.q_res(chips)';

PART_NAME
 R3535 'Q_RES_0402LF-1K,1%,1/16W,CHIP,TMP_QCS21002FB24':;

SECTION_NUMBER 1
 '@T6G_MB_LIB.T6G(SCH_1):PAGE207_I597@PURE_QUANTA.Q_RES(CHIPS)':
 C_PATH='@t6g_mb_lib.t6g(sch_1):page207_i597@pure_quanta.q_res(chips)';

PART_NAME
 R3534 'Q_RES_0402LF-10K,1%,1/16W,EMPTY,TMP_QCS31002FB26':;

SECTION_NUMBER 1
 '@T6G_MB_LIB.T6G(SCH_1):PAGE207_I601@PURE_QUANTA.Q_RES(CHIPS)':
 C_PATH='@t6g_mb_lib.t6g(sch_1):page207_i601@pure_quanta.q_res(chips)';

PART_NAME
 R657 'Q_RES_0402LF-10K,1%,1/16W,CHIP,TMP_QCS31002FB26':;

SECTION_NUMBER 1
 '@T6G_MB_LIB.T6G(SCH_1):PAGE207_I634@PURE_QUANTA.Q_RES(CHIPS)':
 C_PATH='@t6g_mb_lib.t6g(sch_1):page207_i634@pure_quanta.q_res(chips)';

PART_NAME
 R552 'Q_RES_0402LF-33,5%,1/16W,CHIP,CS03302JB29':;

SECTION_NUMBER 1
 '@T6G_MB_LIB.T6G(SCH_1):PAGE207_I636@PURE_QUANTA.Q_RES(CHIPS)':
 C_PATH='@t6g_mb_lib.t6g(sch_1):page207_i636@pure_quanta.q_res(chips)';

PART_NAME
 R551 'Q_RES_0402LF-0,5%,1/16W,CHIP,CS00002JB38':;

SECTION_NUMBER 1
 '@T6G_MB_LIB.T6G(SCH_1):PAGE207_I635@PURE_QUANTA.Q_RES(CHIPS)':
 C_PATH='@t6g_mb_lib.t6g(sch_1):page207_i635@pure_quanta.q_res(chips)';

PART_NAME
 R550 'Q_RES_0402LF-33,5%,1/16W,CHIP,CS03302JB29':;

SECTION_NUMBER 1
 '@T6G_MB_LIB.T6G(SCH_1):PAGE207_I638@PURE_QUANTA.Q_RES(CHIPS)':
 C_PATH='@t6g_mb_lib.t6g(sch_1):page207_i638@pure_quanta.q_res(chips)';

PART_NAME
 R549 'Q_RES_0402LF-0,5%,1/16W,CHIP,CS00002JB38':;

SECTION_NUMBER 1
 '@T6G_MB_LIB.T6G(SCH_1):PAGE207_I637@PURE_QUANTA.Q_RES(CHIPS)':
 C_PATH='@t6g_mb_lib.t6g(sch_1):page207_i637@pure_quanta.q_res(chips)';

PART_NAME
 R532 'Q_RES_0402LF-33,5%,1/16W,CHIP,CS03302JB29':;

SECTION_NUMBER 1
 '@T6G_MB_LIB.T6G(SCH_1):PAGE207_I644@PURE_QUANTA.Q_RES(CHIPS)':
 C_PATH='@t6g_mb_lib.t6g(sch_1):page207_i644@pure_quanta.q_res(chips)';

PART_NAME
 R531 'Q_RES_0402LF-0,5%,1/16W,CHIP,CS00002JB38':;

SECTION_NUMBER 1
 '@T6G_MB_LIB.T6G(SCH_1):PAGE207_I641@PURE_QUANTA.Q_RES(CHIPS)':
 C_PATH='@t6g_mb_lib.t6g(sch_1):page207_i641@pure_quanta.q_res(chips)';

PART_NAME
 R530 'Q_RES_0402LF-1K,1%,1/16W,CHIP,TMP_QCS21002FB24':;

SECTION_NUMBER 1
 '@T6G_MB_LIB.T6G(SCH_1):PAGE207_I600@PURE_QUANTA.Q_RES(CHIPS)':
 C_PATH='@t6g_mb_lib.t6g(sch_1):page207_i600@pure_quanta.q_res(chips)';

PART_NAME
 R529 'Q_RES_0402LF-10K,1%,1/16W,EMPTY,TMP_QCS31002FB26':;

SECTION_NUMBER 1
 '@T6G_MB_LIB.T6G(SCH_1):PAGE207_I604@PURE_QUANTA.Q_RES(CHIPS)':
 C_PATH='@t6g_mb_lib.t6g(sch_1):page207_i604@pure_quanta.q_res(chips)';

PART_NAME
 R458 'Q_RES_0402LF-1K,1%,1/16W,CHIP,TMP_QCS21002FB24':;

SECTION_NUMBER 1
 '@T6G_MB_LIB.T6G(SCH_1):PAGE207_I598@PURE_QUANTA.Q_RES(CHIPS)':
 C_PATH='@t6g_mb_lib.t6g(sch_1):page207_i598@pure_quanta.q_res(chips)';

PART_NAME
 R452 'Q_RES_0402LF-10K,1%,1/16W,EMPTY,TMP_QCS31002FB26':;

SECTION_NUMBER 1
 '@T6G_MB_LIB.T6G(SCH_1):PAGE207_I602@PURE_QUANTA.Q_RES(CHIPS)':
 C_PATH='@t6g_mb_lib.t6g(sch_1):page207_i602@pure_quanta.q_res(chips)';

PART_NAME
 C117 'Q_CAP_0402-0.1UF,25V,10%,X7R,CH4104K1B00':;

SECTION_NUMBER 1
 '@T6G_MB_LIB.T6G(SCH_1):PAGE207_I639@PURE_QUANTA.Q_CAP(CHIPS)':
 C_PATH='@t6g_mb_lib.t6g(sch_1):page207_i639@pure_quanta.q_cap(chips)';

PART_NAME
 U129 'SN74LVC1G32DBVR-SN74LVC1G32DBVR,SMLF,IC,AL001G32015':;

SECTION_NUMBER 1
 '@T6G_MB_LIB.T6G(SCH_1):PAGE275_I46@PURE_QUANTA.SN74LVC1G32DBVR(CHIPS)':
 C_PATH='@t6g_mb_lib.t6g(sch_1):page275_i46@pure_quanta.sn74lvc1g32dbvr(chips)';

PART_NAME
 R3699 'Q_RES_0402LF-4.7K,5%,1/16W,CHIP,TMP_QCS24702JB38':;

SECTION_NUMBER 1
 '@T6G_MB_LIB.T6G(SCH_1):PAGE275_I51@PURE_QUANTA.Q_RES(CHIPS)':
 C_PATH='@t6g_mb_lib.t6g(sch_1):page275_i51@pure_quanta.q_res(chips)';

PART_NAME
 R3698 'Q_RES_0402LF-4.7K,5%,1/16W,CHIP,TMP_QCS24702JB38':;

SECTION_NUMBER 1
 '@T6G_MB_LIB.T6G(SCH_1):PAGE275_I54@PURE_QUANTA.Q_RES(CHIPS)':
 C_PATH='@t6g_mb_lib.t6g(sch_1):page275_i54@pure_quanta.q_res(chips)';

PART_NAME
 R3697 'Q_RES_0402LF-4.7K,5%,1/16W,CHIP,TMP_QCS24702JB38':;

SECTION_NUMBER 1
 '@T6G_MB_LIB.T6G(SCH_1):PAGE275_I57@PURE_QUANTA.Q_RES(CHIPS)':
 C_PATH='@t6g_mb_lib.t6g(sch_1):page275_i57@pure_quanta.q_res(chips)';

PART_NAME
 R3696 'Q_RES_0402LF-4.7K,5%,1/16W,CHIP,TMP_QCS24702JB38':;

SECTION_NUMBER 1
 '@T6G_MB_LIB.T6G(SCH_1):PAGE275_I67@PURE_QUANTA.Q_RES(CHIPS)':
 C_PATH='@t6g_mb_lib.t6g(sch_1):page275_i67@pure_quanta.q_res(chips)';

PART_NAME
 R3556 'Q_RES_0402LF-4.7K,5%,1/16W,CHIP,TMP_QCS24702JB38':;

SECTION_NUMBER 1
 '@T6G_MB_LIB.T6G(SCH_1):PAGE275_I15@PURE_QUANTA.Q_RES(CHIPS)':
 C_PATH='@t6g_mb_lib.t6g(sch_1):page275_i15@pure_quanta.q_res(chips)';

PART_NAME
 R2131 'Q_RES_0402LF-0,5%,1/16W,CHIP,CS00002JB38':;

SECTION_NUMBER 1
 '@T6G_MB_LIB.T6G(SCH_1):PAGE275_I49@PURE_QUANTA.Q_RES(CHIPS)':
 C_PATH='@t6g_mb_lib.t6g(sch_1):page275_i49@pure_quanta.q_res(chips)';

PART_NAME
 R2130 'Q_RES_0402LF-0,5%,1/16W,CHIP,CS00002JB38':;

SECTION_NUMBER 1
 '@T6G_MB_LIB.T6G(SCH_1):PAGE275_I48@PURE_QUANTA.Q_RES(CHIPS)':
 C_PATH='@t6g_mb_lib.t6g(sch_1):page275_i48@pure_quanta.q_res(chips)';

PART_NAME
 R1482 'Q_RES_0402LF-100K,5%,1/16W,CHIP,CS41002JB20':;

SECTION_NUMBER 1
 '@T6G_MB_LIB.T6G(SCH_1):PAGE275_I61@PURE_QUANTA.Q_RES(CHIPS)':
 C_PATH='@t6g_mb_lib.t6g(sch_1):page275_i61@pure_quanta.q_res(chips)';

PART_NAME
 R1481 'Q_RES_0402LF-100K,5%,1/16W,CHIP,CS41002JB20':;

SECTION_NUMBER 1
 '@T6G_MB_LIB.T6G(SCH_1):PAGE275_I70@PURE_QUANTA.Q_RES(CHIPS)':
 C_PATH='@t6g_mb_lib.t6g(sch_1):page275_i70@pure_quanta.q_res(chips)';

PART_NAME
 Q322 'MOSFET_NCH_DUAL-2N7002KDW,SMLF,IC,BAM70020047':;

SECTION_NUMBER 1
 '@T6G_MB_LIB.T6G(SCH_1):PAGE275_I19@PURE_QUANTA.MOSFET_NCH_DUAL(CHIPS)':
 C_PATH='@t6g_mb_lib.t6g(sch_1):page275_i19@pure_quanta.mosfet_nch_dual(chips)';

SECTION_NUMBER 2
 '@T6G_MB_LIB.T6G(SCH_1):PAGE275_I20@PURE_QUANTA.MOSFET_NCH_DUAL(CHIPS)':
 C_PATH='@t6g_mb_lib.t6g(sch_1):page275_i20@pure_quanta.mosfet_nch_dual(chips)';

PART_NAME
 Q314 'MOSFET_NCH_DUAL-2N7002KDW,SMLF,IC,BAM70020047':;

SECTION_NUMBER 1
 '@T6G_MB_LIB.T6G(SCH_1):PAGE275_I69@PURE_QUANTA.MOSFET_NCH_DUAL(CHIPS)':
 C_PATH='@t6g_mb_lib.t6g(sch_1):page275_i69@pure_quanta.mosfet_nch_dual(chips)';

SECTION_NUMBER 2
 '@T6G_MB_LIB.T6G(SCH_1):PAGE275_I66@PURE_QUANTA.MOSFET_NCH_DUAL(CHIPS)':
 C_PATH='@t6g_mb_lib.t6g(sch_1):page275_i66@pure_quanta.mosfet_nch_dual(chips)';

PART_NAME
 Q313 'MOSFET_NCH_DUAL-2N7002KDW,SMLF,IC,BAM70020047':;

SECTION_NUMBER 1
 '@T6G_MB_LIB.T6G(SCH_1):PAGE275_I59@PURE_QUANTA.MOSFET_NCH_DUAL(CHIPS)':
 C_PATH='@t6g_mb_lib.t6g(sch_1):page275_i59@pure_quanta.mosfet_nch_dual(chips)';

SECTION_NUMBER 2
 '@T6G_MB_LIB.T6G(SCH_1):PAGE275_I56@PURE_QUANTA.MOSFET_NCH_DUAL(CHIPS)':
 C_PATH='@t6g_mb_lib.t6g(sch_1):page275_i56@pure_quanta.mosfet_nch_dual(chips)';

PART_NAME
 Q2 'MOSFET_NCH_DUAL-2N7002KDW,SMLF,IC,BAM70020047':;

SECTION_NUMBER 1
 '@T6G_MB_LIB.T6G(SCH_1):PAGE275_I17@PURE_QUANTA.MOSFET_NCH_DUAL(CHIPS)':
 C_PATH='@t6g_mb_lib.t6g(sch_1):page275_i17@pure_quanta.mosfet_nch_dual(chips)';

SECTION_NUMBER 2
 '@T6G_MB_LIB.T6G(SCH_1):PAGE275_I18@PURE_QUANTA.MOSFET_NCH_DUAL(CHIPS)':
 C_PATH='@t6g_mb_lib.t6g(sch_1):page275_i18@pure_quanta.mosfet_nch_dual(chips)';

PART_NAME
 J75 'SCONN10_436501010-SCONN10_43650-1010,SMLF,IO,DFHD10MR148':;

SECTION_NUMBER 1
 '@T6G_MB_LIB.T6G(SCH_1):PAGE275_I78@PURE_QUANTA.SCONN10_436501010(CHIPS)':
 C_PATH='@s6q_mb_lib.s6q(sch_1):page275_i78@pure_quanta.sconn10_436501010(chips)~
';

PART_NAME
 J74 'SCONN10_436501010-SCONN10_43650-1010,SMLF,IO,DFHD10MR148':;

SECTION_NUMBER 1
 '@T6G_MB_LIB.T6G(SCH_1):PAGE275_I77@PURE_QUANTA.SCONN10_436501010(CHIPS)':
 C_PATH='@s6q_mb_lib.s6q(sch_1):page275_i77@pure_quanta.sconn10_436501010(chips)~
';

PART_NAME
 C2897 'Q_CAP_C0603-10UF,16V,20%,X6S,CH6103ME902':;

SECTION_NUMBER 1
 '@T6G_MB_LIB.T6G(SCH_1):PAGE275_I38@PURE_QUANTA.Q_CAP(CHIPS)':
 C_PATH='@t6g_mb_lib.t6g(sch_1):page275_i38@pure_quanta.q_cap(chips)';

PART_NAME
 C2896 'Q_CAP_C0402-1UF,25V,10%,X6S,CH5104KEB02':;

SECTION_NUMBER 1
 '@T6G_MB_LIB.T6G(SCH_1):PAGE275_I34@PURE_QUANTA.Q_CAP(CHIPS)':
 C_PATH='@t6g_mb_lib.t6g(sch_1):page275_i34@pure_quanta.q_cap(chips)';

PART_NAME
 C2895 'Q_CAP_C0603-10UF,16V,20%,X6S,CH6103ME902':;

SECTION_NUMBER 1
 '@T6G_MB_LIB.T6G(SCH_1):PAGE275_I35@PURE_QUANTA.Q_CAP(CHIPS)':
 C_PATH='@t6g_mb_lib.t6g(sch_1):page275_i35@pure_quanta.q_cap(chips)';

PART_NAME
 C2894 'Q_CAP_C0402-1UF,25V,10%,X6S,CH5104KEB02':;

SECTION_NUMBER 1
 '@T6G_MB_LIB.T6G(SCH_1):PAGE275_I33@PURE_QUANTA.Q_CAP(CHIPS)':
 C_PATH='@t6g_mb_lib.t6g(sch_1):page275_i33@pure_quanta.q_cap(chips)';

PART_NAME
 C116 'Q_CAP_0402-0.1UF,25V,10%,X7R,CH4104K1B00':;

SECTION_NUMBER 1
 '@T6G_MB_LIB.T6G(SCH_1):PAGE275_I43@PURE_QUANTA.Q_CAP(CHIPS)':
 C_PATH='@t6g_mb_lib.t6g(sch_1):page275_i43@pure_quanta.q_cap(chips)';

PART_NAME
 U32 'SN74LVC1G14DBVR_SMLF-SN74LVC1G14DBVR,IC,AL001G14009':;

SECTION_NUMBER 1
 '@T6G_MB_LIB.T6G(SCH_1):PAGE200_I7@PURE_QUANTA.SN74LVC1G14DBVR(CHIPS)':
 C_PATH='@t6g_mb_lib.t6g(sch_1):page200_i7@pure_quanta.sn74lvc1g14dbvr(chips)';

PART_NAME
 U31 'SN74LVC1G14DBVR_SMLF-SN74LVC1G14DBVR,IC,AL001G14009':;

SECTION_NUMBER 1
 '@T6G_MB_LIB.T6G(SCH_1):PAGE200_I14@PURE_QUANTA.SN74LVC1G14DBVR(CHIPS)':
 C_PATH='@t6g_mb_lib.t6g(sch_1):page200_i14@pure_quanta.sn74lvc1g14dbvr(chips)';

PART_NAME
 U30 'SN74HC595BRWN-SN74HC595BRWN,SMLF,IC,AL000595002':;

SECTION_NUMBER 1
 '@T6G_MB_LIB.T6G(SCH_1):PAGE200_I38@PURE_QUANTA.SN74HC595BRWN(CHIPS)':
 C_PATH='@t6g_mb_lib.t6g(sch_1):page200_i38@pure_quanta.sn74hc595brwn(chips)';

PART_NAME
 U27 'SN74HC595BRWN-SN74HC595BRWN,SMLF,IC,AL000595002':;

SECTION_NUMBER 1
 '@T6G_MB_LIB.T6G(SCH_1):PAGE200_I22@PURE_QUANTA.SN74HC595BRWN(CHIPS)':
 C_PATH='@t6g_mb_lib.t6g(sch_1):page200_i22@pure_quanta.sn74hc595brwn(chips)';

PART_NAME
 R3667 'Q_RES_0402LF-49.9     ,1%  ,1/16W,CHIP,CS04992FB31':;

SECTION_NUMBER 1
 '@T6G_MB_LIB.T6G(SCH_1):PAGE200_I51@PURE_QUANTA.Q_RES(CHIPS)':
 C_PATH='@t6g_mb_lib.t6g(sch_1):page200_i51@pure_quanta.q_res(chips)';

PART_NAME
 R3666 'Q_RES_0402LF-49.9     ,1%  ,1/16W,CHIP,CS04992FB31':;

SECTION_NUMBER 1
 '@T6G_MB_LIB.T6G(SCH_1):PAGE200_I52@PURE_QUANTA.Q_RES(CHIPS)':
 C_PATH='@t6g_mb_lib.t6g(sch_1):page200_i52@pure_quanta.q_res(chips)';

PART_NAME
 R808 'Q_RES_0402LF-49.9     ,1%  ,1/16W,EMPTY,CS04992FB31':;

SECTION_NUMBER 1
 '@T6G_MB_LIB.T6G(SCH_1):PAGE200_I45@PURE_QUANTA.Q_RES(CHIPS)':
 C_PATH='@t6g_mb_lib.t6g(sch_1):page200_i45@pure_quanta.q_res(chips)';

PART_NAME
 R802 'Q_RES_0402LF-49.9     ,1%  ,1/16W,EMPTY,CS04992FB31':;

SECTION_NUMBER 1
 '@T6G_MB_LIB.T6G(SCH_1):PAGE200_I49@PURE_QUANTA.Q_RES(CHIPS)':
 C_PATH='@t6g_mb_lib.t6g(sch_1):page200_i49@pure_quanta.q_res(chips)';

PART_NAME
 R801 'Q_RES_0402LF-2K,1%,1/16W,CHIP,TMP_QCS22002FB19':;

SECTION_NUMBER 1
 '@T6G_MB_LIB.T6G(SCH_1):PAGE200_I10@PURE_QUANTA.Q_RES(CHIPS)':
 C_PATH='@t6g_mb_lib.t6g(sch_1):page200_i10@pure_quanta.q_res(chips)';

PART_NAME
 R798 'Q_RES_0402LF-0,5%,1/16W,EMPTY,CS00002JB38':;

SECTION_NUMBER 1
 '@T6G_MB_LIB.T6G(SCH_1):PAGE200_I20@PURE_QUANTA.Q_RES(CHIPS)':
 C_PATH='@t6g_mb_lib.t6g(sch_1):page200_i20@pure_quanta.q_res(chips)';

PART_NAME
 R797 'Q_RES_0402LF-0,5%,1/16W,EMPTY,CS00002JB38':;

SECTION_NUMBER 1
 '@T6G_MB_LIB.T6G(SCH_1):PAGE200_I5@PURE_QUANTA.Q_RES(CHIPS)':
 C_PATH='@t6g_mb_lib.t6g(sch_1):page200_i5@pure_quanta.q_res(chips)';

PART_NAME
 C115 'Q_CAP_0402-0.1UF,25V,10%,X7R,CH4104K1B00':;

SECTION_NUMBER 1
 '@T6G_MB_LIB.T6G(SCH_1):PAGE200_I36@PURE_QUANTA.Q_CAP(CHIPS)':
 C_PATH='@t6g_mb_lib.t6g(sch_1):page200_i36@pure_quanta.q_cap(chips)';

PART_NAME
 C114 'Q_CAP_0402-0.1UF,25V,10%,X7R,CH4104K1B00':;

SECTION_NUMBER 1
 '@T6G_MB_LIB.T6G(SCH_1):PAGE200_I3@PURE_QUANTA.Q_CAP(CHIPS)':
 C_PATH='@t6g_mb_lib.t6g(sch_1):page200_i3@pure_quanta.q_cap(chips)';

PART_NAME
 C113 'Q_CAP_0402-0.1UF,25V,10%,X7R,CH4104K1B00':;

SECTION_NUMBER 1
 '@T6G_MB_LIB.T6G(SCH_1):PAGE200_I17@PURE_QUANTA.Q_CAP(CHIPS)':
 C_PATH='@t6g_mb_lib.t6g(sch_1):page200_i17@pure_quanta.q_cap(chips)';

PART_NAME
 C112 'Q_CAP_0402-22PF,50V,5%,NPO,TMP_QCH02206JB08':;

SECTION_NUMBER 1
 '@T6G_MB_LIB.T6G(SCH_1):PAGE200_I43@PURE_QUANTA.Q_CAP(CHIPS)':
 C_PATH='@t6g_mb_lib.t6g(sch_1):page200_i43@pure_quanta.q_cap(chips)';

PART_NAME
 C111 'Q_CAP_0402-22PF,50V,5%,NPO,TMP_QCH02206JB08':;

SECTION_NUMBER 1
 '@T6G_MB_LIB.T6G(SCH_1):PAGE200_I48@PURE_QUANTA.Q_CAP(CHIPS)':
 C_PATH='@t6g_mb_lib.t6g(sch_1):page200_i48@pure_quanta.q_cap(chips)';

PART_NAME
 C110 'Q_CAP_0402-0.1UF,25V,10%,X7R,CH4104K1B00':;

SECTION_NUMBER 1
 '@T6G_MB_LIB.T6G(SCH_1):PAGE200_I25@PURE_QUANTA.Q_CAP(CHIPS)':
 C_PATH='@t6g_mb_lib.t6g(sch_1):page200_i25@pure_quanta.q_cap(chips)';

PART_NAME
 C678 'Q_CAP_DIFFBUS_C0201-DIFF BUS_0.22UF,6.3V,20%,X6S,SP_CH4221MEE01':;

SECTION_NUMBER 1
 '@T6G_MB_LIB.T6G(SCH_1):PAGE141_I164@PURE_QUANTA.Q_CAP_DIFFBUS(CHIPS)':
 C_PATH='@t6g_mb_lib.t6g(sch_1):page141_i164@pure_quanta.q_cap_diffbus(chips)';

PART_NAME
 C677 'Q_CAP_DIFFBUS_C0201-DIFF BUS_0.22UF,6.3V,20%,X6S,SP_CH4221MEE01':;

SECTION_NUMBER 1
 '@T6G_MB_LIB.T6G(SCH_1):PAGE141_I160@PURE_QUANTA.Q_CAP_DIFFBUS(CHIPS)':
 C_PATH='@t6g_mb_lib.t6g(sch_1):page141_i160@pure_quanta.q_cap_diffbus(chips)';

PART_NAME
 C676 'Q_CAP_DIFFBUS_C0201-DIFF BUS_0.22UF,6.3V,20%,X6S,SP_CH4221MEE01':;

SECTION_NUMBER 1
 '@T6G_MB_LIB.T6G(SCH_1):PAGE141_I159@PURE_QUANTA.Q_CAP_DIFFBUS(CHIPS)':
 C_PATH='@t6g_mb_lib.t6g(sch_1):page141_i159@pure_quanta.q_cap_diffbus(chips)';

PART_NAME
 C675 'Q_CAP_DIFFBUS_C0201-DIFF BUS_0.22UF,6.3V,20%,X6S,SP_CH4221MEE01':;

SECTION_NUMBER 1
 '@T6G_MB_LIB.T6G(SCH_1):PAGE141_I158@PURE_QUANTA.Q_CAP_DIFFBUS(CHIPS)':
 C_PATH='@t6g_mb_lib.t6g(sch_1):page141_i158@pure_quanta.q_cap_diffbus(chips)';

PART_NAME
 C674 'Q_CAP_DIFFBUS_C0201-DIFF BUS_0.22UF,6.3V,20%,X6S,SP_CH4221MEE01':;

SECTION_NUMBER 1
 '@T6G_MB_LIB.T6G(SCH_1):PAGE141_I154@PURE_QUANTA.Q_CAP_DIFFBUS(CHIPS)':
 C_PATH='@t6g_mb_lib.t6g(sch_1):page141_i154@pure_quanta.q_cap_diffbus(chips)';

PART_NAME
 C673 'Q_CAP_DIFFBUS_C0201-DIFF BUS_0.22UF,6.3V,20%,X6S,SP_CH4221MEE01':;

SECTION_NUMBER 1
 '@T6G_MB_LIB.T6G(SCH_1):PAGE141_I153@PURE_QUANTA.Q_CAP_DIFFBUS(CHIPS)':
 C_PATH='@t6g_mb_lib.t6g(sch_1):page141_i153@pure_quanta.q_cap_diffbus(chips)';

PART_NAME
 C672 'Q_CAP_DIFFBUS_C0201-DIFF BUS_0.22UF,6.3V,20%,X6S,SP_CH4221MEE01':;

SECTION_NUMBER 1
 '@T6G_MB_LIB.T6G(SCH_1):PAGE141_I150@PURE_QUANTA.Q_CAP_DIFFBUS(CHIPS)':
 C_PATH='@t6g_mb_lib.t6g(sch_1):page141_i150@pure_quanta.q_cap_diffbus(chips)';

PART_NAME
 C671 'Q_CAP_DIFFBUS_C0201-DIFF BUS_0.22UF,6.3V,20%,X6S,SP_CH4221MEE01':;

SECTION_NUMBER 1
 '@T6G_MB_LIB.T6G(SCH_1):PAGE141_I149@PURE_QUANTA.Q_CAP_DIFFBUS(CHIPS)':
 C_PATH='@t6g_mb_lib.t6g(sch_1):page141_i149@pure_quanta.q_cap_diffbus(chips)';

PART_NAME
 C670 'Q_CAP_DIFFBUS_C0201-DIFF BUS_0.22UF,6.3V,20%,X6S,SP_CH4221MEE01':;

SECTION_NUMBER 1
 '@T6G_MB_LIB.T6G(SCH_1):PAGE141_I163@PURE_QUANTA.Q_CAP_DIFFBUS(CHIPS)':
 C_PATH='@t6g_mb_lib.t6g(sch_1):page141_i163@pure_quanta.q_cap_diffbus(chips)';

PART_NAME
 C669 'Q_CAP_DIFFBUS_C0201-DIFF BUS_0.22UF,6.3V,20%,X6S,SP_CH4221MEE01':;

SECTION_NUMBER 1
 '@T6G_MB_LIB.T6G(SCH_1):PAGE141_I162@PURE_QUANTA.Q_CAP_DIFFBUS(CHIPS)':
 C_PATH='@t6g_mb_lib.t6g(sch_1):page141_i162@pure_quanta.q_cap_diffbus(chips)';

PART_NAME
 C668 'Q_CAP_DIFFBUS_C0201-DIFF BUS_0.22UF,6.3V,20%,X6S,SP_CH4221MEE01':;

SECTION_NUMBER 1
 '@T6G_MB_LIB.T6G(SCH_1):PAGE141_I161@PURE_QUANTA.Q_CAP_DIFFBUS(CHIPS)':
 C_PATH='@t6g_mb_lib.t6g(sch_1):page141_i161@pure_quanta.q_cap_diffbus(chips)';

PART_NAME
 C667 'Q_CAP_DIFFBUS_C0201-DIFF BUS_0.22UF,6.3V,20%,X6S,SP_CH4221MEE01':;

SECTION_NUMBER 1
 '@T6G_MB_LIB.T6G(SCH_1):PAGE141_I157@PURE_QUANTA.Q_CAP_DIFFBUS(CHIPS)':
 C_PATH='@t6g_mb_lib.t6g(sch_1):page141_i157@pure_quanta.q_cap_diffbus(chips)';

PART_NAME
 C666 'Q_CAP_DIFFBUS_C0201-DIFF BUS_0.22UF,6.3V,20%,X6S,SP_CH4221MEE01':;

SECTION_NUMBER 1
 '@T6G_MB_LIB.T6G(SCH_1):PAGE141_I155@PURE_QUANTA.Q_CAP_DIFFBUS(CHIPS)':
 C_PATH='@t6g_mb_lib.t6g(sch_1):page141_i155@pure_quanta.q_cap_diffbus(chips)';

PART_NAME
 C665 'Q_CAP_DIFFBUS_C0201-DIFF BUS_0.22UF,6.3V,20%,X6S,SP_CH4221MEE01':;

SECTION_NUMBER 1
 '@T6G_MB_LIB.T6G(SCH_1):PAGE141_I156@PURE_QUANTA.Q_CAP_DIFFBUS(CHIPS)':
 C_PATH='@t6g_mb_lib.t6g(sch_1):page141_i156@pure_quanta.q_cap_diffbus(chips)';

PART_NAME
 C664 'Q_CAP_DIFFBUS_C0201-DIFF BUS_0.22UF,6.3V,20%,X6S,SP_CH4221MEE01':;

SECTION_NUMBER 1
 '@T6G_MB_LIB.T6G(SCH_1):PAGE141_I152@PURE_QUANTA.Q_CAP_DIFFBUS(CHIPS)':
 C_PATH='@t6g_mb_lib.t6g(sch_1):page141_i152@pure_quanta.q_cap_diffbus(chips)';

PART_NAME
 C663 'Q_CAP_DIFFBUS_C0201-DIFF BUS_0.22UF,6.3V,20%,X6S,SP_CH4221MEE01':;

SECTION_NUMBER 1
 '@T6G_MB_LIB.T6G(SCH_1):PAGE141_I151@PURE_QUANTA.Q_CAP_DIFFBUS(CHIPS)':
 C_PATH='@t6g_mb_lib.t6g(sch_1):page141_i151@pure_quanta.q_cap_diffbus(chips)';

PART_NAME
 C662 'Q_CAP_DIFFBUS_C0201-DIFF BUS_0.22UF,6.3V,20%,X6S,SP_CH4221MEE01':;

SECTION_NUMBER 1
 '@T6G_MB_LIB.T6G(SCH_1):PAGE141_I148@PURE_QUANTA.Q_CAP_DIFFBUS(CHIPS)':
 C_PATH='@t6g_mb_lib.t6g(sch_1):page141_i148@pure_quanta.q_cap_diffbus(chips)';

PART_NAME
 C661 'Q_CAP_DIFFBUS_C0201-DIFF BUS_0.22UF,6.3V,20%,X6S,SP_CH4221MEE01':;

SECTION_NUMBER 1
 '@T6G_MB_LIB.T6G(SCH_1):PAGE141_I144@PURE_QUANTA.Q_CAP_DIFFBUS(CHIPS)':
 C_PATH='@t6g_mb_lib.t6g(sch_1):page141_i144@pure_quanta.q_cap_diffbus(chips)';

PART_NAME
 C660 'Q_CAP_DIFFBUS_C0201-DIFF BUS_0.22UF,6.3V,20%,X6S,SP_CH4221MEE01':;

SECTION_NUMBER 1
 '@T6G_MB_LIB.T6G(SCH_1):PAGE141_I143@PURE_QUANTA.Q_CAP_DIFFBUS(CHIPS)':
 C_PATH='@t6g_mb_lib.t6g(sch_1):page141_i143@pure_quanta.q_cap_diffbus(chips)';

PART_NAME
 C659 'Q_CAP_DIFFBUS_C0201-DIFF BUS_0.22UF,6.3V,20%,X6S,SP_CH4221MEE01':;

SECTION_NUMBER 1
 '@T6G_MB_LIB.T6G(SCH_1):PAGE141_I142@PURE_QUANTA.Q_CAP_DIFFBUS(CHIPS)':
 C_PATH='@t6g_mb_lib.t6g(sch_1):page141_i142@pure_quanta.q_cap_diffbus(chips)';

PART_NAME
 C658 'Q_CAP_DIFFBUS_C0201-DIFF BUS_0.22UF,6.3V,20%,X6S,SP_CH4221MEE01':;

SECTION_NUMBER 1
 '@T6G_MB_LIB.T6G(SCH_1):PAGE141_I138@PURE_QUANTA.Q_CAP_DIFFBUS(CHIPS)':
 C_PATH='@t6g_mb_lib.t6g(sch_1):page141_i138@pure_quanta.q_cap_diffbus(chips)';

PART_NAME
 C657 'Q_CAP_DIFFBUS_C0201-DIFF BUS_0.22UF,6.3V,20%,X6S,SP_CH4221MEE01':;

SECTION_NUMBER 1
 '@T6G_MB_LIB.T6G(SCH_1):PAGE141_I137@PURE_QUANTA.Q_CAP_DIFFBUS(CHIPS)':
 C_PATH='@t6g_mb_lib.t6g(sch_1):page141_i137@pure_quanta.q_cap_diffbus(chips)';

PART_NAME
 C656 'Q_CAP_DIFFBUS_C0201-DIFF BUS_0.22UF,6.3V,20%,X6S,SP_CH4221MEE01':;

SECTION_NUMBER 1
 '@T6G_MB_LIB.T6G(SCH_1):PAGE141_I134@PURE_QUANTA.Q_CAP_DIFFBUS(CHIPS)':
 C_PATH='@t6g_mb_lib.t6g(sch_1):page141_i134@pure_quanta.q_cap_diffbus(chips)';

PART_NAME
 C654 'Q_CAP_DIFFBUS_C0201-DIFF BUS_0.22UF,6.3V,20%,X6S,SP_CH4221MEE01':;

SECTION_NUMBER 1
 '@T6G_MB_LIB.T6G(SCH_1):PAGE141_I133@PURE_QUANTA.Q_CAP_DIFFBUS(CHIPS)':
 C_PATH='@t6g_mb_lib.t6g(sch_1):page141_i133@pure_quanta.q_cap_diffbus(chips)';

PART_NAME
 C648 'Q_CAP_DIFFBUS_C0201-DIFF BUS_0.22UF,6.3V,20%,X6S,SP_CH4221MEE01':;

SECTION_NUMBER 1
 '@T6G_MB_LIB.T6G(SCH_1):PAGE141_I147@PURE_QUANTA.Q_CAP_DIFFBUS(CHIPS)':
 C_PATH='@t6g_mb_lib.t6g(sch_1):page141_i147@pure_quanta.q_cap_diffbus(chips)';

PART_NAME
 C647 'Q_CAP_DIFFBUS_C0201-DIFF BUS_0.22UF,6.3V,20%,X6S,SP_CH4221MEE01':;

SECTION_NUMBER 1
 '@T6G_MB_LIB.T6G(SCH_1):PAGE141_I146@PURE_QUANTA.Q_CAP_DIFFBUS(CHIPS)':
 C_PATH='@t6g_mb_lib.t6g(sch_1):page141_i146@pure_quanta.q_cap_diffbus(chips)';

PART_NAME
 C646 'Q_CAP_DIFFBUS_C0201-DIFF BUS_0.22UF,6.3V,20%,X6S,SP_CH4221MEE01':;

SECTION_NUMBER 1
 '@T6G_MB_LIB.T6G(SCH_1):PAGE141_I145@PURE_QUANTA.Q_CAP_DIFFBUS(CHIPS)':
 C_PATH='@t6g_mb_lib.t6g(sch_1):page141_i145@pure_quanta.q_cap_diffbus(chips)';

PART_NAME
 C645 'Q_CAP_DIFFBUS_C0201-DIFF BUS_0.22UF,6.3V,20%,X6S,SP_CH4221MEE01':;

SECTION_NUMBER 1
 '@T6G_MB_LIB.T6G(SCH_1):PAGE141_I141@PURE_QUANTA.Q_CAP_DIFFBUS(CHIPS)':
 C_PATH='@t6g_mb_lib.t6g(sch_1):page141_i141@pure_quanta.q_cap_diffbus(chips)';

PART_NAME
 C642 'Q_CAP_DIFFBUS_C0201-DIFF BUS_0.22UF,6.3V,20%,X6S,SP_CH4221MEE01':;

SECTION_NUMBER 1
 '@T6G_MB_LIB.T6G(SCH_1):PAGE141_I136@PURE_QUANTA.Q_CAP_DIFFBUS(CHIPS)':
 C_PATH='@t6g_mb_lib.t6g(sch_1):page141_i136@pure_quanta.q_cap_diffbus(chips)';

PART_NAME
 C641 'Q_CAP_DIFFBUS_C0201-DIFF BUS_0.22UF,6.3V,20%,X6S,SP_CH4221MEE01':;

SECTION_NUMBER 1
 '@T6G_MB_LIB.T6G(SCH_1):PAGE141_I166@PURE_QUANTA.Q_CAP_DIFFBUS(CHIPS)':
 C_PATH='@t6g_mb_lib.t6g(sch_1):page141_i166@pure_quanta.q_cap_diffbus(chips)';

PART_NAME
 C109 'Q_CAP_DIFFBUS_C0201-DIFF BUS_0.22UF,6.3V,20%,X6S,SP_CH4221MEE01':;

SECTION_NUMBER 1
 '@T6G_MB_LIB.T6G(SCH_1):PAGE141_I140@PURE_QUANTA.Q_CAP_DIFFBUS(CHIPS)':
 C_PATH='@t6g_mb_lib.t6g(sch_1):page141_i140@pure_quanta.q_cap_diffbus(chips)';

PART_NAME
 C108 'Q_CAP_DIFFBUS_C0201-DIFF BUS_0.22UF,6.3V,20%,X6S,SP_CH4221MEE01':;

SECTION_NUMBER 1
 '@T6G_MB_LIB.T6G(SCH_1):PAGE141_I139@PURE_QUANTA.Q_CAP_DIFFBUS(CHIPS)':
 C_PATH='@t6g_mb_lib.t6g(sch_1):page141_i139@pure_quanta.q_cap_diffbus(chips)';

PART_NAME
 U7 '74LVC1G07GV-74LVC1G07GV,SMLF,IC,AL1G0007001':;

SECTION_NUMBER 1
 '@T6G_MB_LIB.T6G(SCH_1):PAGE94_I7@PURE_QUANTA.74LVC1G07GV(CHIPS)':
 C_PATH='@t6g_mb_lib.t6g(sch_1):page94_i7@pure_quanta.\74lvc1g07gv\(chips)';

PART_NAME
 R198 'Q_RES_0402LF-10K,1%,1/16W,EMPTY,TMP_QCS31002FB26':;

SECTION_NUMBER 1
 '@T6G_MB_LIB.T6G(SCH_1):PAGE94_I18@PURE_QUANTA.Q_RES(CHIPS)':
 C_PATH='@t6g_mb_lib.t6g(sch_1):page94_i18@pure_quanta.q_res(chips)';

PART_NAME
 R197 'Q_RES_0402LF-10K,1%,1/16W,EMPTY,TMP_QCS31002FB26':;

SECTION_NUMBER 1
 '@T6G_MB_LIB.T6G(SCH_1):PAGE94_I26@PURE_QUANTA.Q_RES(CHIPS)':
 C_PATH='@t6g_mb_lib.t6g(sch_1):page94_i26@pure_quanta.q_res(chips)';

PART_NAME
 R196 'Q_RES_0402LF-49.9     ,1%  ,1/16W,CHIP,CS04992FB31':;

SECTION_NUMBER 1
 '@T6G_MB_LIB.T6G(SCH_1):PAGE94_I17@PURE_QUANTA.Q_RES(CHIPS)':
 C_PATH='@t6g_mb_lib.t6g(sch_1):page94_i17@pure_quanta.q_res(chips)';

PART_NAME
 R195 'Q_RES_0402LF-49.9     ,1%  ,1/16W,CHIP,CS04992FB31':;

SECTION_NUMBER 1
 '@T6G_MB_LIB.T6G(SCH_1):PAGE94_I22@PURE_QUANTA.Q_RES(CHIPS)':
 C_PATH='@t6g_mb_lib.t6g(sch_1):page94_i22@pure_quanta.q_res(chips)';

PART_NAME
 R194 'Q_RES_0402LF-301,1%,1/16W,CHIP,TMP_QCS13012FB14':;

SECTION_NUMBER 1
 '@T6G_MB_LIB.T6G(SCH_1):PAGE94_I14@PURE_QUANTA.Q_RES(CHIPS)':
 C_PATH='@t6g_mb_lib.t6g(sch_1):page94_i14@pure_quanta.q_res(chips)';

PART_NAME
 R193 'Q_RES_0402LF-0,5%,1/16W,EMPTY,CS00002JB38':;

SECTION_NUMBER 1
 '@T6G_MB_LIB.T6G(SCH_1):PAGE94_I23@PURE_QUANTA.Q_RES(CHIPS)':
 C_PATH='@t6g_mb_lib.t6g(sch_1):page94_i23@pure_quanta.q_res(chips)';

PART_NAME
 R192 'Q_RES_0402LF-301,1%,1/16W,CHIP,TMP_QCS13012FB14':;

SECTION_NUMBER 1
 '@T6G_MB_LIB.T6G(SCH_1):PAGE94_I13@PURE_QUANTA.Q_RES(CHIPS)':
 C_PATH='@t6g_mb_lib.t6g(sch_1):page94_i13@pure_quanta.q_res(chips)';

PART_NAME
 R191 'Q_RES_0402LF-0,5%,1/16W,CHIP,CS00002JB38':;

SECTION_NUMBER 1
 '@T6G_MB_LIB.T6G(SCH_1):PAGE94_I4@PURE_QUANTA.Q_RES(CHIPS)':
 C_PATH='@t6g_mb_lib.t6g(sch_1):page94_i4@pure_quanta.q_res(chips)';

PART_NAME
 R190 'Q_RES_0402LF-0,5%,1/16W,CHIP,CS00002JB38':;

SECTION_NUMBER 1
 '@T6G_MB_LIB.T6G(SCH_1):PAGE94_I5@PURE_QUANTA.Q_RES(CHIPS)':
 C_PATH='@t6g_mb_lib.t6g(sch_1):page94_i5@pure_quanta.q_res(chips)';

PART_NAME
 R189 'Q_RES_1206LF-10K,1%,1/4W,CHIP,TMP_QCS31006F200':;

SECTION_NUMBER 1
 '@T6G_MB_LIB.T6G(SCH_1):PAGE94_I10@PURE_QUANTA.Q_RES(CHIPS)':
 C_PATH='@t6g_mb_lib.t6g(sch_1):page94_i10@pure_quanta.q_res(chips)';

PART_NAME
 R188 'Q_RES_0402LF-0,5%,1/16W,CHIP,CS00002JB38':;

SECTION_NUMBER 1
 '@T6G_MB_LIB.T6G(SCH_1):PAGE94_I1@PURE_QUANTA.Q_RES(CHIPS)':
 C_PATH='@t6g_mb_lib.t6g(sch_1):page94_i1@pure_quanta.q_res(chips)';

PART_NAME
 R187 'Q_RES_0402LF-0,5%,1/16W,EMPTY,CS00002JB38':;

SECTION_NUMBER 1
 '@T6G_MB_LIB.T6G(SCH_1):PAGE94_I9@PURE_QUANTA.Q_RES(CHIPS)':
 C_PATH='@t6g_mb_lib.t6g(sch_1):page94_i9@pure_quanta.q_res(chips)';

PART_NAME
 C105 'Q_CAP_0402-0.1UF,25V,10%,X7R,CH4104K1B00':;

SECTION_NUMBER 1
 '@T6G_MB_LIB.T6G(SCH_1):PAGE94_I25@PURE_QUANTA.Q_CAP(CHIPS)':
 C_PATH='@t6g_mb_lib.t6g(sch_1):page94_i25@pure_quanta.q_cap(chips)';

PART_NAME
 Y3 'Q_XTAL_4P_13BI_24GND-25MHZ,SMLF,MISC,BG625000802':;

SECTION_NUMBER 1
 '@T6G_MB_LIB.T6G(SCH_1):PAGE176_I345@PURE_QUANTA.Q_XTAL_4P_13BI_24GND(CHIPS)':
 C_PATH='@t6g_mb_lib.t6g(sch_1):page176_i345@pure_quanta.q_xtal_4p_13bi_24gnd(ch~
ips)';

PART_NAME
 Y1 'Q_CRYSTAL_SMLF-32.768KHZ,IC,BG632768012':;

SECTION_NUMBER 1
 '@T6G_MB_LIB.T6G(SCH_1):PAGE176_I326@PURE_QUANTA.Q_CRYSTAL(CHIPS)':
 C_PATH='@t6g_mb_lib.t6g(sch_1):page176_i326@pure_quanta.q_crystal(chips)';

PART_NAME
 R1721 'Q_RES_0402LF-0,5%,1/16W,CHIP,CS00002JB38':;

SECTION_NUMBER 1
 '@T6G_MB_LIB.T6G(SCH_1):PAGE176_I322@PURE_QUANTA.Q_RES(CHIPS)':
 C_PATH='@t6g_mb_lib.t6g(sch_1):page176_i322@pure_quanta.q_res(chips)';

PART_NAME
 R1720 'Q_RES_0402LF-0,5%,1/16W,CHIP,CS00002JB38':;

SECTION_NUMBER 1
 '@T6G_MB_LIB.T6G(SCH_1):PAGE176_I343@PURE_QUANTA.Q_RES(CHIPS)':
 C_PATH='@t6g_mb_lib.t6g(sch_1):page176_i343@pure_quanta.q_res(chips)';

PART_NAME
 R1316 'Q_RES_0603LF-200K,0.1%,1/10W,CHIP,CS42003B901':;

SECTION_NUMBER 1
 '@T6G_MB_LIB.T6G(SCH_1):PAGE176_I344@PURE_QUANTA.Q_RES(CHIPS)':
 C_PATH='@t6g_mb_lib.t6g(sch_1):page176_i344@pure_quanta.q_res(chips)';

PART_NAME
 R477 'Q_RES_0402LF-60.4,1%,1/16W,CHIP,CS06042FB03':;

SECTION_NUMBER 1
 '@T6G_MB_LIB.T6G(SCH_1):PAGE176_I341@PURE_QUANTA.Q_RES(CHIPS)':
 C_PATH='@t6g_mb_lib.t6g(sch_1):page176_i341@pure_quanta.q_res(chips)';

PART_NAME
 R120 'Q_RES_0603LF-10M,1%,1/10W,CHIP,CS61003F900':;

SECTION_NUMBER 1
 '@T6G_MB_LIB.T6G(SCH_1):PAGE176_I325@PURE_QUANTA.Q_RES(CHIPS)':
 C_PATH='@t6g_mb_lib.t6g(sch_1):page176_i325@pure_quanta.q_res(chips)';

PART_NAME
 C1508 'Q_CAP_0402-27PF  ,50V ,5% ,NPO,CH02706JB06':;

SECTION_NUMBER 1
 '@T6G_MB_LIB.T6G(SCH_1):PAGE176_I328@PURE_QUANTA.Q_CAP(CHIPS)':
 C_PATH='@t6g_mb_lib.t6g(sch_1):page176_i328@pure_quanta.q_cap(chips)';

PART_NAME
 C1507 'Q_CAP_0402-27PF  ,50V ,5% ,NPO,CH02706JB06':;

SECTION_NUMBER 1
 '@T6G_MB_LIB.T6G(SCH_1):PAGE176_I329@PURE_QUANTA.Q_CAP(CHIPS)':
 C_PATH='@t6g_mb_lib.t6g(sch_1):page176_i329@pure_quanta.q_cap(chips)';

PART_NAME
 C609 'Q_CAP_0402-0.1UF,25V,10%,X7R,CH4104K1B00':;

SECTION_NUMBER 1
 '@T6G_MB_LIB.T6G(SCH_1):PAGE176_I339@PURE_QUANTA.Q_CAP(CHIPS)':
 C_PATH='@t6g_mb_lib.t6g(sch_1):page176_i339@pure_quanta.q_cap(chips)';

PART_NAME
 C104 'Q_CAP_0402-27PF  ,50V ,5% ,NPO,CH02706JB06':;

SECTION_NUMBER 1
 '@T6G_MB_LIB.T6G(SCH_1):PAGE176_I346@PURE_QUANTA.Q_CAP(CHIPS)':
 C_PATH='@t6g_mb_lib.t6g(sch_1):page176_i346@pure_quanta.q_cap(chips)';

PART_NAME
 C103 'Q_CAP_0402-27PF  ,50V ,5% ,NPO,CH02706JB06':;

SECTION_NUMBER 1
 '@T6G_MB_LIB.T6G(SCH_1):PAGE176_I348@PURE_QUANTA.Q_CAP(CHIPS)':
 C_PATH='@t6g_mb_lib.t6g(sch_1):page176_i348@pure_quanta.q_cap(chips)';

PART_NAME
 U11 'GTL2014PW-GTL2014PW,SMLF,IC,AL002014K01':;

SECTION_NUMBER 1
 '@T6G_MB_LIB.T6G(SCH_1):PAGE89_I35@PURE_QUANTA.GTL2014PW(CHIPS)':
 C_PATH='@t6g_mb_lib.t6g(sch_1):page89_i35@pure_quanta.gtl2014pw(chips)';

PART_NAME
 R364 'Q_RES_0402LF-33,5%,1/16W,EMPTY,CS03302JB29':;

SECTION_NUMBER 1
 '@T6G_MB_LIB.T6G(SCH_1):PAGE89_I48@PURE_QUANTA.Q_RES(CHIPS)':
 C_PATH='@t6g_mb_lib.t6g(sch_1):page89_i48@pure_quanta.q_res(chips)';

PART_NAME
 R363 'Q_RES_0402LF-33,5%,1/16W,EMPTY,CS03302JB29':;

SECTION_NUMBER 1
 '@T6G_MB_LIB.T6G(SCH_1):PAGE89_I49@PURE_QUANTA.Q_RES(CHIPS)':
 C_PATH='@t6g_mb_lib.t6g(sch_1):page89_i49@pure_quanta.q_res(chips)';

PART_NAME
 R362 'Q_RES_0402LF-33,5%,1/16W,EMPTY,CS03302JB29':;

SECTION_NUMBER 1
 '@T6G_MB_LIB.T6G(SCH_1):PAGE89_I51@PURE_QUANTA.Q_RES(CHIPS)':
 C_PATH='@t6g_mb_lib.t6g(sch_1):page89_i51@pure_quanta.q_res(chips)';

PART_NAME
 R361 'Q_RES_0402LF-33,5%,1/16W,EMPTY,CS03302JB29':;

SECTION_NUMBER 1
 '@T6G_MB_LIB.T6G(SCH_1):PAGE89_I50@PURE_QUANTA.Q_RES(CHIPS)':
 C_PATH='@t6g_mb_lib.t6g(sch_1):page89_i50@pure_quanta.q_res(chips)';

PART_NAME
 R360 'Q_RES_0402LF-33,5%,1/16W,EMPTY,CS03302JB29':;

SECTION_NUMBER 1
 '@T6G_MB_LIB.T6G(SCH_1):PAGE89_I52@PURE_QUANTA.Q_RES(CHIPS)':
 C_PATH='@t6g_mb_lib.t6g(sch_1):page89_i52@pure_quanta.q_res(chips)';

PART_NAME
 R359 'Q_RES_0402LF-33,5%,1/16W,EMPTY,CS03302JB29':;

SECTION_NUMBER 1
 '@T6G_MB_LIB.T6G(SCH_1):PAGE89_I53@PURE_QUANTA.Q_RES(CHIPS)':
 C_PATH='@t6g_mb_lib.t6g(sch_1):page89_i53@pure_quanta.q_res(chips)';

PART_NAME
 R358 'Q_RES_0402LF-33,5%,1/16W,CHIP,CS03302JB29':;

SECTION_NUMBER 1
 '@T6G_MB_LIB.T6G(SCH_1):PAGE89_I37@PURE_QUANTA.Q_RES(CHIPS)':
 C_PATH='@t6g_mb_lib.t6g(sch_1):page89_i37@pure_quanta.q_res(chips)';

PART_NAME
 R357 'Q_RES_0402LF-33,5%,1/16W,CHIP,CS03302JB29':;

SECTION_NUMBER 1
 '@T6G_MB_LIB.T6G(SCH_1):PAGE89_I36@PURE_QUANTA.Q_RES(CHIPS)':
 C_PATH='@t6g_mb_lib.t6g(sch_1):page89_i36@pure_quanta.q_res(chips)';

PART_NAME
 R356 'Q_RES_0402LF-33,5%,1/16W,CHIP,CS03302JB29':;

SECTION_NUMBER 1
 '@T6G_MB_LIB.T6G(SCH_1):PAGE89_I38@PURE_QUANTA.Q_RES(CHIPS)':
 C_PATH='@t6g_mb_lib.t6g(sch_1):page89_i38@pure_quanta.q_res(chips)';

PART_NAME
 R355 'Q_RES_0402LF-1K,1%,1/16W,CHIP,TMP_QCS21002FB24':;

SECTION_NUMBER 1
 '@T6G_MB_LIB.T6G(SCH_1):PAGE89_I43@PURE_QUANTA.Q_RES(CHIPS)':
 C_PATH='@t6g_mb_lib.t6g(sch_1):page89_i43@pure_quanta.q_res(chips)';

PART_NAME
 R354 'Q_RES_0402LF-4.32K,1%,1/16W,CHIP,TMP_QCS24322FB14':;

SECTION_NUMBER 1
 '@T6G_MB_LIB.T6G(SCH_1):PAGE89_I44@PURE_QUANTA.Q_RES(CHIPS)':
 C_PATH='@t6g_mb_lib.t6g(sch_1):page89_i44@pure_quanta.q_res(chips)';

PART_NAME
 R353 'Q_RES_0402LF-150,1%,1/16W,CHIP,TMP_QCS11502FB21':;

SECTION_NUMBER 1
 '@T6G_MB_LIB.T6G(SCH_1):PAGE89_I32@PURE_QUANTA.Q_RES(CHIPS)':
 C_PATH='@t6g_mb_lib.t6g(sch_1):page89_i32@pure_quanta.q_res(chips)';

PART_NAME
 R352 'Q_RES_0402LF-150,1%,1/16W,CHIP,TMP_QCS11502FB21':;

SECTION_NUMBER 1
 '@T6G_MB_LIB.T6G(SCH_1):PAGE89_I31@PURE_QUANTA.Q_RES(CHIPS)':
 C_PATH='@t6g_mb_lib.t6g(sch_1):page89_i31@pure_quanta.q_res(chips)';

PART_NAME
 R351 'Q_RES_0402LF-150,1%,1/16W,CHIP,TMP_QCS11502FB21':;

SECTION_NUMBER 1
 '@T6G_MB_LIB.T6G(SCH_1):PAGE89_I30@PURE_QUANTA.Q_RES(CHIPS)':
 C_PATH='@t6g_mb_lib.t6g(sch_1):page89_i30@pure_quanta.q_res(chips)';

PART_NAME
 R350 'Q_RES_0402LF-0,5%,1/16W,EMPTY,CS00002JB38':;

SECTION_NUMBER 1
 '@T6G_MB_LIB.T6G(SCH_1):PAGE89_I26@PURE_QUANTA.Q_RES(CHIPS)':
 C_PATH='@t6g_mb_lib.t6g(sch_1):page89_i26@pure_quanta.q_res(chips)';

PART_NAME
 R349 'Q_RES_0402LF-0,5%,1/16W,EMPTY,CS00002JB38':;

SECTION_NUMBER 1
 '@T6G_MB_LIB.T6G(SCH_1):PAGE89_I25@PURE_QUANTA.Q_RES(CHIPS)':
 C_PATH='@t6g_mb_lib.t6g(sch_1):page89_i25@pure_quanta.q_res(chips)';

PART_NAME
 R348 'Q_RES_0402LF-0,5%,1/16W,EMPTY,CS00002JB38':;

SECTION_NUMBER 1
 '@T6G_MB_LIB.T6G(SCH_1):PAGE89_I27@PURE_QUANTA.Q_RES(CHIPS)':
 C_PATH='@t6g_mb_lib.t6g(sch_1):page89_i27@pure_quanta.q_res(chips)';

PART_NAME
 R347 'Q_RES_0402LF-33,5%,1/16W,CHIP,CS03302JB29':;

SECTION_NUMBER 1
 '@T6G_MB_LIB.T6G(SCH_1):PAGE89_I13@PURE_QUANTA.Q_RES(CHIPS)':
 C_PATH='@t6g_mb_lib.t6g(sch_1):page89_i13@pure_quanta.q_res(chips)';

PART_NAME
 R346 'Q_RES_0402LF-33,5%,1/16W,CHIP,CS03302JB29':;

SECTION_NUMBER 1
 '@T6G_MB_LIB.T6G(SCH_1):PAGE89_I14@PURE_QUANTA.Q_RES(CHIPS)':
 C_PATH='@t6g_mb_lib.t6g(sch_1):page89_i14@pure_quanta.q_res(chips)';

PART_NAME
 R345 'Q_RES_0402LF-0,5%,1/16W,CHIP,CS00002JB38':;

SECTION_NUMBER 1
 '@T6G_MB_LIB.T6G(SCH_1):PAGE89_I15@PURE_QUANTA.Q_RES(CHIPS)':
 C_PATH='@t6g_mb_lib.t6g(sch_1):page89_i15@pure_quanta.q_res(chips)';

PART_NAME
 R344 'Q_RES_0402LF-0,5%,1/16W,CHIP,CS00002JB38':;

SECTION_NUMBER 1
 '@T6G_MB_LIB.T6G(SCH_1):PAGE89_I16@PURE_QUANTA.Q_RES(CHIPS)':
 C_PATH='@t6g_mb_lib.t6g(sch_1):page89_i16@pure_quanta.q_res(chips)';

PART_NAME
 R343 'Q_RES_0402LF-33,5%,1/16W,CHIP,CS03302JB29':;

SECTION_NUMBER 1
 '@T6G_MB_LIB.T6G(SCH_1):PAGE89_I17@PURE_QUANTA.Q_RES(CHIPS)':
 C_PATH='@t6g_mb_lib.t6g(sch_1):page89_i17@pure_quanta.q_res(chips)';

PART_NAME
 R342 'Q_RES_0402LF-33,5%,1/16W,CHIP,CS03302JB29':;

SECTION_NUMBER 1
 '@T6G_MB_LIB.T6G(SCH_1):PAGE89_I18@PURE_QUANTA.Q_RES(CHIPS)':
 C_PATH='@t6g_mb_lib.t6g(sch_1):page89_i18@pure_quanta.q_res(chips)';

PART_NAME
 R341 'Q_RES_0402LF-0,5%,1/16W,CHIP,CS00002JB38':;

SECTION_NUMBER 1
 '@T6G_MB_LIB.T6G(SCH_1):PAGE89_I19@PURE_QUANTA.Q_RES(CHIPS)':
 C_PATH='@t6g_mb_lib.t6g(sch_1):page89_i19@pure_quanta.q_res(chips)';

PART_NAME
 R340 'Q_RES_0402LF-0,5%,1/16W,CHIP,CS00002JB38':;

SECTION_NUMBER 1
 '@T6G_MB_LIB.T6G(SCH_1):PAGE89_I20@PURE_QUANTA.Q_RES(CHIPS)':
 C_PATH='@t6g_mb_lib.t6g(sch_1):page89_i20@pure_quanta.q_res(chips)';

PART_NAME
 R339 'Q_RES_0402LF-33,5%,1/16W,CHIP,CS03302JB29':;

SECTION_NUMBER 1
 '@T6G_MB_LIB.T6G(SCH_1):PAGE89_I21@PURE_QUANTA.Q_RES(CHIPS)':
 C_PATH='@t6g_mb_lib.t6g(sch_1):page89_i21@pure_quanta.q_res(chips)';

PART_NAME
 R338 'Q_RES_0402LF-33,5%,1/16W,CHIP,CS03302JB29':;

SECTION_NUMBER 1
 '@T6G_MB_LIB.T6G(SCH_1):PAGE89_I23@PURE_QUANTA.Q_RES(CHIPS)':
 C_PATH='@t6g_mb_lib.t6g(sch_1):page89_i23@pure_quanta.q_res(chips)';

PART_NAME
 R337 'Q_RES_0402LF-0,5%,1/16W,CHIP,CS00002JB38':;

SECTION_NUMBER 1
 '@T6G_MB_LIB.T6G(SCH_1):PAGE89_I22@PURE_QUANTA.Q_RES(CHIPS)':
 C_PATH='@t6g_mb_lib.t6g(sch_1):page89_i22@pure_quanta.q_res(chips)';

PART_NAME
 R336 'Q_RES_0402LF-0,5%,1/16W,CHIP,CS00002JB38':;

SECTION_NUMBER 1
 '@T6G_MB_LIB.T6G(SCH_1):PAGE89_I24@PURE_QUANTA.Q_RES(CHIPS)':
 C_PATH='@t6g_mb_lib.t6g(sch_1):page89_i24@pure_quanta.q_res(chips)';

PART_NAME
 R89 'Q_RES_0402LF-1K,1%,1/16W,CHIP,TMP_QCS21002FB24':;

SECTION_NUMBER 1
 '@T6G_MB_LIB.T6G(SCH_1):PAGE89_I46@PURE_QUANTA.Q_RES(CHIPS)':
 C_PATH='@t6g_mb_lib.t6g(sch_1):page89_i46@pure_quanta.q_res(chips)';

PART_NAME
 R88 'Q_RES_0402LF-150,1%,1/16W,CHIP,TMP_QCS11502FB21':;

SECTION_NUMBER 1
 '@T6G_MB_LIB.T6G(SCH_1):PAGE89_I29@PURE_QUANTA.Q_RES(CHIPS)':
 C_PATH='@t6g_mb_lib.t6g(sch_1):page89_i29@pure_quanta.q_res(chips)';

PART_NAME
 C1212 'Q_CAP_0402-0.1UF,25V,10%,X7R,CH4104K1B00':;

SECTION_NUMBER 1
 '@T6G_MB_LIB.T6G(SCH_1):PAGE89_I54@PURE_QUANTA.Q_CAP(CHIPS)':
 C_PATH='@t6g_mb_lib.t6g(sch_1):page89_i54@pure_quanta.q_cap(chips)';

PART_NAME
 C102 'Q_CAP_C0402-1UF,25V,10%,X6S,CH5104KEB02':;

SECTION_NUMBER 1
 '@T6G_MB_LIB.T6G(SCH_1):PAGE89_I40@PURE_QUANTA.Q_CAP(CHIPS)':
 C_PATH='@t6g_mb_lib.t6g(sch_1):page89_i40@pure_quanta.q_cap(chips)';

PART_NAME
 C1045 'Q_CAP_C0402-10UF,4V,20%,X6S,CH610KMEB09':;

SECTION_NUMBER 1
 '@T6G_MB_LIB.T6G(SCH_1):PAGE77_I283@PURE_QUANTA.Q_CAP(CHIPS)':
 C_PATH='@t6g_mb_lib.t6g(sch_1):page77_i283@pure_quanta.q_cap(chips)';

PART_NAME
 C1044 'Q_CAP_C0402-10UF,4V,20%,X6S,CH610KMEB09':;

SECTION_NUMBER 1
 '@T6G_MB_LIB.T6G(SCH_1):PAGE77_I274@PURE_QUANTA.Q_CAP(CHIPS)':
 C_PATH='@t6g_mb_lib.t6g(sch_1):page77_i274@pure_quanta.q_cap(chips)';

PART_NAME
 C1043 'Q_CAP_C0402-10UF,4V,20%,X6S,CH610KMEB09':;

SECTION_NUMBER 1
 '@T6G_MB_LIB.T6G(SCH_1):PAGE77_I272@PURE_QUANTA.Q_CAP(CHIPS)':
 C_PATH='@t6g_mb_lib.t6g(sch_1):page77_i272@pure_quanta.q_cap(chips)';

PART_NAME
 C1041 'Q_CAP_C0402-10UF,4V,20%,X6S,CH610KMEB09':;

SECTION_NUMBER 1
 '@T6G_MB_LIB.T6G(SCH_1):PAGE77_I285@PURE_QUANTA.Q_CAP(CHIPS)':
 C_PATH='@t6g_mb_lib.t6g(sch_1):page77_i285@pure_quanta.q_cap(chips)';

PART_NAME
 C1040 'Q_CAP_C0402-10UF,4V,20%,X6S,CH610KMEB09':;

SECTION_NUMBER 1
 '@T6G_MB_LIB.T6G(SCH_1):PAGE77_I281@PURE_QUANTA.Q_CAP(CHIPS)':
 C_PATH='@t6g_mb_lib.t6g(sch_1):page77_i281@pure_quanta.q_cap(chips)';

PART_NAME
 C1039 'Q_CAP_C0402-10UF,4V,20%,X6S,CH610KMEB09':;

SECTION_NUMBER 1
 '@T6G_MB_LIB.T6G(SCH_1):PAGE77_I278@PURE_QUANTA.Q_CAP(CHIPS)':
 C_PATH='@t6g_mb_lib.t6g(sch_1):page77_i278@pure_quanta.q_cap(chips)';

PART_NAME
 C1038 'Q_CAP_C0402-10UF,4V,20%,X6S,CH610KMEB09':;

SECTION_NUMBER 1
 '@T6G_MB_LIB.T6G(SCH_1):PAGE77_I276@PURE_QUANTA.Q_CAP(CHIPS)':
 C_PATH='@t6g_mb_lib.t6g(sch_1):page77_i276@pure_quanta.q_cap(chips)';

PART_NAME
 C1037 'Q_CAP_C0402-10UF,4V,20%,X6S,CH610KMEB09':;

SECTION_NUMBER 1
 '@T6G_MB_LIB.T6G(SCH_1):PAGE77_I286@PURE_QUANTA.Q_CAP(CHIPS)':
 C_PATH='@t6g_mb_lib.t6g(sch_1):page77_i286@pure_quanta.q_cap(chips)';

PART_NAME
 C1036 'Q_CAP_C0402-10UF,4V,20%,X6S,CH610KMEB09':;

SECTION_NUMBER 1
 '@T6G_MB_LIB.T6G(SCH_1):PAGE77_I282@PURE_QUANTA.Q_CAP(CHIPS)':
 C_PATH='@t6g_mb_lib.t6g(sch_1):page77_i282@pure_quanta.q_cap(chips)';

PART_NAME
 C1035 'Q_CAP_C0402-10UF,4V,20%,X6S,CH610KMEB09':;

SECTION_NUMBER 1
 '@T6G_MB_LIB.T6G(SCH_1):PAGE77_I280@PURE_QUANTA.Q_CAP(CHIPS)':
 C_PATH='@t6g_mb_lib.t6g(sch_1):page77_i280@pure_quanta.q_cap(chips)';

PART_NAME
 C1034 'Q_CAP_C0402-10UF,4V,20%,X6S,CH610KMEB09':;

SECTION_NUMBER 1
 '@T6G_MB_LIB.T6G(SCH_1):PAGE77_I279@PURE_QUANTA.Q_CAP(CHIPS)':
 C_PATH='@t6g_mb_lib.t6g(sch_1):page77_i279@pure_quanta.q_cap(chips)';

PART_NAME
 C1033 'Q_CAP_C0402-10UF,4V,20%,X6S,CH610KMEB09':;

SECTION_NUMBER 1
 '@T6G_MB_LIB.T6G(SCH_1):PAGE77_I303@PURE_QUANTA.Q_CAP(CHIPS)':
 C_PATH='@t6g_mb_lib.t6g(sch_1):page77_i303@pure_quanta.q_cap(chips)';

PART_NAME
 C1032 'Q_CAP_C0402-10UF,4V,20%,X6S,CH610KMEB09':;

SECTION_NUMBER 1
 '@T6G_MB_LIB.T6G(SCH_1):PAGE77_I294@PURE_QUANTA.Q_CAP(CHIPS)':
 C_PATH='@t6g_mb_lib.t6g(sch_1):page77_i294@pure_quanta.q_cap(chips)';

PART_NAME
 C1031 'Q_CAP_C0402-10UF,4V,20%,X6S,CH610KMEB09':;

SECTION_NUMBER 1
 '@T6G_MB_LIB.T6G(SCH_1):PAGE77_I289@PURE_QUANTA.Q_CAP(CHIPS)':
 C_PATH='@t6g_mb_lib.t6g(sch_1):page77_i289@pure_quanta.q_cap(chips)';

PART_NAME
 C1030 'Q_CAP_C0402-10UF,4V,20%,X6S,CH610KMEB09':;

SECTION_NUMBER 1
 '@T6G_MB_LIB.T6G(SCH_1):PAGE77_I288@PURE_QUANTA.Q_CAP(CHIPS)':
 C_PATH='@t6g_mb_lib.t6g(sch_1):page77_i288@pure_quanta.q_cap(chips)';

PART_NAME
 C1029 'Q_CAP_C0402-10UF,4V,20%,X6S,CH610KMEB09':;

SECTION_NUMBER 1
 '@T6G_MB_LIB.T6G(SCH_1):PAGE77_I304@PURE_QUANTA.Q_CAP(CHIPS)':
 C_PATH='@t6g_mb_lib.t6g(sch_1):page77_i304@pure_quanta.q_cap(chips)';

PART_NAME
 C1028 'Q_CAP_C0402-10UF,4V,20%,X6S,CH610KMEB09':;

SECTION_NUMBER 1
 '@T6G_MB_LIB.T6G(SCH_1):PAGE77_I295@PURE_QUANTA.Q_CAP(CHIPS)':
 C_PATH='@t6g_mb_lib.t6g(sch_1):page77_i295@pure_quanta.q_cap(chips)';

PART_NAME
 C1027 'Q_CAP_C0402-10UF,4V,20%,X6S,CH610KMEB09':;

SECTION_NUMBER 1
 '@T6G_MB_LIB.T6G(SCH_1):PAGE77_I292@PURE_QUANTA.Q_CAP(CHIPS)':
 C_PATH='@t6g_mb_lib.t6g(sch_1):page77_i292@pure_quanta.q_cap(chips)';

PART_NAME
 C1026 'Q_CAP_C0402-10UF,4V,20%,X6S,CH610KMEB09':;

SECTION_NUMBER 1
 '@T6G_MB_LIB.T6G(SCH_1):PAGE77_I290@PURE_QUANTA.Q_CAP(CHIPS)':
 C_PATH='@t6g_mb_lib.t6g(sch_1):page77_i290@pure_quanta.q_cap(chips)';

PART_NAME
 C1025 'Q_CAP_C0402-10UF,4V,20%,X6S,CH610KMEB09':;

SECTION_NUMBER 1
 '@T6G_MB_LIB.T6G(SCH_1):PAGE77_I305@PURE_QUANTA.Q_CAP(CHIPS)':
 C_PATH='@t6g_mb_lib.t6g(sch_1):page77_i305@pure_quanta.q_cap(chips)';

PART_NAME
 C1024 'Q_CAP_C0402-10UF,4V,20%,X6S,CH610KMEB09':;

SECTION_NUMBER 1
 '@T6G_MB_LIB.T6G(SCH_1):PAGE77_I296@PURE_QUANTA.Q_CAP(CHIPS)':
 C_PATH='@t6g_mb_lib.t6g(sch_1):page77_i296@pure_quanta.q_cap(chips)';

PART_NAME
 C1023 'Q_CAP_C0402-10UF,4V,20%,X6S,CH610KMEB09':;

SECTION_NUMBER 1
 '@T6G_MB_LIB.T6G(SCH_1):PAGE77_I293@PURE_QUANTA.Q_CAP(CHIPS)':
 C_PATH='@t6g_mb_lib.t6g(sch_1):page77_i293@pure_quanta.q_cap(chips)';

PART_NAME
 C1022 'Q_CAP_C0402-10UF,4V,20%,X6S,CH610KMEB09':;

SECTION_NUMBER 1
 '@T6G_MB_LIB.T6G(SCH_1):PAGE77_I291@PURE_QUANTA.Q_CAP(CHIPS)':
 C_PATH='@t6g_mb_lib.t6g(sch_1):page77_i291@pure_quanta.q_cap(chips)';

PART_NAME
 C1021 'Q_CAP_C0402-10UF,4V,20%,X6S,CH610KMEB09':;

SECTION_NUMBER 1
 '@T6G_MB_LIB.T6G(SCH_1):PAGE77_I307@PURE_QUANTA.Q_CAP(CHIPS)':
 C_PATH='@t6g_mb_lib.t6g(sch_1):page77_i307@pure_quanta.q_cap(chips)';

PART_NAME
 C1020 'Q_CAP_C0402-10UF,4V,20%,X6S,CH610KMEB09':;

SECTION_NUMBER 1
 '@T6G_MB_LIB.T6G(SCH_1):PAGE77_I301@PURE_QUANTA.Q_CAP(CHIPS)':
 C_PATH='@t6g_mb_lib.t6g(sch_1):page77_i301@pure_quanta.q_cap(chips)';

PART_NAME
 C1019 'Q_CAP_C0402-10UF,4V,20%,X6S,CH610KMEB09':;

SECTION_NUMBER 1
 '@T6G_MB_LIB.T6G(SCH_1):PAGE77_I298@PURE_QUANTA.Q_CAP(CHIPS)':
 C_PATH='@t6g_mb_lib.t6g(sch_1):page77_i298@pure_quanta.q_cap(chips)';

PART_NAME
 C1018 'Q_CAP_C0402-10UF,4V,20%,X6S,CH610KMEB09':;

SECTION_NUMBER 1
 '@T6G_MB_LIB.T6G(SCH_1):PAGE77_I297@PURE_QUANTA.Q_CAP(CHIPS)':
 C_PATH='@t6g_mb_lib.t6g(sch_1):page77_i297@pure_quanta.q_cap(chips)';

PART_NAME
 C1017 'Q_CAP_C0402-10UF,4V,20%,X6S,CH610KMEB09':;

SECTION_NUMBER 1
 '@T6G_MB_LIB.T6G(SCH_1):PAGE77_I308@PURE_QUANTA.Q_CAP(CHIPS)':
 C_PATH='@t6g_mb_lib.t6g(sch_1):page77_i308@pure_quanta.q_cap(chips)';

PART_NAME
 C1016 'Q_CAP_C0402-10UF,4V,20%,X6S,CH610KMEB09':;

SECTION_NUMBER 1
 '@T6G_MB_LIB.T6G(SCH_1):PAGE77_I302@PURE_QUANTA.Q_CAP(CHIPS)':
 C_PATH='@t6g_mb_lib.t6g(sch_1):page77_i302@pure_quanta.q_cap(chips)';

PART_NAME
 C1015 'Q_CAP_C0402-10UF,4V,20%,X6S,CH610KMEB09':;

SECTION_NUMBER 1
 '@T6G_MB_LIB.T6G(SCH_1):PAGE77_I300@PURE_QUANTA.Q_CAP(CHIPS)':
 C_PATH='@t6g_mb_lib.t6g(sch_1):page77_i300@pure_quanta.q_cap(chips)';

PART_NAME
 C1014 'Q_CAP_C0402-10UF,4V,20%,X6S,CH610KMEB09':;

SECTION_NUMBER 1
 '@T6G_MB_LIB.T6G(SCH_1):PAGE77_I299@PURE_QUANTA.Q_CAP(CHIPS)':
 C_PATH='@t6g_mb_lib.t6g(sch_1):page77_i299@pure_quanta.q_cap(chips)';

PART_NAME
 C1013 'Q_CAP_C0402-10UF,4V,20%,X6S,CH610KMEB09':;

SECTION_NUMBER 1
 '@T6G_MB_LIB.T6G(SCH_1):PAGE77_I333@PURE_QUANTA.Q_CAP(CHIPS)':
 C_PATH='@t6g_mb_lib.t6g(sch_1):page77_i333@pure_quanta.q_cap(chips)';

PART_NAME
 C1012 'Q_CAP_C0402-10UF,4V,20%,X6S,CH610KMEB09':;

SECTION_NUMBER 1
 '@T6G_MB_LIB.T6G(SCH_1):PAGE77_I321@PURE_QUANTA.Q_CAP(CHIPS)':
 C_PATH='@t6g_mb_lib.t6g(sch_1):page77_i321@pure_quanta.q_cap(chips)';

PART_NAME
 C1011 'Q_CAP_C0402-10UF,4V,20%,X6S,CH610KMEB09':;

SECTION_NUMBER 1
 '@T6G_MB_LIB.T6G(SCH_1):PAGE77_I317@PURE_QUANTA.Q_CAP(CHIPS)':
 C_PATH='@t6g_mb_lib.t6g(sch_1):page77_i317@pure_quanta.q_cap(chips)';

PART_NAME
 C1010 'Q_CAP_C0402-10UF,4V,20%,X6S,CH610KMEB09':;

SECTION_NUMBER 1
 '@T6G_MB_LIB.T6G(SCH_1):PAGE77_I316@PURE_QUANTA.Q_CAP(CHIPS)':
 C_PATH='@t6g_mb_lib.t6g(sch_1):page77_i316@pure_quanta.q_cap(chips)';

PART_NAME
 C1009 'Q_CAP_C0402-10UF,4V,20%,X6S,CH610KMEB09':;

SECTION_NUMBER 1
 '@T6G_MB_LIB.T6G(SCH_1):PAGE77_I335@PURE_QUANTA.Q_CAP(CHIPS)':
 C_PATH='@t6g_mb_lib.t6g(sch_1):page77_i335@pure_quanta.q_cap(chips)';

PART_NAME
 C1008 'Q_CAP_C0402-10UF,4V,20%,X6S,CH610KMEB09':;

SECTION_NUMBER 1
 '@T6G_MB_LIB.T6G(SCH_1):PAGE77_I323@PURE_QUANTA.Q_CAP(CHIPS)':
 C_PATH='@t6g_mb_lib.t6g(sch_1):page77_i323@pure_quanta.q_cap(chips)';

PART_NAME
 C1007 'Q_CAP_C0402-10UF,4V,20%,X6S,CH610KMEB09':;

SECTION_NUMBER 1
 '@T6G_MB_LIB.T6G(SCH_1):PAGE77_I320@PURE_QUANTA.Q_CAP(CHIPS)':
 C_PATH='@t6g_mb_lib.t6g(sch_1):page77_i320@pure_quanta.q_cap(chips)';

PART_NAME
 C1006 'Q_CAP_C0402-10UF,4V,20%,X6S,CH610KMEB09':;

SECTION_NUMBER 1
 '@T6G_MB_LIB.T6G(SCH_1):PAGE77_I318@PURE_QUANTA.Q_CAP(CHIPS)':
 C_PATH='@t6g_mb_lib.t6g(sch_1):page77_i318@pure_quanta.q_cap(chips)';

PART_NAME
 C1005 'Q_CAP_C0402-10UF,4V,20%,X6S,CH610KMEB09':;

SECTION_NUMBER 1
 '@T6G_MB_LIB.T6G(SCH_1):PAGE77_I336@PURE_QUANTA.Q_CAP(CHIPS)':
 C_PATH='@t6g_mb_lib.t6g(sch_1):page77_i336@pure_quanta.q_cap(chips)';

PART_NAME
 C1004 'Q_CAP_C0402-10UF,4V,20%,X6S,CH610KMEB09':;

SECTION_NUMBER 1
 '@T6G_MB_LIB.T6G(SCH_1):PAGE77_I330@PURE_QUANTA.Q_CAP(CHIPS)':
 C_PATH='@t6g_mb_lib.t6g(sch_1):page77_i330@pure_quanta.q_cap(chips)';

PART_NAME
 C1003 'Q_CAP_C0402-10UF,4V,20%,X6S,CH610KMEB09':;

SECTION_NUMBER 1
 '@T6G_MB_LIB.T6G(SCH_1):PAGE77_I326@PURE_QUANTA.Q_CAP(CHIPS)':
 C_PATH='@t6g_mb_lib.t6g(sch_1):page77_i326@pure_quanta.q_cap(chips)';

PART_NAME
 C1002 'Q_CAP_C0402-10UF,4V,20%,X6S,CH610KMEB09':;

SECTION_NUMBER 1
 '@T6G_MB_LIB.T6G(SCH_1):PAGE77_I324@PURE_QUANTA.Q_CAP(CHIPS)':
 C_PATH='@t6g_mb_lib.t6g(sch_1):page77_i324@pure_quanta.q_cap(chips)';

PART_NAME
 C1001 'Q_CAP_C0402-10UF,4V,20%,X6S,CH610KMEB09':;

SECTION_NUMBER 1
 '@T6G_MB_LIB.T6G(SCH_1):PAGE77_I338@PURE_QUANTA.Q_CAP(CHIPS)':
 C_PATH='@t6g_mb_lib.t6g(sch_1):page77_i338@pure_quanta.q_cap(chips)';

PART_NAME
 C1000 'Q_CAP_C0402-10UF,4V,20%,X6S,CH610KMEB09':;

SECTION_NUMBER 1
 '@T6G_MB_LIB.T6G(SCH_1):PAGE77_I332@PURE_QUANTA.Q_CAP(CHIPS)':
 C_PATH='@t6g_mb_lib.t6g(sch_1):page77_i332@pure_quanta.q_cap(chips)';

PART_NAME
 C999 'Q_CAP_C0402-10UF,4V,20%,X6S,CH610KMEB09':;

SECTION_NUMBER 1
 '@T6G_MB_LIB.T6G(SCH_1):PAGE77_I328@PURE_QUANTA.Q_CAP(CHIPS)':
 C_PATH='@t6g_mb_lib.t6g(sch_1):page77_i328@pure_quanta.q_cap(chips)';

PART_NAME
 C998 'Q_CAP_C0402-10UF,4V,20%,X6S,CH610KMEB09':;

SECTION_NUMBER 1
 '@T6G_MB_LIB.T6G(SCH_1):PAGE77_I327@PURE_QUANTA.Q_CAP(CHIPS)':
 C_PATH='@t6g_mb_lib.t6g(sch_1):page77_i327@pure_quanta.q_cap(chips)';

PART_NAME
 C997 'Q_CAP_C0402-10UF,4V,20%,X6S,CH610KMEB09':;

SECTION_NUMBER 1
 '@T6G_MB_LIB.T6G(SCH_1):PAGE77_I365@PURE_QUANTA.Q_CAP(CHIPS)':
 C_PATH='@t6g_mb_lib.t6g(sch_1):page77_i365@pure_quanta.q_cap(chips)';

PART_NAME
 C996 'Q_CAP_C0402-10UF,4V,20%,X6S,CH610KMEB09':;

SECTION_NUMBER 1
 '@T6G_MB_LIB.T6G(SCH_1):PAGE77_I356@PURE_QUANTA.Q_CAP(CHIPS)':
 C_PATH='@t6g_mb_lib.t6g(sch_1):page77_i356@pure_quanta.q_cap(chips)';

PART_NAME
 C995 'Q_CAP_C0402-10UF,4V,20%,X6S,CH610KMEB09':;

SECTION_NUMBER 1
 '@T6G_MB_LIB.T6G(SCH_1):PAGE77_I351@PURE_QUANTA.Q_CAP(CHIPS)':
 C_PATH='@t6g_mb_lib.t6g(sch_1):page77_i351@pure_quanta.q_cap(chips)';

PART_NAME
 C994 'Q_CAP_C0402-10UF,4V,20%,X6S,CH610KMEB09':;

SECTION_NUMBER 1
 '@T6G_MB_LIB.T6G(SCH_1):PAGE77_I350@PURE_QUANTA.Q_CAP(CHIPS)':
 C_PATH='@t6g_mb_lib.t6g(sch_1):page77_i350@pure_quanta.q_cap(chips)';

PART_NAME
 C993 'Q_CAP_C0402-10UF,4V,20%,X6S,CH610KMEB09':;

SECTION_NUMBER 1
 '@T6G_MB_LIB.T6G(SCH_1):PAGE77_I366@PURE_QUANTA.Q_CAP(CHIPS)':
 C_PATH='@t6g_mb_lib.t6g(sch_1):page77_i366@pure_quanta.q_cap(chips)';

PART_NAME
 C992 'Q_CAP_C0402-10UF,4V,20%,X6S,CH610KMEB09':;

SECTION_NUMBER 1
 '@T6G_MB_LIB.T6G(SCH_1):PAGE77_I357@PURE_QUANTA.Q_CAP(CHIPS)':
 C_PATH='@t6g_mb_lib.t6g(sch_1):page77_i357@pure_quanta.q_cap(chips)';

PART_NAME
 C991 'Q_CAP_C0402-10UF,4V,20%,X6S,CH610KMEB09':;

SECTION_NUMBER 1
 '@T6G_MB_LIB.T6G(SCH_1):PAGE77_I353@PURE_QUANTA.Q_CAP(CHIPS)':
 C_PATH='@t6g_mb_lib.t6g(sch_1):page77_i353@pure_quanta.q_cap(chips)';

PART_NAME
 C990 'Q_CAP_C0402-10UF,4V,20%,X6S,CH610KMEB09':;

SECTION_NUMBER 1
 '@T6G_MB_LIB.T6G(SCH_1):PAGE77_I352@PURE_QUANTA.Q_CAP(CHIPS)':
 C_PATH='@t6g_mb_lib.t6g(sch_1):page77_i352@pure_quanta.q_cap(chips)';

PART_NAME
 C989 'Q_CAP_C0402-10UF,4V,20%,X6S,CH610KMEB09':;

SECTION_NUMBER 1
 '@T6G_MB_LIB.T6G(SCH_1):PAGE77_I367@PURE_QUANTA.Q_CAP(CHIPS)':
 C_PATH='@t6g_mb_lib.t6g(sch_1):page77_i367@pure_quanta.q_cap(chips)';

PART_NAME
 C988 'Q_CAP_C0402-10UF,4V,20%,X6S,CH610KMEB09':;

SECTION_NUMBER 1
 '@T6G_MB_LIB.T6G(SCH_1):PAGE77_I358@PURE_QUANTA.Q_CAP(CHIPS)':
 C_PATH='@t6g_mb_lib.t6g(sch_1):page77_i358@pure_quanta.q_cap(chips)';

PART_NAME
 C987 'Q_CAP_C0402-10UF,4V,20%,X6S,CH610KMEB09':;

SECTION_NUMBER 1
 '@T6G_MB_LIB.T6G(SCH_1):PAGE77_I355@PURE_QUANTA.Q_CAP(CHIPS)':
 C_PATH='@t6g_mb_lib.t6g(sch_1):page77_i355@pure_quanta.q_cap(chips)';

PART_NAME
 C986 'Q_CAP_C0402-10UF,4V,20%,X6S,CH610KMEB09':;

SECTION_NUMBER 1
 '@T6G_MB_LIB.T6G(SCH_1):PAGE77_I354@PURE_QUANTA.Q_CAP(CHIPS)':
 C_PATH='@t6g_mb_lib.t6g(sch_1):page77_i354@pure_quanta.q_cap(chips)';

PART_NAME
 C985 'Q_CAP_C0402-10UF,4V,20%,X6S,CH610KMEB09':;

SECTION_NUMBER 1
 '@T6G_MB_LIB.T6G(SCH_1):PAGE77_I375@PURE_QUANTA.Q_CAP(CHIPS)':
 C_PATH='@t6g_mb_lib.t6g(sch_1):page77_i375@pure_quanta.q_cap(chips)';

PART_NAME
 C984 'Q_CAP_C0402-10UF,4V,20%,X6S,CH610KMEB09':;

SECTION_NUMBER 1
 '@T6G_MB_LIB.T6G(SCH_1):PAGE77_I363@PURE_QUANTA.Q_CAP(CHIPS)':
 C_PATH='@t6g_mb_lib.t6g(sch_1):page77_i363@pure_quanta.q_cap(chips)';

PART_NAME
 C983 'Q_CAP_C0402-10UF,4V,20%,X6S,CH610KMEB09':;

SECTION_NUMBER 1
 '@T6G_MB_LIB.T6G(SCH_1):PAGE77_I360@PURE_QUANTA.Q_CAP(CHIPS)':
 C_PATH='@t6g_mb_lib.t6g(sch_1):page77_i360@pure_quanta.q_cap(chips)';

PART_NAME
 C982 'Q_CAP_C0402-10UF,4V,20%,X6S,CH610KMEB09':;

SECTION_NUMBER 1
 '@T6G_MB_LIB.T6G(SCH_1):PAGE77_I359@PURE_QUANTA.Q_CAP(CHIPS)':
 C_PATH='@t6g_mb_lib.t6g(sch_1):page77_i359@pure_quanta.q_cap(chips)';

PART_NAME
 C981 'Q_CAP_C0402-10UF,4V,20%,X6S,CH610KMEB09':;

SECTION_NUMBER 1
 '@T6G_MB_LIB.T6G(SCH_1):PAGE77_I376@PURE_QUANTA.Q_CAP(CHIPS)':
 C_PATH='@t6g_mb_lib.t6g(sch_1):page77_i376@pure_quanta.q_cap(chips)';

PART_NAME
 C980 'Q_CAP_C0402-10UF,4V,20%,X6S,CH610KMEB09':;

SECTION_NUMBER 1
 '@T6G_MB_LIB.T6G(SCH_1):PAGE77_I364@PURE_QUANTA.Q_CAP(CHIPS)':
 C_PATH='@t6g_mb_lib.t6g(sch_1):page77_i364@pure_quanta.q_cap(chips)';

PART_NAME
 C979 'Q_CAP_C0402-10UF,4V,20%,X6S,CH610KMEB09':;

SECTION_NUMBER 1
 '@T6G_MB_LIB.T6G(SCH_1):PAGE77_I362@PURE_QUANTA.Q_CAP(CHIPS)':
 C_PATH='@t6g_mb_lib.t6g(sch_1):page77_i362@pure_quanta.q_cap(chips)';

PART_NAME
 C978 'Q_CAP_C0402-10UF,4V,20%,X6S,CH610KMEB09':;

SECTION_NUMBER 1
 '@T6G_MB_LIB.T6G(SCH_1):PAGE77_I361@PURE_QUANTA.Q_CAP(CHIPS)':
 C_PATH='@t6g_mb_lib.t6g(sch_1):page77_i361@pure_quanta.q_cap(chips)';

PART_NAME
 C977 'Q_CAP_C0402-10UF,4V,20%,X6S,CH610KMEB09':;

SECTION_NUMBER 1
 '@T6G_MB_LIB.T6G(SCH_1):PAGE77_I391@PURE_QUANTA.Q_CAP(CHIPS)':
 C_PATH='@t6g_mb_lib.t6g(sch_1):page77_i391@pure_quanta.q_cap(chips)';

PART_NAME
 C976 'Q_CAP_C0402-10UF,4V,20%,X6S,CH610KMEB09':;

SECTION_NUMBER 1
 '@T6G_MB_LIB.T6G(SCH_1):PAGE77_I384@PURE_QUANTA.Q_CAP(CHIPS)':
 C_PATH='@t6g_mb_lib.t6g(sch_1):page77_i384@pure_quanta.q_cap(chips)';

PART_NAME
 C975 'Q_CAP_C0402-10UF,4V,20%,X6S,CH610KMEB09':;

SECTION_NUMBER 1
 '@T6G_MB_LIB.T6G(SCH_1):PAGE77_I381@PURE_QUANTA.Q_CAP(CHIPS)':
 C_PATH='@t6g_mb_lib.t6g(sch_1):page77_i381@pure_quanta.q_cap(chips)';

PART_NAME
 C974 'Q_CAP_C0402-10UF,4V,20%,X6S,CH610KMEB09':;

SECTION_NUMBER 1
 '@T6G_MB_LIB.T6G(SCH_1):PAGE77_I380@PURE_QUANTA.Q_CAP(CHIPS)':
 C_PATH='@t6g_mb_lib.t6g(sch_1):page77_i380@pure_quanta.q_cap(chips)';

PART_NAME
 C973 'Q_CAP_C0402-10UF,4V,20%,X6S,CH610KMEB09':;

SECTION_NUMBER 1
 '@T6G_MB_LIB.T6G(SCH_1):PAGE77_I392@PURE_QUANTA.Q_CAP(CHIPS)':
 C_PATH='@t6g_mb_lib.t6g(sch_1):page77_i392@pure_quanta.q_cap(chips)';

PART_NAME
 C972 'Q_CAP_C0402-10UF,4V,20%,X6S,CH610KMEB09':;

SECTION_NUMBER 1
 '@T6G_MB_LIB.T6G(SCH_1):PAGE77_I385@PURE_QUANTA.Q_CAP(CHIPS)':
 C_PATH='@t6g_mb_lib.t6g(sch_1):page77_i385@pure_quanta.q_cap(chips)';

PART_NAME
 C971 'Q_CAP_C0402-10UF,4V,20%,X6S,CH610KMEB09':;

SECTION_NUMBER 1
 '@T6G_MB_LIB.T6G(SCH_1):PAGE77_I383@PURE_QUANTA.Q_CAP(CHIPS)':
 C_PATH='@t6g_mb_lib.t6g(sch_1):page77_i383@pure_quanta.q_cap(chips)';

PART_NAME
 C970 'Q_CAP_C0402-10UF,4V,20%,X6S,CH610KMEB09':;

SECTION_NUMBER 1
 '@T6G_MB_LIB.T6G(SCH_1):PAGE77_I382@PURE_QUANTA.Q_CAP(CHIPS)':
 C_PATH='@t6g_mb_lib.t6g(sch_1):page77_i382@pure_quanta.q_cap(chips)';

PART_NAME
 C969 'Q_CAP_C0402-10UF,4V,20%,X6S,CH610KMEB09':;

SECTION_NUMBER 1
 '@T6G_MB_LIB.T6G(SCH_1):PAGE77_I398@PURE_QUANTA.Q_CAP(CHIPS)':
 C_PATH='@t6g_mb_lib.t6g(sch_1):page77_i398@pure_quanta.q_cap(chips)';

PART_NAME
 C968 'Q_CAP_C0402-10UF,4V,20%,X6S,CH610KMEB09':;

SECTION_NUMBER 1
 '@T6G_MB_LIB.T6G(SCH_1):PAGE77_I390@PURE_QUANTA.Q_CAP(CHIPS)':
 C_PATH='@t6g_mb_lib.t6g(sch_1):page77_i390@pure_quanta.q_cap(chips)';

PART_NAME
 C967 'Q_CAP_C0402-10UF,4V,20%,X6S,CH610KMEB09':;

SECTION_NUMBER 1
 '@T6G_MB_LIB.T6G(SCH_1):PAGE77_I388@PURE_QUANTA.Q_CAP(CHIPS)':
 C_PATH='@t6g_mb_lib.t6g(sch_1):page77_i388@pure_quanta.q_cap(chips)';

PART_NAME
 C966 'Q_CAP_C0402-10UF,4V,20%,X6S,CH610KMEB09':;

SECTION_NUMBER 1
 '@T6G_MB_LIB.T6G(SCH_1):PAGE77_I386@PURE_QUANTA.Q_CAP(CHIPS)':
 C_PATH='@t6g_mb_lib.t6g(sch_1):page77_i386@pure_quanta.q_cap(chips)';

PART_NAME
 C590 'Q_CAP_C0402-10UF,4V,20%,X6S,CH610KMEB09':;

SECTION_NUMBER 1
 '@T6G_MB_LIB.T6G(SCH_1):PAGE77_I311@PURE_QUANTA.Q_CAP(CHIPS)':
 C_PATH='@t6g_mb_lib.t6g(sch_1):page77_i311@pure_quanta.q_cap(chips)';

PART_NAME
 C422 'Q_CAP_C0402-10UF,4V,20%,X6S,CH610KMEB09':;

SECTION_NUMBER 1
 '@T6G_MB_LIB.T6G(SCH_1):PAGE77_I306@PURE_QUANTA.Q_CAP(CHIPS)':
 C_PATH='@t6g_mb_lib.t6g(sch_1):page77_i306@pure_quanta.q_cap(chips)';

PART_NAME
 C421 'Q_CAP_C0402-10UF,4V,20%,X6S,CH610KMEB09':;

SECTION_NUMBER 1
 '@T6G_MB_LIB.T6G(SCH_1):PAGE77_I310@PURE_QUANTA.Q_CAP(CHIPS)':
 C_PATH='@t6g_mb_lib.t6g(sch_1):page77_i310@pure_quanta.q_cap(chips)';

PART_NAME
 C420 'Q_CAP_C0402-10UF,4V,20%,X6S,CH610KMEB09':;

SECTION_NUMBER 1
 '@T6G_MB_LIB.T6G(SCH_1):PAGE77_I313@PURE_QUANTA.Q_CAP(CHIPS)':
 C_PATH='@t6g_mb_lib.t6g(sch_1):page77_i313@pure_quanta.q_cap(chips)';

PART_NAME
 C419 'Q_CAP_C0402-10UF,4V,20%,X6S,CH610KMEB09':;

SECTION_NUMBER 1
 '@T6G_MB_LIB.T6G(SCH_1):PAGE77_I315@PURE_QUANTA.Q_CAP(CHIPS)':
 C_PATH='@t6g_mb_lib.t6g(sch_1):page77_i315@pure_quanta.q_cap(chips)';

PART_NAME
 C418 'Q_CAP_C0402-10UF,4V,20%,X6S,CH610KMEB09':;

SECTION_NUMBER 1
 '@T6G_MB_LIB.T6G(SCH_1):PAGE77_I344@PURE_QUANTA.Q_CAP(CHIPS)':
 C_PATH='@t6g_mb_lib.t6g(sch_1):page77_i344@pure_quanta.q_cap(chips)';

PART_NAME
 C417 'Q_CAP_C0402-10UF,4V,20%,X6S,CH610KMEB09':;

SECTION_NUMBER 1
 '@T6G_MB_LIB.T6G(SCH_1):PAGE77_I347@PURE_QUANTA.Q_CAP(CHIPS)':
 C_PATH='@t6g_mb_lib.t6g(sch_1):page77_i347@pure_quanta.q_cap(chips)';

PART_NAME
 C416 'Q_CAP_C0402-10UF,4V,20%,X6S,CH610KMEB09':;

SECTION_NUMBER 1
 '@T6G_MB_LIB.T6G(SCH_1):PAGE77_I340@PURE_QUANTA.Q_CAP(CHIPS)':
 C_PATH='@t6g_mb_lib.t6g(sch_1):page77_i340@pure_quanta.q_cap(chips)';

PART_NAME
 C415 'Q_CAP_C0402-10UF,4V,20%,X6S,CH610KMEB09':;

SECTION_NUMBER 1
 '@T6G_MB_LIB.T6G(SCH_1):PAGE77_I348@PURE_QUANTA.Q_CAP(CHIPS)':
 C_PATH='@t6g_mb_lib.t6g(sch_1):page77_i348@pure_quanta.q_cap(chips)';

PART_NAME
 C414 'Q_CAP_C0402-10UF,4V,20%,X6S,CH610KMEB09':;

SECTION_NUMBER 1
 '@T6G_MB_LIB.T6G(SCH_1):PAGE77_I342@PURE_QUANTA.Q_CAP(CHIPS)':
 C_PATH='@t6g_mb_lib.t6g(sch_1):page77_i342@pure_quanta.q_cap(chips)';

PART_NAME
 C413 'Q_CAP_C0402-10UF,4V,20%,X6S,CH610KMEB09':;

SECTION_NUMBER 1
 '@T6G_MB_LIB.T6G(SCH_1):PAGE77_I403@PURE_QUANTA.Q_CAP(CHIPS)':
 C_PATH='@t6g_mb_lib.t6g(sch_1):page77_i403@pure_quanta.q_cap(chips)';

PART_NAME
 C412 'Q_CAP_C0402-10UF,4V,20%,X6S,CH610KMEB09':;

SECTION_NUMBER 1
 '@T6G_MB_LIB.T6G(SCH_1):PAGE77_I370@PURE_QUANTA.Q_CAP(CHIPS)':
 C_PATH='@t6g_mb_lib.t6g(sch_1):page77_i370@pure_quanta.q_cap(chips)';

PART_NAME
 C411 'Q_CAP_C0402-10UF,4V,20%,X6S,CH610KMEB09':;

SECTION_NUMBER 1
 '@T6G_MB_LIB.T6G(SCH_1):PAGE77_I404@PURE_QUANTA.Q_CAP(CHIPS)':
 C_PATH='@t6g_mb_lib.t6g(sch_1):page77_i404@pure_quanta.q_cap(chips)';

PART_NAME
 C410 'Q_CAP_C0402-10UF,4V,20%,X6S,CH610KMEB09':;

SECTION_NUMBER 1
 '@T6G_MB_LIB.T6G(SCH_1):PAGE77_I371@PURE_QUANTA.Q_CAP(CHIPS)':
 C_PATH='@t6g_mb_lib.t6g(sch_1):page77_i371@pure_quanta.q_cap(chips)';

PART_NAME
 C409 'Q_CAP_C0402-10UF,4V,20%,X6S,CH610KMEB09':;

SECTION_NUMBER 1
 '@T6G_MB_LIB.T6G(SCH_1):PAGE77_I405@PURE_QUANTA.Q_CAP(CHIPS)':
 C_PATH='@t6g_mb_lib.t6g(sch_1):page77_i405@pure_quanta.q_cap(chips)';

PART_NAME
 C408 'Q_CAP_C0402-10UF,4V,20%,X6S,CH610KMEB09':;

SECTION_NUMBER 1
 '@T6G_MB_LIB.T6G(SCH_1):PAGE77_I374@PURE_QUANTA.Q_CAP(CHIPS)':
 C_PATH='@t6g_mb_lib.t6g(sch_1):page77_i374@pure_quanta.q_cap(chips)';

PART_NAME
 C407 'Q_CAP_C0402-10UF,4V,20%,X6S,CH610KMEB09':;

SECTION_NUMBER 1
 '@T6G_MB_LIB.T6G(SCH_1):PAGE77_I406@PURE_QUANTA.Q_CAP(CHIPS)':
 C_PATH='@t6g_mb_lib.t6g(sch_1):page77_i406@pure_quanta.q_cap(chips)';

PART_NAME
 C406 'Q_CAP_C0402-10UF,4V,20%,X6S,CH610KMEB09':;

SECTION_NUMBER 1
 '@T6G_MB_LIB.T6G(SCH_1):PAGE77_I408@PURE_QUANTA.Q_CAP(CHIPS)':
 C_PATH='@t6g_mb_lib.t6g(sch_1):page77_i408@pure_quanta.q_cap(chips)';

PART_NAME
 C405 'Q_CAP_C0402-10UF,4V,20%,X6S,CH610KMEB09':;

SECTION_NUMBER 1
 '@T6G_MB_LIB.T6G(SCH_1):PAGE77_I379@PURE_QUANTA.Q_CAP(CHIPS)':
 C_PATH='@t6g_mb_lib.t6g(sch_1):page77_i379@pure_quanta.q_cap(chips)';

PART_NAME
 C404 'Q_CAP_C0402-10UF,4V,20%,X6S,CH610KMEB09':;

SECTION_NUMBER 1
 '@T6G_MB_LIB.T6G(SCH_1):PAGE77_I409@PURE_QUANTA.Q_CAP(CHIPS)':
 C_PATH='@t6g_mb_lib.t6g(sch_1):page77_i409@pure_quanta.q_cap(chips)';

PART_NAME
 C403 'Q_CAP_C0402-10UF,4V,20%,X6S,CH610KMEB09':;

SECTION_NUMBER 1
 '@T6G_MB_LIB.T6G(SCH_1):PAGE77_I394@PURE_QUANTA.Q_CAP(CHIPS)':
 C_PATH='@t6g_mb_lib.t6g(sch_1):page77_i394@pure_quanta.q_cap(chips)';

PART_NAME
 C402 'Q_CAP_C0402-10UF,4V,20%,X6S,CH610KMEB09':;

SECTION_NUMBER 1
 '@T6G_MB_LIB.T6G(SCH_1):PAGE77_I410@PURE_QUANTA.Q_CAP(CHIPS)':
 C_PATH='@t6g_mb_lib.t6g(sch_1):page77_i410@pure_quanta.q_cap(chips)';

PART_NAME
 C401 'Q_CAP_C0402-10UF,4V,20%,X6S,CH610KMEB09':;

SECTION_NUMBER 1
 '@T6G_MB_LIB.T6G(SCH_1):PAGE77_I396@PURE_QUANTA.Q_CAP(CHIPS)':
 C_PATH='@t6g_mb_lib.t6g(sch_1):page77_i396@pure_quanta.q_cap(chips)';

PART_NAME
 C400 'Q_CAP_C0402-10UF,4V,20%,X6S,CH610KMEB09':;

SECTION_NUMBER 1
 '@T6G_MB_LIB.T6G(SCH_1):PAGE77_I412@PURE_QUANTA.Q_CAP(CHIPS)':
 C_PATH='@t6g_mb_lib.t6g(sch_1):page77_i412@pure_quanta.q_cap(chips)';

PART_NAME
 C399 'Q_CAP_C0402-10UF,4V,20%,X6S,CH610KMEB09':;

SECTION_NUMBER 1
 '@T6G_MB_LIB.T6G(SCH_1):PAGE77_I402@PURE_QUANTA.Q_CAP(CHIPS)':
 C_PATH='@t6g_mb_lib.t6g(sch_1):page77_i402@pure_quanta.q_cap(chips)';

PART_NAME
 C220 'Q_CAP_0805-47UF,4V,20%,X6S,CH647KMEA00':;

SECTION_NUMBER 1
 '@T6G_MB_LIB.T6G(SCH_1):PAGE77_I271@PURE_QUANTA.Q_CAP(CHIPS)':
 C_PATH='@t6g_mb_lib.t6g(sch_1):page77_i271@pure_quanta.q_cap(chips)';

PART_NAME
 C219 'Q_CAP_0805-47UF,4V,20%,X6S,CH647KMEA00':;

SECTION_NUMBER 1
 '@T6G_MB_LIB.T6G(SCH_1):PAGE77_I341@PURE_QUANTA.Q_CAP(CHIPS)':
 C_PATH='@t6g_mb_lib.t6g(sch_1):page77_i341@pure_quanta.q_cap(chips)';

PART_NAME
 C218 'Q_CAP_0805-47UF,4V,20%,X6S,CH647KMEA00':;

SECTION_NUMBER 1
 '@T6G_MB_LIB.T6G(SCH_1):PAGE77_I368@PURE_QUANTA.Q_CAP(CHIPS)':
 C_PATH='@t6g_mb_lib.t6g(sch_1):page77_i368@pure_quanta.q_cap(chips)';

PART_NAME
 C217 'Q_CAP_0805-47UF,4V,20%,X6S,CH647KMEA00':;

SECTION_NUMBER 1
 '@T6G_MB_LIB.T6G(SCH_1):PAGE77_I369@PURE_QUANTA.Q_CAP(CHIPS)':
 C_PATH='@t6g_mb_lib.t6g(sch_1):page77_i369@pure_quanta.q_cap(chips)';

PART_NAME
 C216 'Q_CAP_0805-47UF,4V,20%,X6S,CH647KMEA00':;

SECTION_NUMBER 1
 '@T6G_MB_LIB.T6G(SCH_1):PAGE77_I372@PURE_QUANTA.Q_CAP(CHIPS)':
 C_PATH='@t6g_mb_lib.t6g(sch_1):page77_i372@pure_quanta.q_cap(chips)';

PART_NAME
 C215 'Q_CAP_0805-47UF,4V,20%,X6S,CH647KMEA00':;

SECTION_NUMBER 1
 '@T6G_MB_LIB.T6G(SCH_1):PAGE77_I377@PURE_QUANTA.Q_CAP(CHIPS)':
 C_PATH='@t6g_mb_lib.t6g(sch_1):page77_i377@pure_quanta.q_cap(chips)';

PART_NAME
 C214 'Q_CAP_0805-47UF,4V,20%,X6S,CH647KMEA00':;

SECTION_NUMBER 1
 '@T6G_MB_LIB.T6G(SCH_1):PAGE77_I378@PURE_QUANTA.Q_CAP(CHIPS)':
 C_PATH='@t6g_mb_lib.t6g(sch_1):page77_i378@pure_quanta.q_cap(chips)';

PART_NAME
 C213 'Q_CAP_0805-47UF,4V,20%,X6S,CH647KMEA00':;

SECTION_NUMBER 1
 '@T6G_MB_LIB.T6G(SCH_1):PAGE77_I393@PURE_QUANTA.Q_CAP(CHIPS)':
 C_PATH='@t6g_mb_lib.t6g(sch_1):page77_i393@pure_quanta.q_cap(chips)';

PART_NAME
 C212 'Q_CAP_0805-47UF,4V,20%,X6S,CH647KMEA00':;

SECTION_NUMBER 1
 '@T6G_MB_LIB.T6G(SCH_1):PAGE77_I395@PURE_QUANTA.Q_CAP(CHIPS)':
 C_PATH='@t6g_mb_lib.t6g(sch_1):page77_i395@pure_quanta.q_cap(chips)';

PART_NAME
 C101 'Q_CAP_0805-47UF,4V,20%,X6S,CH647KMEA00':;

SECTION_NUMBER 1
 '@T6G_MB_LIB.T6G(SCH_1):PAGE77_I400@PURE_QUANTA.Q_CAP(CHIPS)':
 C_PATH='@t6g_mb_lib.t6g(sch_1):page77_i400@pure_quanta.q_cap(chips)';

PART_NAME
 U9 'GTL2014PW-GTL2014PW,SMLF,IC,AL002014K01':;

SECTION_NUMBER 1
 '@T6G_MB_LIB.T6G(SCH_1):PAGE93_I27@PURE_QUANTA.GTL2014PW(CHIPS)':
 C_PATH='@t6g_mb_lib.t6g(sch_1):page93_i27@pure_quanta.gtl2014pw(chips)';

PART_NAME
 R315 'Q_RES_0402LF-33,5%,1/16W,CHIP,CS03302JB29':;

SECTION_NUMBER 1
 '@T6G_MB_LIB.T6G(SCH_1):PAGE93_I28@PURE_QUANTA.Q_RES(CHIPS)':
 C_PATH='@t6g_mb_lib.t6g(sch_1):page93_i28@pure_quanta.q_res(chips)';

PART_NAME
 R314 'Q_RES_0402LF-49.9     ,1%  ,1/16W,EMPTY,CS04992FB31':;

SECTION_NUMBER 1
 '@T6G_MB_LIB.T6G(SCH_1):PAGE93_I29@PURE_QUANTA.Q_RES(CHIPS)':
 C_PATH='@t6g_mb_lib.t6g(sch_1):page93_i29@pure_quanta.q_res(chips)';

PART_NAME
 R313 'Q_RES_0402LF-33,5%,1/16W,EMPTY,CS03302JB29':;

SECTION_NUMBER 1
 '@T6G_MB_LIB.T6G(SCH_1):PAGE93_I30@PURE_QUANTA.Q_RES(CHIPS)':
 C_PATH='@t6g_mb_lib.t6g(sch_1):page93_i30@pure_quanta.q_res(chips)';

PART_NAME
 R312 'Q_RES_0402LF-33,5%,1/16W,EMPTY,CS03302JB29':;

SECTION_NUMBER 1
 '@T6G_MB_LIB.T6G(SCH_1):PAGE93_I31@PURE_QUANTA.Q_RES(CHIPS)':
 C_PATH='@t6g_mb_lib.t6g(sch_1):page93_i31@pure_quanta.q_res(chips)';

PART_NAME
 R311 'Q_RES_0402LF-1K,1%,1/16W,CHIP,TMP_QCS21002FB24':;

SECTION_NUMBER 1
 '@T6G_MB_LIB.T6G(SCH_1):PAGE93_I38@PURE_QUANTA.Q_RES(CHIPS)':
 C_PATH='@t6g_mb_lib.t6g(sch_1):page93_i38@pure_quanta.q_res(chips)';

PART_NAME
 R310 'Q_RES_0402LF-4.32K,1%,1/16W,CHIP,TMP_QCS24322FB14':;

SECTION_NUMBER 1
 '@T6G_MB_LIB.T6G(SCH_1):PAGE93_I39@PURE_QUANTA.Q_RES(CHIPS)':
 C_PATH='@t6g_mb_lib.t6g(sch_1):page93_i39@pure_quanta.q_res(chips)';

PART_NAME
 R308 'Q_RES_0402LF-0,5%,1/16W,EMPTY,CS00002JB38':;

SECTION_NUMBER 1
 '@T6G_MB_LIB.T6G(SCH_1):PAGE93_I15@PURE_QUANTA.Q_RES(CHIPS)':
 C_PATH='@t6g_mb_lib.t6g(sch_1):page93_i15@pure_quanta.q_res(chips)';

PART_NAME
 R307 'Q_RES_0402LF-0,5%,1/16W,EMPTY,CS00002JB38':;

SECTION_NUMBER 1
 '@T6G_MB_LIB.T6G(SCH_1):PAGE93_I17@PURE_QUANTA.Q_RES(CHIPS)':
 C_PATH='@t6g_mb_lib.t6g(sch_1):page93_i17@pure_quanta.q_res(chips)';

PART_NAME
 R306 'Q_RES_0402LF-0,5%,1/16W,EMPTY,CS00002JB38':;

SECTION_NUMBER 1
 '@T6G_MB_LIB.T6G(SCH_1):PAGE93_I16@PURE_QUANTA.Q_RES(CHIPS)':
 C_PATH='@t6g_mb_lib.t6g(sch_1):page93_i16@pure_quanta.q_res(chips)';

PART_NAME
 R305 'Q_RES_0402LF-0,5%,1/16W,CHIP,CS00002JB38':;

SECTION_NUMBER 1
 '@T6G_MB_LIB.T6G(SCH_1):PAGE93_I6@PURE_QUANTA.Q_RES(CHIPS)':
 C_PATH='@t6g_mb_lib.t6g(sch_1):page93_i6@pure_quanta.q_res(chips)';

PART_NAME
 R304 'Q_RES_0402LF-33,5%,1/16W,CHIP,CS03302JB29':;

SECTION_NUMBER 1
 '@T6G_MB_LIB.T6G(SCH_1):PAGE93_I7@PURE_QUANTA.Q_RES(CHIPS)':
 C_PATH='@t6g_mb_lib.t6g(sch_1):page93_i7@pure_quanta.q_res(chips)';

PART_NAME
 R303 'Q_RES_0402LF-301,1%,1/16W,CHIP,TMP_QCS13012FB14':;

SECTION_NUMBER 1
 '@T6G_MB_LIB.T6G(SCH_1):PAGE93_I8@PURE_QUANTA.Q_RES(CHIPS)':
 C_PATH='@t6g_mb_lib.t6g(sch_1):page93_i8@pure_quanta.q_res(chips)';

PART_NAME
 R302 'Q_RES_0402LF-33,5%,1/16W,CHIP,CS03302JB29':;

SECTION_NUMBER 1
 '@T6G_MB_LIB.T6G(SCH_1):PAGE93_I11@PURE_QUANTA.Q_RES(CHIPS)':
 C_PATH='@t6g_mb_lib.t6g(sch_1):page93_i11@pure_quanta.q_res(chips)';

PART_NAME
 R301 'Q_RES_0402LF-301,1%,1/16W,CHIP,TMP_QCS13012FB14':;

SECTION_NUMBER 1
 '@T6G_MB_LIB.T6G(SCH_1):PAGE93_I12@PURE_QUANTA.Q_RES(CHIPS)':
 C_PATH='@t6g_mb_lib.t6g(sch_1):page93_i12@pure_quanta.q_res(chips)';

PART_NAME
 R300 'Q_RES_0402LF-0,5%,1/16W,CHIP,CS00002JB38':;

SECTION_NUMBER 1
 '@T6G_MB_LIB.T6G(SCH_1):PAGE93_I13@PURE_QUANTA.Q_RES(CHIPS)':
 C_PATH='@t6g_mb_lib.t6g(sch_1):page93_i13@pure_quanta.q_res(chips)';

PART_NAME
 R299 'Q_RES_0402LF-0,5%,1/16W,CHIP,CS00002JB38':;

SECTION_NUMBER 1
 '@T6G_MB_LIB.T6G(SCH_1):PAGE93_I23@PURE_QUANTA.Q_RES(CHIPS)':
 C_PATH='@t6g_mb_lib.t6g(sch_1):page93_i23@pure_quanta.q_res(chips)';

PART_NAME
 R298 'Q_RES_0402LF-301,1%,1/16W,CHIP,TMP_QCS13012FB14':;

SECTION_NUMBER 1
 '@T6G_MB_LIB.T6G(SCH_1):PAGE93_I24@PURE_QUANTA.Q_RES(CHIPS)':
 C_PATH='@t6g_mb_lib.t6g(sch_1):page93_i24@pure_quanta.q_res(chips)';

PART_NAME
 R297 'Q_RES_0402LF-0,5%,1/16W,CHIP,CS00002JB38':;

SECTION_NUMBER 1
 '@T6G_MB_LIB.T6G(SCH_1):PAGE93_I25@PURE_QUANTA.Q_RES(CHIPS)':
 C_PATH='@t6g_mb_lib.t6g(sch_1):page93_i25@pure_quanta.q_res(chips)';

PART_NAME
 R296 'Q_RES_0402LF-301,1%,1/16W,CHIP,TMP_QCS13012FB14':;

SECTION_NUMBER 1
 '@T6G_MB_LIB.T6G(SCH_1):PAGE93_I26@PURE_QUANTA.Q_RES(CHIPS)':
 C_PATH='@t6g_mb_lib.t6g(sch_1):page93_i26@pure_quanta.q_res(chips)';

PART_NAME
 R83 'Q_RES_0402LF-1K,1%,1/16W,CHIP,TMP_QCS21002FB24':;

SECTION_NUMBER 1
 '@T6G_MB_LIB.T6G(SCH_1):PAGE93_I32@PURE_QUANTA.Q_RES(CHIPS)':
 C_PATH='@t6g_mb_lib.t6g(sch_1):page93_i32@pure_quanta.q_res(chips)';

PART_NAME
 R82 'Q_RES_0402LF-150,1%,1/16W,CHIP,TMP_QCS11502FB21':;

SECTION_NUMBER 1
 '@T6G_MB_LIB.T6G(SCH_1):PAGE93_I47@PURE_QUANTA.Q_RES(CHIPS)':
 C_PATH='@t6g_mb_lib.t6g(sch_1):page93_i47@pure_quanta.q_res(chips)';

PART_NAME
 C107 'Q_CAP_0402-0.1UF,25V,10%,X7R,CH4104K1B00':;

SECTION_NUMBER 1
 '@T6G_MB_LIB.T6G(SCH_1):PAGE93_I42@PURE_QUANTA.Q_CAP(CHIPS)':
 C_PATH='@t6g_mb_lib.t6g(sch_1):page93_i42@pure_quanta.q_cap(chips)';

PART_NAME
 C100 'Q_CAP_C0402-1UF,25V,10%,X6S,CH5104KEB02':;

SECTION_NUMBER 1
 '@T6G_MB_LIB.T6G(SCH_1):PAGE93_I36@PURE_QUANTA.Q_CAP(CHIPS)':
 C_PATH='@t6g_mb_lib.t6g(sch_1):page93_i36@pure_quanta.q_cap(chips)';

PART_NAME
 U180 'GTL2014PW-GTL2014PW,SMLF,IC,AL002014K01':;

SECTION_NUMBER 1
 '@T6G_MB_LIB.T6G(SCH_1):PAGE98_I80@PURE_QUANTA.GTL2014PW(CHIPS)':
 C_PATH='@t6g_mb_lib.t6g(sch_1):page98_i80@pure_quanta.gtl2014pw(chips)';

PART_NAME
 R2071 'Q_RES_0402LF-2K,1%,1/16W,EMPTY,TMP_QCS22002FB19':;

SECTION_NUMBER 1
 '@T6G_MB_LIB.T6G(SCH_1):PAGE98_I86@PURE_QUANTA.Q_RES(CHIPS)':
 C_PATH='@t6g_mb_lib.t6g(sch_1):page98_i86@pure_quanta.q_res(chips)';

PART_NAME
 R2070 'Q_RES_0402LF-2K,1%,1/16W,EMPTY,TMP_QCS22002FB19':;

SECTION_NUMBER 1
 '@T6G_MB_LIB.T6G(SCH_1):PAGE98_I83@PURE_QUANTA.Q_RES(CHIPS)':
 C_PATH='@t6g_mb_lib.t6g(sch_1):page98_i83@pure_quanta.q_res(chips)';

PART_NAME
 R2069 'Q_RES_0402LF-100,1%,1/16W,EMPTY,TMP_QCS11002FB22':;

SECTION_NUMBER 1
 '@T6G_MB_LIB.T6G(SCH_1):PAGE98_I94@PURE_QUANTA.Q_RES(CHIPS)':
 C_PATH='@t6g_mb_lib.t6g(sch_1):page98_i94@pure_quanta.q_res(chips)';

PART_NAME
 R228 'Q_RES_0402LF-0,5%,1/16W,EMPTY,CS00002JB38':;

SECTION_NUMBER 1
 '@T6G_MB_LIB.T6G(SCH_1):PAGE98_I79@PURE_QUANTA.Q_RES(CHIPS)':
 C_PATH='@t6g_mb_lib.t6g(sch_1):page98_i79@pure_quanta.q_res(chips)';

PART_NAME
 R227 'Q_RES_0402LF-0,5%,1/16W,EMPTY,CS00002JB38':;

SECTION_NUMBER 1
 '@T6G_MB_LIB.T6G(SCH_1):PAGE98_I78@PURE_QUANTA.Q_RES(CHIPS)':
 C_PATH='@t6g_mb_lib.t6g(sch_1):page98_i78@pure_quanta.q_res(chips)';

PART_NAME
 R226 'Q_RES_0402LF-0,5%,1/16W,EMPTY,CS00002JB38':;

SECTION_NUMBER 1
 '@T6G_MB_LIB.T6G(SCH_1):PAGE98_I77@PURE_QUANTA.Q_RES(CHIPS)':
 C_PATH='@t6g_mb_lib.t6g(sch_1):page98_i77@pure_quanta.q_res(chips)';

PART_NAME
 R225 'Q_RES_0402LF-0,5%,1/16W,EMPTY,CS00002JB38':;

SECTION_NUMBER 1
 '@T6G_MB_LIB.T6G(SCH_1):PAGE98_I76@PURE_QUANTA.Q_RES(CHIPS)':
 C_PATH='@t6g_mb_lib.t6g(sch_1):page98_i76@pure_quanta.q_res(chips)';

PART_NAME
 R224 'Q_RES_0402LF-1K,1%,1/16W,CHIP,TMP_QCS21002FB24':;

SECTION_NUMBER 1
 '@T6G_MB_LIB.T6G(SCH_1):PAGE98_I59@PURE_QUANTA.Q_RES(CHIPS)':
 C_PATH='@t6g_mb_lib.t6g(sch_1):page98_i59@pure_quanta.q_res(chips)';

PART_NAME
 R223 'Q_RES_0402LF-4.32K,1%,1/16W,CHIP,TMP_QCS24322FB14':;

SECTION_NUMBER 1
 '@T6G_MB_LIB.T6G(SCH_1):PAGE98_I57@PURE_QUANTA.Q_RES(CHIPS)':
 C_PATH='@t6g_mb_lib.t6g(sch_1):page98_i57@pure_quanta.q_res(chips)';

PART_NAME
 R222 'Q_RES_0402LF-100,1%,1/16W,EMPTY,TMP_QCS11002FB22':;

SECTION_NUMBER 1
 '@T6G_MB_LIB.T6G(SCH_1):PAGE98_I62@PURE_QUANTA.Q_RES(CHIPS)':
 C_PATH='@t6g_mb_lib.t6g(sch_1):page98_i62@pure_quanta.q_res(chips)';

PART_NAME
 R221 'Q_RES_0402LF-100,1%,1/16W,EMPTY,TMP_QCS11002FB22':;

SECTION_NUMBER 1
 '@T6G_MB_LIB.T6G(SCH_1):PAGE98_I61@PURE_QUANTA.Q_RES(CHIPS)':
 C_PATH='@t6g_mb_lib.t6g(sch_1):page98_i61@pure_quanta.q_res(chips)';

PART_NAME
 R220 'Q_RES_0402LF-100,1%,1/16W,CHIP,TMP_QCS11002FB22':;

SECTION_NUMBER 1
 '@T6G_MB_LIB.T6G(SCH_1):PAGE98_I66@PURE_QUANTA.Q_RES(CHIPS)':
 C_PATH='@t6g_mb_lib.t6g(sch_1):page98_i66@pure_quanta.q_res(chips)';

PART_NAME
 R219 'Q_RES_0402LF-100,1%,1/16W,CHIP,TMP_QCS11002FB22':;

SECTION_NUMBER 1
 '@T6G_MB_LIB.T6G(SCH_1):PAGE98_I63@PURE_QUANTA.Q_RES(CHIPS)':
 C_PATH='@t6g_mb_lib.t6g(sch_1):page98_i63@pure_quanta.q_res(chips)';

PART_NAME
 R218 'Q_RES_0402LF-0,5%,1/16W,CHIP,CS00002JB38':;

SECTION_NUMBER 1
 '@T6G_MB_LIB.T6G(SCH_1):PAGE98_I107@PURE_QUANTA.Q_RES(CHIPS)':
 C_PATH='@t6g_mb_lib.t6g(sch_1):page98_i107@pure_quanta.q_res(chips)';

PART_NAME
 R217 'Q_RES_0402LF-0,5%,1/16W,CHIP,CS00002JB38':;

SECTION_NUMBER 1
 '@T6G_MB_LIB.T6G(SCH_1):PAGE98_I106@PURE_QUANTA.Q_RES(CHIPS)':
 C_PATH='@t6g_mb_lib.t6g(sch_1):page98_i106@pure_quanta.q_res(chips)';

PART_NAME
 R216 'Q_RES_0402LF-0,5%,1/16W,CHIP,CS00002JB38':;

SECTION_NUMBER 1
 '@T6G_MB_LIB.T6G(SCH_1):PAGE98_I105@PURE_QUANTA.Q_RES(CHIPS)':
 C_PATH='@t6g_mb_lib.t6g(sch_1):page98_i105@pure_quanta.q_res(chips)';

PART_NAME
 R215 'Q_RES_0402LF-0,5%,1/16W,CHIP,CS00002JB38':;

SECTION_NUMBER 1
 '@T6G_MB_LIB.T6G(SCH_1):PAGE98_I104@PURE_QUANTA.Q_RES(CHIPS)':
 C_PATH='@t6g_mb_lib.t6g(sch_1):page98_i104@pure_quanta.q_res(chips)';

PART_NAME
 R214 'Q_RES_0402LF-0,5%,1/16W,EMPTY,CS00002JB38':;

SECTION_NUMBER 1
 '@T6G_MB_LIB.T6G(SCH_1):PAGE98_I103@PURE_QUANTA.Q_RES(CHIPS)':
 C_PATH='@t6g_mb_lib.t6g(sch_1):page98_i103@pure_quanta.q_res(chips)';

PART_NAME
 R213 'Q_RES_0402LF-0,5%,1/16W,EMPTY,CS00002JB38':;

SECTION_NUMBER 1
 '@T6G_MB_LIB.T6G(SCH_1):PAGE98_I102@PURE_QUANTA.Q_RES(CHIPS)':
 C_PATH='@t6g_mb_lib.t6g(sch_1):page98_i102@pure_quanta.q_res(chips)';

PART_NAME
 R212 'Q_RES_0402LF-0,5%,1/16W,EMPTY,CS00002JB38':;

SECTION_NUMBER 1
 '@T6G_MB_LIB.T6G(SCH_1):PAGE98_I101@PURE_QUANTA.Q_RES(CHIPS)':
 C_PATH='@t6g_mb_lib.t6g(sch_1):page98_i101@pure_quanta.q_res(chips)';

PART_NAME
 R211 'Q_RES_0402LF-0,5%,1/16W,EMPTY,CS00002JB38':;

SECTION_NUMBER 1
 '@T6G_MB_LIB.T6G(SCH_1):PAGE98_I100@PURE_QUANTA.Q_RES(CHIPS)':
 C_PATH='@t6g_mb_lib.t6g(sch_1):page98_i100@pure_quanta.q_res(chips)';

PART_NAME
 R210 'Q_RES_0402LF-0,5%,1/16W,CHIP,CS00002JB38':;

SECTION_NUMBER 1
 '@T6G_MB_LIB.T6G(SCH_1):PAGE98_I91@PURE_QUANTA.Q_RES(CHIPS)':
 C_PATH='@t6g_mb_lib.t6g(sch_1):page98_i91@pure_quanta.q_res(chips)';

PART_NAME
 R209 'Q_RES_0402LF-0,5%,1/16W,EMPTY,CS00002JB38':;

SECTION_NUMBER 1
 '@T6G_MB_LIB.T6G(SCH_1):PAGE98_I89@PURE_QUANTA.Q_RES(CHIPS)':
 C_PATH='@t6g_mb_lib.t6g(sch_1):page98_i89@pure_quanta.q_res(chips)';

PART_NAME
 R208 'Q_RES_0402LF-0,5%,1/16W,CHIP,CS00002JB38':;

SECTION_NUMBER 1
 '@T6G_MB_LIB.T6G(SCH_1):PAGE98_I88@PURE_QUANTA.Q_RES(CHIPS)':
 C_PATH='@t6g_mb_lib.t6g(sch_1):page98_i88@pure_quanta.q_res(chips)';

PART_NAME
 R207 'Q_RES_0402LF-0,5%,1/16W,EMPTY,CS00002JB38':;

SECTION_NUMBER 1
 '@T6G_MB_LIB.T6G(SCH_1):PAGE98_I87@PURE_QUANTA.Q_RES(CHIPS)':
 C_PATH='@t6g_mb_lib.t6g(sch_1):page98_i87@pure_quanta.q_res(chips)';

PART_NAME
 R206 'Q_RES_0402LF-33,5%,1/16W,CHIP,CS03302JB29':;

SECTION_NUMBER 1
 '@T6G_MB_LIB.T6G(SCH_1):PAGE98_I111@PURE_QUANTA.Q_RES(CHIPS)':
 C_PATH='@t6g_mb_lib.t6g(sch_1):page98_i111@pure_quanta.q_res(chips)';

PART_NAME
 R205 'Q_RES_0402LF-33,5%,1/16W,CHIP,CS03302JB29':;

SECTION_NUMBER 1
 '@T6G_MB_LIB.T6G(SCH_1):PAGE98_I110@PURE_QUANTA.Q_RES(CHIPS)':
 C_PATH='@t6g_mb_lib.t6g(sch_1):page98_i110@pure_quanta.q_res(chips)';

PART_NAME
 R204 'Q_RES_0402LF-33,5%,1/16W,CHIP,CS03302JB29':;

SECTION_NUMBER 1
 '@T6G_MB_LIB.T6G(SCH_1):PAGE98_I109@PURE_QUANTA.Q_RES(CHIPS)':
 C_PATH='@t6g_mb_lib.t6g(sch_1):page98_i109@pure_quanta.q_res(chips)';

PART_NAME
 R203 'Q_RES_0402LF-33,5%,1/16W,CHIP,CS03302JB29':;

SECTION_NUMBER 1
 '@T6G_MB_LIB.T6G(SCH_1):PAGE98_I108@PURE_QUANTA.Q_RES(CHIPS)':
 C_PATH='@t6g_mb_lib.t6g(sch_1):page98_i108@pure_quanta.q_res(chips)';

PART_NAME
 R201 'Q_RES_0402LF-100,1%,1/16W,EMPTY,TMP_QCS11002FB22':;

SECTION_NUMBER 1
 '@T6G_MB_LIB.T6G(SCH_1):PAGE98_I96@PURE_QUANTA.Q_RES(CHIPS)':
 C_PATH='@t6g_mb_lib.t6g(sch_1):page98_i96@pure_quanta.q_res(chips)';

PART_NAME
 R200 'Q_RES_0402LF-100,1%,1/16W,EMPTY,TMP_QCS11002FB22':;

SECTION_NUMBER 1
 '@T6G_MB_LIB.T6G(SCH_1):PAGE98_I97@PURE_QUANTA.Q_RES(CHIPS)':
 C_PATH='@t6g_mb_lib.t6g(sch_1):page98_i97@pure_quanta.q_res(chips)';

PART_NAME
 R199 'Q_RES_0402LF-100,1%,1/16W,EMPTY,TMP_QCS11002FB22':;

SECTION_NUMBER 1
 '@T6G_MB_LIB.T6G(SCH_1):PAGE98_I99@PURE_QUANTA.Q_RES(CHIPS)':
 C_PATH='@t6g_mb_lib.t6g(sch_1):page98_i99@pure_quanta.q_res(chips)';

PART_NAME
 R81 'Q_RES_0402LF-1K,1%,1/16W,CHIP,TMP_QCS21002FB24':;

SECTION_NUMBER 1
 '@T6G_MB_LIB.T6G(SCH_1):PAGE98_I58@PURE_QUANTA.Q_RES(CHIPS)':
 C_PATH='@t6g_mb_lib.t6g(sch_1):page98_i58@pure_quanta.q_res(chips)';

PART_NAME
 Q106 'MOSFET_N_123-BSS123-7-F,SMLF,IC,BAM01230014':;

SECTION_NUMBER 1
 '@T6G_MB_LIB.T6G(SCH_1):PAGE98_I85@PURE_QUANTA.MOSFET_N_123(CHIPS)':
 C_PATH='@t6g_mb_lib.t6g(sch_1):page98_i85@pure_quanta.mosfet_n_123(chips)';

PART_NAME
 Q105 'MOSFET_N_123-BSS123-7-F,SMLF,IC,BAM01230014':;

SECTION_NUMBER 1
 '@T6G_MB_LIB.T6G(SCH_1):PAGE98_I82@PURE_QUANTA.MOSFET_N_123(CHIPS)':
 C_PATH='@t6g_mb_lib.t6g(sch_1):page98_i82@pure_quanta.mosfet_n_123(chips)';

PART_NAME
 C106 'Q_CAP_0402-0.1UF,25V,10%,X7R,CH4104K1B00':;

SECTION_NUMBER 1
 '@T6G_MB_LIB.T6G(SCH_1):PAGE98_I55@PURE_QUANTA.Q_CAP(CHIPS)':
 C_PATH='@t6g_mb_lib.t6g(sch_1):page98_i55@pure_quanta.q_cap(chips)';

PART_NAME
 C99 'Q_CAP_C0402-1UF,25V,10%,X6S,CH5104KEB02':;

SECTION_NUMBER 1
 '@T6G_MB_LIB.T6G(SCH_1):PAGE98_I67@PURE_QUANTA.Q_CAP(CHIPS)':
 C_PATH='@t6g_mb_lib.t6g(sch_1):page98_i67@pure_quanta.q_cap(chips)';

PART_NAME
 R80 'Q_RES_0402LF-196K,1%,1/16W,CHIP,CS41962FB01':;

SECTION_NUMBER 1
 '@T6G_MB_LIB.T6G(SCH_1):PAGE125_I349@PURE_QUANTA.Q_RES(CHIPS)':
 C_PATH='@t6g_mb_lib.t6g(sch_1):page125_i349@pure_quanta.q_res(chips)';

PART_NAME
 J24 'SCONN288_ADR50001P003C01-SCONN288_ADR50001-P003C01,SMLF,IO,DFHST8FS301':;

SECTION_NUMBER 1
 '@T6G_MB_LIB.T6G(SCH_1):PAGE125_I346@PURE_QUANTA.SCONN288_ADR50001P003C01(CHIPS)':
 C_PATH='@t6g_mb_lib.t6g(sch_1):page125_i346@pure_quanta.sconn288_adr50001p003c0~
1(chips)';

SECTION_NUMBER 2
 '@T6G_MB_LIB.T6G(SCH_1):PAGE125_I347@PURE_QUANTA.SCONN288_ADR50001P003C01(CHIPS)':
 C_PATH='@t6g_mb_lib.t6g(sch_1):page125_i347@pure_quanta.sconn288_adr50001p003c0~
1(chips)';

SECTION_NUMBER 3
 '@T6G_MB_LIB.T6G(SCH_1):PAGE125_I348@PURE_QUANTA.SCONN288_ADR50001P003C01(CHIPS)':
 C_PATH='@t6g_mb_lib.t6g(sch_1):page125_i348@pure_quanta.sconn288_adr50001p003c0~
1(chips)';

PART_NAME
 C98 'Q_CAP_C0805-10UF,16V,10%,X7R,CH6103K1A00':
;

SECTION_NUMBER 1
 '@T6G_MB_LIB.T6G(SCH_1):PAGE125_I339@PURE_QUANTA.Q_CAP(CHIPS)':
 C_PATH='@t6g_mb_lib.t6g(sch_1):page125_i339@pure_quanta.q_cap(chips)';

PART_NAME
 C97 'Q_CAP_C0805-10UF,16V,10%,X7R,CH6103K1A00':
;

SECTION_NUMBER 1
 '@T6G_MB_LIB.T6G(SCH_1):PAGE125_I345@PURE_QUANTA.Q_CAP(CHIPS)':
 C_PATH='@t6g_mb_lib.t6g(sch_1):page125_i345@pure_quanta.q_cap(chips)';

PART_NAME
 C96 'Q_CAP_C0402-2.2UF,6.3V,20%,X6S,CH5221MEB00':
;

SECTION_NUMBER 1
 '@T6G_MB_LIB.T6G(SCH_1):PAGE125_I342@PURE_QUANTA.Q_CAP(CHIPS)':
 C_PATH='@t6g_mb_lib.t6g(sch_1):page125_i342@pure_quanta.q_cap(chips)';

PART_NAME
 R79 'Q_RES_0402LF-10K,1%,1/16W,CHIP,CS31002FB08':
;

SECTION_NUMBER 1
 '@T6G_MB_LIB.T6G(SCH_1):PAGE126_I331@PURE_QUANTA.Q_RES(CHIPS)':
 C_PATH='@t6g_mb_lib.t6g(sch_1):page126_i331@pure_quanta.q_res(chips)';

PART_NAME
 J25 'SCONN288_ADR50001P013C01-SCONN288_ADR50001-P013C01,SMLF,IO,DFHST8FS302':;

SECTION_NUMBER 1
 '@T6G_MB_LIB.T6G(SCH_1):PAGE126_I345@PURE_QUANTA.SCONN288_ADR50001P013C01(CHIPS)':
 C_PATH='@t6g_mb_lib.t6g(sch_1):page126_i345@pure_quanta.sconn288_adr50001p013c0~
1(chips)';

SECTION_NUMBER 2
 '@T6G_MB_LIB.T6G(SCH_1):PAGE126_I346@PURE_QUANTA.SCONN288_ADR50001P013C01(CHIPS)':
 C_PATH='@t6g_mb_lib.t6g(sch_1):page126_i346@pure_quanta.sconn288_adr50001p013c0~
1(chips)';

SECTION_NUMBER 3
 '@T6G_MB_LIB.T6G(SCH_1):PAGE126_I344@PURE_QUANTA.SCONN288_ADR50001P013C01(CHIPS)':
 C_PATH='@t6g_mb_lib.t6g(sch_1):page126_i344@pure_quanta.sconn288_adr50001p013c0~
1(chips)';

PART_NAME
 C95 'Q_CAP_C0805-10UF,16V,10%,X7R,CH6103K1A00':
;

SECTION_NUMBER 1
 '@T6G_MB_LIB.T6G(SCH_1):PAGE126_I336@PURE_QUANTA.Q_CAP(CHIPS)':
 C_PATH='@t6g_mb_lib.t6g(sch_1):page126_i336@pure_quanta.q_cap(chips)';

PART_NAME
 C94 'Q_CAP_C0805-10UF,16V,10%,X7R,CH6103K1A00':
;

SECTION_NUMBER 1
 '@T6G_MB_LIB.T6G(SCH_1):PAGE126_I343@PURE_QUANTA.Q_CAP(CHIPS)':
 C_PATH='@t6g_mb_lib.t6g(sch_1):page126_i343@pure_quanta.q_cap(chips)';

PART_NAME
 C93 'Q_CAP_C0402-2.2UF,6.3V,20%,X6S,CH5221MEB00':
;

SECTION_NUMBER 1
 '@T6G_MB_LIB.T6G(SCH_1):PAGE126_I339@PURE_QUANTA.Q_CAP(CHIPS)':
 C_PATH='@t6g_mb_lib.t6g(sch_1):page126_i339@pure_quanta.q_cap(chips)';

PART_NAME
 R78 'Q_RES_0402LF-15.4K,1%,1/16W,CHIP,CS31542FB14':;

SECTION_NUMBER 1
 '@T6G_MB_LIB.T6G(SCH_1):PAGE127_I350@PURE_QUANTA.Q_RES(CHIPS)':
 C_PATH='@t6g_mb_lib.t6g(sch_1):page127_i350@pure_quanta.q_res(chips)';

PART_NAME
 J26 'SCONN288_ADR50001P003C01-SCONN288_ADR50001-P003C01,SMLF,IO,DFHST8FS301':;

SECTION_NUMBER 1
 '@T6G_MB_LIB.T6G(SCH_1):PAGE127_I347@PURE_QUANTA.SCONN288_ADR50001P003C01(CHIPS)':
 C_PATH='@t6g_mb_lib.t6g(sch_1):page127_i347@pure_quanta.sconn288_adr50001p003c0~
1(chips)';

SECTION_NUMBER 2
 '@T6G_MB_LIB.T6G(SCH_1):PAGE127_I348@PURE_QUANTA.SCONN288_ADR50001P003C01(CHIPS)':
 C_PATH='@t6g_mb_lib.t6g(sch_1):page127_i348@pure_quanta.sconn288_adr50001p003c0~
1(chips)';

SECTION_NUMBER 3
 '@T6G_MB_LIB.T6G(SCH_1):PAGE127_I349@PURE_QUANTA.SCONN288_ADR50001P003C01(CHIPS)':
 C_PATH='@t6g_mb_lib.t6g(sch_1):page127_i349@pure_quanta.sconn288_adr50001p003c0~
1(chips)';

PART_NAME
 C92 'Q_CAP_C0805-10UF,16V,10%,X7R,CH6103K1A00':
;

SECTION_NUMBER 1
 '@T6G_MB_LIB.T6G(SCH_1):PAGE127_I338@PURE_QUANTA.Q_CAP(CHIPS)':
 C_PATH='@t6g_mb_lib.t6g(sch_1):page127_i338@pure_quanta.q_cap(chips)';

PART_NAME
 C91 'Q_CAP_C0805-10UF,16V,10%,X7R,CH6103K1A00':
;

SECTION_NUMBER 1
 '@T6G_MB_LIB.T6G(SCH_1):PAGE127_I346@PURE_QUANTA.Q_CAP(CHIPS)':
 C_PATH='@t6g_mb_lib.t6g(sch_1):page127_i346@pure_quanta.q_cap(chips)';

PART_NAME
 C90 'Q_CAP_C0402-2.2UF,6.3V,20%,X6S,CH5221MEB00':
;

SECTION_NUMBER 1
 '@T6G_MB_LIB.T6G(SCH_1):PAGE127_I341@PURE_QUANTA.Q_CAP(CHIPS)':
 C_PATH='@t6g_mb_lib.t6g(sch_1):page127_i341@pure_quanta.q_cap(chips)';

PART_NAME
 R77 'Q_RES_0402LF-23.2K,1%,1/16W,CHIP,TMP_QCS32322FB11':;

SECTION_NUMBER 1
 '@T6G_MB_LIB.T6G(SCH_1):PAGE128_I349@PURE_QUANTA.Q_RES(CHIPS)':
 C_PATH='@t6g_mb_lib.t6g(sch_1):page128_i349@pure_quanta.q_res(chips)';

PART_NAME
 J27 'SCONN288_ADR50001P013C01-SCONN288_ADR50001-P013C01,SMLF,IO,DFHST8FS302':;

SECTION_NUMBER 1
 '@T6G_MB_LIB.T6G(SCH_1):PAGE128_I346@PURE_QUANTA.SCONN288_ADR50001P013C01(CHIPS)':
 C_PATH='@t6g_mb_lib.t6g(sch_1):page128_i346@pure_quanta.sconn288_adr50001p013c0~
1(chips)';

SECTION_NUMBER 2
 '@T6G_MB_LIB.T6G(SCH_1):PAGE128_I347@PURE_QUANTA.SCONN288_ADR50001P013C01(CHIPS)':
 C_PATH='@t6g_mb_lib.t6g(sch_1):page128_i347@pure_quanta.sconn288_adr50001p013c0~
1(chips)';

SECTION_NUMBER 3
 '@T6G_MB_LIB.T6G(SCH_1):PAGE128_I348@PURE_QUANTA.SCONN288_ADR50001P013C01(CHIPS)':
 C_PATH='@t6g_mb_lib.t6g(sch_1):page128_i348@pure_quanta.sconn288_adr50001p013c0~
1(chips)';

PART_NAME
 C89 'Q_CAP_C0805-10UF,16V,10%,X7R,CH6103K1A00':
;

SECTION_NUMBER 1
 '@T6G_MB_LIB.T6G(SCH_1):PAGE128_I338@PURE_QUANTA.Q_CAP(CHIPS)':
 C_PATH='@t6g_mb_lib.t6g(sch_1):page128_i338@pure_quanta.q_cap(chips)';

PART_NAME
 C88 'Q_CAP_C0805-10UF,16V,10%,X7R,CH6103K1A00':
;

SECTION_NUMBER 1
 '@T6G_MB_LIB.T6G(SCH_1):PAGE128_I345@PURE_QUANTA.Q_CAP(CHIPS)':
 C_PATH='@t6g_mb_lib.t6g(sch_1):page128_i345@pure_quanta.q_cap(chips)';

PART_NAME
 C87 'Q_CAP_C0402-2.2UF,6.3V,20%,X6S,CH5221MEB00':
;

SECTION_NUMBER 1
 '@T6G_MB_LIB.T6G(SCH_1):PAGE128_I341@PURE_QUANTA.Q_CAP(CHIPS)':
 C_PATH='@t6g_mb_lib.t6g(sch_1):page128_i341@pure_quanta.q_cap(chips)';

PART_NAME
 R76 'Q_RES_0402LF-35.7K,1%,1/16W,CHIP,CS33572FB01':;

SECTION_NUMBER 1
 '@T6G_MB_LIB.T6G(SCH_1):PAGE129_I348@PURE_QUANTA.Q_RES(CHIPS)':
 C_PATH='@t6g_mb_lib.t6g(sch_1):page129_i348@pure_quanta.q_res(chips)';

PART_NAME
 J28 'SCONN288_ADR50001P003C01-SCONN288_ADR50001-P003C01,SMLF,IO,DFHST8FS301':;

SECTION_NUMBER 1
 '@T6G_MB_LIB.T6G(SCH_1):PAGE129_I345@PURE_QUANTA.SCONN288_ADR50001P003C01(CHIPS)':
 C_PATH='@t6g_mb_lib.t6g(sch_1):page129_i345@pure_quanta.sconn288_adr50001p003c0~
1(chips)';

SECTION_NUMBER 2
 '@T6G_MB_LIB.T6G(SCH_1):PAGE129_I346@PURE_QUANTA.SCONN288_ADR50001P003C01(CHIPS)':
 C_PATH='@t6g_mb_lib.t6g(sch_1):page129_i346@pure_quanta.sconn288_adr50001p003c0~
1(chips)';

SECTION_NUMBER 3
 '@T6G_MB_LIB.T6G(SCH_1):PAGE129_I347@PURE_QUANTA.SCONN288_ADR50001P003C01(CHIPS)':
 C_PATH='@t6g_mb_lib.t6g(sch_1):page129_i347@pure_quanta.sconn288_adr50001p003c0~
1(chips)';

PART_NAME
 C86 'Q_CAP_C0805-10UF,16V,10%,X7R,CH6103K1A00':
;

SECTION_NUMBER 1
 '@T6G_MB_LIB.T6G(SCH_1):PAGE129_I338@PURE_QUANTA.Q_CAP(CHIPS)':
 C_PATH='@t6g_mb_lib.t6g(sch_1):page129_i338@pure_quanta.q_cap(chips)';

PART_NAME
 C85 'Q_CAP_C0805-10UF,16V,10%,X7R,CH6103K1A00':
;

SECTION_NUMBER 1
 '@T6G_MB_LIB.T6G(SCH_1):PAGE129_I344@PURE_QUANTA.Q_CAP(CHIPS)':
 C_PATH='@t6g_mb_lib.t6g(sch_1):page129_i344@pure_quanta.q_cap(chips)';

PART_NAME
 C84 'Q_CAP_C0402-2.2UF,6.3V,20%,X6S,CH5221MEB00':
;

SECTION_NUMBER 1
 '@T6G_MB_LIB.T6G(SCH_1):PAGE129_I341@PURE_QUANTA.Q_CAP(CHIPS)':
 C_PATH='@t6g_mb_lib.t6g(sch_1):page129_i341@pure_quanta.q_cap(chips)';

PART_NAME
 R75 'Q_RES_0402LF-54.9K,1%,1/16W,CHIP,TMP_QCS35492FB14':;

SECTION_NUMBER 1
 '@T6G_MB_LIB.T6G(SCH_1):PAGE130_I348@PURE_QUANTA.Q_RES(CHIPS)':
 C_PATH='@t6g_mb_lib.t6g(sch_1):page130_i348@pure_quanta.q_res(chips)';

PART_NAME
 J29 'SCONN288_ADR50001P013C01-SCONN288_ADR50001-P013C01,SMLF,IO,DFHST8FS302':;

SECTION_NUMBER 1
 '@T6G_MB_LIB.T6G(SCH_1):PAGE130_I346@PURE_QUANTA.SCONN288_ADR50001P013C01(CHIPS)':
 C_PATH='@t6g_mb_lib.t6g(sch_1):page130_i346@pure_quanta.sconn288_adr50001p013c0~
1(chips)';

SECTION_NUMBER 2
 '@T6G_MB_LIB.T6G(SCH_1):PAGE130_I347@PURE_QUANTA.SCONN288_ADR50001P013C01(CHIPS)':
 C_PATH='@t6g_mb_lib.t6g(sch_1):page130_i347@pure_quanta.sconn288_adr50001p013c0~
1(chips)';

SECTION_NUMBER 3
 '@T6G_MB_LIB.T6G(SCH_1):PAGE130_I345@PURE_QUANTA.SCONN288_ADR50001P013C01(CHIPS)':
 C_PATH='@t6g_mb_lib.t6g(sch_1):page130_i345@pure_quanta.sconn288_adr50001p013c0~
1(chips)';

PART_NAME
 C83 'Q_CAP_C0805-10UF,16V,10%,X7R,CH6103K1A00':
;

SECTION_NUMBER 1
 '@T6G_MB_LIB.T6G(SCH_1):PAGE130_I338@PURE_QUANTA.Q_CAP(CHIPS)':
 C_PATH='@t6g_mb_lib.t6g(sch_1):page130_i338@pure_quanta.q_cap(chips)';

PART_NAME
 C82 'Q_CAP_C0805-10UF,16V,10%,X7R,CH6103K1A00':
;

SECTION_NUMBER 1
 '@T6G_MB_LIB.T6G(SCH_1):PAGE130_I344@PURE_QUANTA.Q_CAP(CHIPS)':
 C_PATH='@t6g_mb_lib.t6g(sch_1):page130_i344@pure_quanta.q_cap(chips)';

PART_NAME
 C81 'Q_CAP_C0402-2.2UF,6.3V,20%,X6S,CH5221MEB00':
;

SECTION_NUMBER 1
 '@T6G_MB_LIB.T6G(SCH_1):PAGE130_I341@PURE_QUANTA.Q_CAP(CHIPS)':
 C_PATH='@t6g_mb_lib.t6g(sch_1):page130_i341@pure_quanta.q_cap(chips)';

PART_NAME
 R74 'Q_RES_0402LF-84.5K,1%,1/16W,CHIP,CS38452FB14':;

SECTION_NUMBER 1
 '@T6G_MB_LIB.T6G(SCH_1):PAGE131_I348@PURE_QUANTA.Q_RES(CHIPS)':
 C_PATH='@t6g_mb_lib.t6g(sch_1):page131_i348@pure_quanta.q_res(chips)';

PART_NAME
 J30 'SCONN288_ADR50001P003C01-SCONN288_ADR50001-P003C01,SMLF,IO,DFHST8FS301':;

SECTION_NUMBER 1
 '@T6G_MB_LIB.T6G(SCH_1):PAGE131_I345@PURE_QUANTA.SCONN288_ADR50001P003C01(CHIPS)':
 C_PATH='@t6g_mb_lib.t6g(sch_1):page131_i345@pure_quanta.sconn288_adr50001p003c0~
1(chips)';

SECTION_NUMBER 2
 '@T6G_MB_LIB.T6G(SCH_1):PAGE131_I346@PURE_QUANTA.SCONN288_ADR50001P003C01(CHIPS)':
 C_PATH='@t6g_mb_lib.t6g(sch_1):page131_i346@pure_quanta.sconn288_adr50001p003c0~
1(chips)';

SECTION_NUMBER 3
 '@T6G_MB_LIB.T6G(SCH_1):PAGE131_I347@PURE_QUANTA.SCONN288_ADR50001P003C01(CHIPS)':
 C_PATH='@t6g_mb_lib.t6g(sch_1):page131_i347@pure_quanta.sconn288_adr50001p003c0~
1(chips)';

PART_NAME
 C80 'Q_CAP_C0805-10UF,16V,10%,X7R,CH6103K1A00':
;

SECTION_NUMBER 1
 '@T6G_MB_LIB.T6G(SCH_1):PAGE131_I338@PURE_QUANTA.Q_CAP(CHIPS)':
 C_PATH='@t6g_mb_lib.t6g(sch_1):page131_i338@pure_quanta.q_cap(chips)';

PART_NAME
 C79 'Q_CAP_C0805-10UF,16V,10%,X7R,CH6103K1A00':
;

SECTION_NUMBER 1
 '@T6G_MB_LIB.T6G(SCH_1):PAGE131_I344@PURE_QUANTA.Q_CAP(CHIPS)':
 C_PATH='@t6g_mb_lib.t6g(sch_1):page131_i344@pure_quanta.q_cap(chips)';

PART_NAME
 C78 'Q_CAP_C0402-2.2UF,6.3V,20%,X6S,CH5221MEB00':
;

SECTION_NUMBER 1
 '@T6G_MB_LIB.T6G(SCH_1):PAGE131_I340@PURE_QUANTA.Q_CAP(CHIPS)':
 C_PATH='@t6g_mb_lib.t6g(sch_1):page131_i340@pure_quanta.q_cap(chips)';

PART_NAME
 R73 'Q_RES_0402LF-127K,1%,1/16W,CHIP,CS41272FB19':;

SECTION_NUMBER 1
 '@T6G_MB_LIB.T6G(SCH_1):PAGE132_I348@PURE_QUANTA.Q_RES(CHIPS)':
 C_PATH='@t6g_mb_lib.t6g(sch_1):page132_i348@pure_quanta.q_res(chips)';

PART_NAME
 J31 'SCONN288_ADR50001P013C01-SCONN288_ADR50001-P013C01,SMLF,IO,DFHST8FS302':;

SECTION_NUMBER 1
 '@T6G_MB_LIB.T6G(SCH_1):PAGE132_I345@PURE_QUANTA.SCONN288_ADR50001P013C01(CHIPS)':
 C_PATH='@t6g_mb_lib.t6g(sch_1):page132_i345@pure_quanta.sconn288_adr50001p013c0~
1(chips)';

SECTION_NUMBER 2
 '@T6G_MB_LIB.T6G(SCH_1):PAGE132_I346@PURE_QUANTA.SCONN288_ADR50001P013C01(CHIPS)':
 C_PATH='@t6g_mb_lib.t6g(sch_1):page132_i346@pure_quanta.sconn288_adr50001p013c0~
1(chips)';

SECTION_NUMBER 3
 '@T6G_MB_LIB.T6G(SCH_1):PAGE132_I347@PURE_QUANTA.SCONN288_ADR50001P013C01(CHIPS)':
 C_PATH='@t6g_mb_lib.t6g(sch_1):page132_i347@pure_quanta.sconn288_adr50001p013c0~
1(chips)';

PART_NAME
 C77 'Q_CAP_C0805-10UF,16V,10%,X7R,CH6103K1A00':
;

SECTION_NUMBER 1
 '@T6G_MB_LIB.T6G(SCH_1):PAGE132_I338@PURE_QUANTA.Q_CAP(CHIPS)':
 C_PATH='@t6g_mb_lib.t6g(sch_1):page132_i338@pure_quanta.q_cap(chips)';

PART_NAME
 C76 'Q_CAP_C0805-10UF,16V,10%,X7R,CH6103K1A00':
;

SECTION_NUMBER 1
 '@T6G_MB_LIB.T6G(SCH_1):PAGE132_I344@PURE_QUANTA.Q_CAP(CHIPS)':
 C_PATH='@t6g_mb_lib.t6g(sch_1):page132_i344@pure_quanta.q_cap(chips)';

PART_NAME
 C75 'Q_CAP_C0402-2.2UF,6.3V,20%,X6S,CH5221MEB00':
;

SECTION_NUMBER 1
 '@T6G_MB_LIB.T6G(SCH_1):PAGE132_I340@PURE_QUANTA.Q_CAP(CHIPS)':
 C_PATH='@t6g_mb_lib.t6g(sch_1):page132_i340@pure_quanta.q_cap(chips)';

PART_NAME
 R72 'Q_RES_0402LF-196K,1%,1/16W,CHIP,CS41962FB01':;

SECTION_NUMBER 1
 '@T6G_MB_LIB.T6G(SCH_1):PAGE133_I348@PURE_QUANTA.Q_RES(CHIPS)':
 C_PATH='@t6g_mb_lib.t6g(sch_1):page133_i348@pure_quanta.q_res(chips)';

PART_NAME
 J32 'SCONN288_ADR50001P003C01-SCONN288_ADR50001-P003C01,SMLF,IO,DFHST8FS301':;

SECTION_NUMBER 1
 '@T6G_MB_LIB.T6G(SCH_1):PAGE133_I345@PURE_QUANTA.SCONN288_ADR50001P003C01(CHIPS)':
 C_PATH='@t6g_mb_lib.t6g(sch_1):page133_i345@pure_quanta.sconn288_adr50001p003c0~
1(chips)';

SECTION_NUMBER 2
 '@T6G_MB_LIB.T6G(SCH_1):PAGE133_I346@PURE_QUANTA.SCONN288_ADR50001P003C01(CHIPS)':
 C_PATH='@t6g_mb_lib.t6g(sch_1):page133_i346@pure_quanta.sconn288_adr50001p003c0~
1(chips)';

SECTION_NUMBER 3
 '@T6G_MB_LIB.T6G(SCH_1):PAGE133_I347@PURE_QUANTA.SCONN288_ADR50001P003C01(CHIPS)':
 C_PATH='@t6g_mb_lib.t6g(sch_1):page133_i347@pure_quanta.sconn288_adr50001p003c0~
1(chips)';

PART_NAME
 C74 'Q_CAP_C0805-10UF,16V,10%,X7R,CH6103K1A00':
;

SECTION_NUMBER 1
 '@T6G_MB_LIB.T6G(SCH_1):PAGE133_I338@PURE_QUANTA.Q_CAP(CHIPS)':
 C_PATH='@t6g_mb_lib.t6g(sch_1):page133_i338@pure_quanta.q_cap(chips)';

PART_NAME
 C73 'Q_CAP_C0805-10UF,16V,10%,X7R,CH6103K1A00':
;

SECTION_NUMBER 1
 '@T6G_MB_LIB.T6G(SCH_1):PAGE133_I344@PURE_QUANTA.Q_CAP(CHIPS)':
 C_PATH='@t6g_mb_lib.t6g(sch_1):page133_i344@pure_quanta.q_cap(chips)';

PART_NAME
 C72 'Q_CAP_C0402-2.2UF,6.3V,20%,X6S,CH5221MEB00':
;

SECTION_NUMBER 1
 '@T6G_MB_LIB.T6G(SCH_1):PAGE133_I340@PURE_QUANTA.Q_CAP(CHIPS)':
 C_PATH='@t6g_mb_lib.t6g(sch_1):page133_i340@pure_quanta.q_cap(chips)';

PART_NAME
 U1 'SOCKET4677_AZIFS035P001C01-SOCKET4677_AZIFS035-P001C01,SMLF,IO,DGA^7000012':;

SECTION_NUMBER 1
 '@T6G_MB_LIB.T6G(SCH_1):PAGE47_I589@PURE_QUANTA.SOCKET4677_AZIFS035P001C01(CHIPS)':
 C_PATH='@t6g_mb_lib.t6g(sch_1):page47_i589@pure_quanta.socket4677_azifs035p001c~
01(chips)';

SECTION_NUMBER 2
 '@T6G_MB_LIB.T6G(SCH_1):PAGE48_I287@PURE_QUANTA.SOCKET4677_AZIFS035P001C01(CHIPS)':
 C_PATH='@t6g_mb_lib.t6g(sch_1):page48_i287@pure_quanta.socket4677_azifs035p001c~
01(chips)';

SECTION_NUMBER 3
 '@T6G_MB_LIB.T6G(SCH_1):PAGE49_I292@PURE_QUANTA.SOCKET4677_AZIFS035P001C01(CHIPS)':
 C_PATH='@t6g_mb_lib.t6g(sch_1):page49_i292@pure_quanta.socket4677_azifs035p001c~
01(chips)';

SECTION_NUMBER 4
 '@T6G_MB_LIB.T6G(SCH_1):PAGE50_I75@PURE_QUANTA.SOCKET4677_AZIFS035P001C01(CHIPS)':
 C_PATH='@t6g_mb_lib.t6g(sch_1):page50_i75@pure_quanta.socket4677_azifs035p001c0~
1(chips)';

SECTION_NUMBER 5
 '@T6G_MB_LIB.T6G(SCH_1):PAGE51_I5@PURE_QUANTA.SOCKET4677_AZIFS035P001C01(CHIPS)':
 C_PATH='@t6g_mb_lib.t6g(sch_1):page51_i5@pure_quanta.socket4677_azifs035p001c01~
(chips)';

SECTION_NUMBER 6
 '@T6G_MB_LIB.T6G(SCH_1):PAGE52_I7@PURE_QUANTA.SOCKET4677_AZIFS035P001C01(CHIPS)':
 C_PATH='@t6g_mb_lib.t6g(sch_1):page52_i7@pure_quanta.socket4677_azifs035p001c01~
(chips)';

SECTION_NUMBER 7
 '@T6G_MB_LIB.T6G(SCH_1):PAGE53_I242@PURE_QUANTA.SOCKET4677_AZIFS035P001C01(CHIPS)':
 C_PATH='@t6g_mb_lib.t6g(sch_1):page53_i242@pure_quanta.socket4677_azifs035p001c~
01(chips)';

SECTION_NUMBER 8
 '@T6G_MB_LIB.T6G(SCH_1):PAGE54_I660@PURE_QUANTA.SOCKET4677_AZIFS035P001C01(CHIPS)':
 C_PATH='@t6g_mb_lib.t6g(sch_1):page54_i660@pure_quanta.socket4677_azifs035p001c~
01(chips)';

SECTION_NUMBER 9
 '@T6G_MB_LIB.T6G(SCH_1):PAGE55_I654@PURE_QUANTA.SOCKET4677_AZIFS035P001C01(CHIPS)':
 C_PATH='@t6g_mb_lib.t6g(sch_1):page55_i654@pure_quanta.socket4677_azifs035p001c~
01(chips)';

SECTION_NUMBER 10
 '@T6G_MB_LIB.T6G(SCH_1):PAGE56_I713@PURE_QUANTA.SOCKET4677_AZIFS035P001C01(CHIPS)':
 C_PATH='@t6g_mb_lib.t6g(sch_1):page56_i713@pure_quanta.socket4677_azifs035p001c~
01(chips)';

SECTION_NUMBER 11
 '@T6G_MB_LIB.T6G(SCH_1):PAGE57_I616@PURE_QUANTA.SOCKET4677_AZIFS035P001C01(CHIPS)':
 C_PATH='@t6g_mb_lib.t6g(sch_1):page57_i616@pure_quanta.socket4677_azifs035p001c~
01(chips)';

SECTION_NUMBER 12
 '@T6G_MB_LIB.T6G(SCH_1):PAGE58_I944@PURE_QUANTA.SOCKET4677_AZIFS035P001C01(CHIPS)':
 C_PATH='@t6g_mb_lib.t6g(sch_1):page58_i944@pure_quanta.socket4677_azifs035p001c~
01(chips)';

SECTION_NUMBER 13
 '@T6G_MB_LIB.T6G(SCH_1):PAGE59_I631@PURE_QUANTA.SOCKET4677_AZIFS035P001C01(CHIPS)':
 C_PATH='@t6g_mb_lib.t6g(sch_1):page59_i631@pure_quanta.socket4677_azifs035p001c~
01(chips)';

SECTION_NUMBER 14
 '@T6G_MB_LIB.T6G(SCH_1):PAGE60_I637@PURE_QUANTA.SOCKET4677_AZIFS035P001C01(CHIPS)':
 C_PATH='@t6g_mb_lib.t6g(sch_1):page60_i637@pure_quanta.socket4677_azifs035p001c~
01(chips)';

SECTION_NUMBER 15
 '@T6G_MB_LIB.T6G(SCH_1):PAGE61_I637@PURE_QUANTA.SOCKET4677_AZIFS035P001C01(CHIPS)':
 C_PATH='@t6g_mb_lib.t6g(sch_1):page61_i637@pure_quanta.socket4677_azifs035p001c~
01(chips)';

SECTION_NUMBER 16
 '@T6G_MB_LIB.T6G(SCH_1):PAGE62_I107@PURE_QUANTA.SOCKET4677_AZIFS035P001C01(CHIPS)':
 C_PATH='@t6g_mb_lib.t6g(sch_1):page62_i107@pure_quanta.socket4677_azifs035p001c~
01(chips)';

SECTION_NUMBER 17
 '@T6G_MB_LIB.T6G(SCH_1):PAGE62_I108@PURE_QUANTA.SOCKET4677_AZIFS035P001C01(CHIPS)':
 C_PATH='@t6g_mb_lib.t6g(sch_1):page62_i108@pure_quanta.socket4677_azifs035p001c~
01(chips)';

SECTION_NUMBER 18
 '@T6G_MB_LIB.T6G(SCH_1):PAGE63_I409@PURE_QUANTA.SOCKET4677_AZIFS035P001C01(CHIPS)':
 C_PATH='@t6g_mb_lib.t6g(sch_1):page63_i409@pure_quanta.socket4677_azifs035p001c~
01(chips)';

SECTION_NUMBER 19
 '@T6G_MB_LIB.T6G(SCH_1):PAGE63_I410@PURE_QUANTA.SOCKET4677_AZIFS035P001C01(CHIPS)':
 C_PATH='@t6g_mb_lib.t6g(sch_1):page63_i410@pure_quanta.socket4677_azifs035p001c~
01(chips)';

SECTION_NUMBER 20
 '@T6G_MB_LIB.T6G(SCH_1):PAGE64_I69@PURE_QUANTA.SOCKET4677_AZIFS035P001C01(CHIPS)':
 C_PATH='@t6g_mb_lib.t6g(sch_1):page64_i69@pure_quanta.socket4677_azifs035p001c0~
1(chips)';

SECTION_NUMBER 21
 '@T6G_MB_LIB.T6G(SCH_1):PAGE65_I69@PURE_QUANTA.SOCKET4677_AZIFS035P001C01(CHIPS)':
 C_PATH='@t6g_mb_lib.t6g(sch_1):page65_i69@pure_quanta.socket4677_azifs035p001c0~
1(chips)';

SECTION_NUMBER 22
 '@T6G_MB_LIB.T6G(SCH_1):PAGE66_I101@PURE_QUANTA.SOCKET4677_AZIFS035P001C01(CHIPS)':
 C_PATH='@t6g_mb_lib.t6g(sch_1):page66_i101@pure_quanta.socket4677_azifs035p001c~
01(chips)';

SECTION_NUMBER 23
 '@T6G_MB_LIB.T6G(SCH_1):PAGE67_I101@PURE_QUANTA.SOCKET4677_AZIFS035P001C01(CHIPS)':
 C_PATH='@t6g_mb_lib.t6g(sch_1):page67_i101@pure_quanta.socket4677_azifs035p001c~
01(chips)';

SECTION_NUMBER 24
 '@T6G_MB_LIB.T6G(SCH_1):PAGE68_I355@PURE_QUANTA.SOCKET4677_AZIFS035P001C01(CHIPS)':
 C_PATH='@t6g_mb_lib.t6g(sch_1):page68_i355@pure_quanta.socket4677_azifs035p001c~
01(chips)';

SECTION_NUMBER 25
 '@T6G_MB_LIB.T6G(SCH_1):PAGE69_I102@PURE_QUANTA.SOCKET4677_AZIFS035P001C01(CHIPS)':
 C_PATH='@t6g_mb_lib.t6g(sch_1):page69_i102@pure_quanta.socket4677_azifs035p001c~
01(chips)';

SECTION_NUMBER 26
 '@T6G_MB_LIB.T6G(SCH_1):PAGE70_I19@PURE_QUANTA.SOCKET4677_AZIFS035P001C01(CHIPS)':
 C_PATH='@t6g_mb_lib.t6g(sch_1):page70_i19@pure_quanta.socket4677_azifs035p001c0~
1(chips)';

SECTION_NUMBER 27
 '@T6G_MB_LIB.T6G(SCH_1):PAGE70_I20@PURE_QUANTA.SOCKET4677_AZIFS035P001C01(CHIPS)':
 C_PATH='@t6g_mb_lib.t6g(sch_1):page70_i20@pure_quanta.socket4677_azifs035p001c0~
1(chips)';

SECTION_NUMBER 28
 '@T6G_MB_LIB.T6G(SCH_1):PAGE71_I52@PURE_QUANTA.SOCKET4677_AZIFS035P001C01(CHIPS)':
 C_PATH='@t6g_mb_lib.t6g(sch_1):page71_i52@pure_quanta.socket4677_azifs035p001c0~
1(chips)';

SECTION_NUMBER 29
 '@T6G_MB_LIB.T6G(SCH_1):PAGE71_I53@PURE_QUANTA.SOCKET4677_AZIFS035P001C01(CHIPS)':
 C_PATH='@t6g_mb_lib.t6g(sch_1):page71_i53@pure_quanta.socket4677_azifs035p001c0~
1(chips)';

SECTION_NUMBER 30
 '@T6G_MB_LIB.T6G(SCH_1):PAGE72_I28@PURE_QUANTA.SOCKET4677_AZIFS035P001C01(CHIPS)':
 C_PATH='@t6g_mb_lib.t6g(sch_1):page72_i28@pure_quanta.socket4677_azifs035p001c0~
1(chips)';

SECTION_NUMBER 31
 '@T6G_MB_LIB.T6G(SCH_1):PAGE72_I29@PURE_QUANTA.SOCKET4677_AZIFS035P001C01(CHIPS)':
 C_PATH='@t6g_mb_lib.t6g(sch_1):page72_i29@pure_quanta.socket4677_azifs035p001c0~
1(chips)';

SECTION_NUMBER 32
 '@T6G_MB_LIB.T6G(SCH_1):PAGE72_I30@PURE_QUANTA.SOCKET4677_AZIFS035P001C01(CHIPS)':
 C_PATH='@t6g_mb_lib.t6g(sch_1):page72_i30@pure_quanta.socket4677_azifs035p001c0~
1(chips)';

SECTION_NUMBER 33
 '@T6G_MB_LIB.T6G(SCH_1):PAGE73_I15@PURE_QUANTA.SOCKET4677_AZIFS035P001C01(CHIPS)':
 C_PATH='@t6g_mb_lib.t6g(sch_1):page73_i15@pure_quanta.socket4677_azifs035p001c0~
1(chips)';

SECTION_NUMBER 34
 '@T6G_MB_LIB.T6G(SCH_1):PAGE73_I18@PURE_QUANTA.SOCKET4677_AZIFS035P001C01(CHIPS)':
 C_PATH='@t6g_mb_lib.t6g(sch_1):page73_i18@pure_quanta.socket4677_azifs035p001c0~
1(chips)';

SECTION_NUMBER 35
 '@T6G_MB_LIB.T6G(SCH_1):PAGE73_I19@PURE_QUANTA.SOCKET4677_AZIFS035P001C01(CHIPS)':
 C_PATH='@t6g_mb_lib.t6g(sch_1):page73_i19@pure_quanta.socket4677_azifs035p001c0~
1(chips)';

SECTION_NUMBER 36
 '@T6G_MB_LIB.T6G(SCH_1):PAGE74_I35@PURE_QUANTA.SOCKET4677_AZIFS035P001C01(CHIPS)':
 C_PATH='@t6g_mb_lib.t6g(sch_1):page74_i35@pure_quanta.socket4677_azifs035p001c0~
1(chips)';

SECTION_NUMBER 37
 '@T6G_MB_LIB.T6G(SCH_1):PAGE74_I36@PURE_QUANTA.SOCKET4677_AZIFS035P001C01(CHIPS)':
 C_PATH='@t6g_mb_lib.t6g(sch_1):page74_i36@pure_quanta.socket4677_azifs035p001c0~
1(chips)';

SECTION_NUMBER 38
 '@T6G_MB_LIB.T6G(SCH_1):PAGE74_I37@PURE_QUANTA.SOCKET4677_AZIFS035P001C01(CHIPS)':
 C_PATH='@t6g_mb_lib.t6g(sch_1):page74_i37@pure_quanta.socket4677_azifs035p001c0~
1(chips)';

SECTION_NUMBER 39
 '@T6G_MB_LIB.T6G(SCH_1):PAGE75_I7@PURE_QUANTA.SOCKET4677_AZIFS035P001C01(CHIPS)':
 C_PATH='@t6g_mb_lib.t6g(sch_1):page75_i7@pure_quanta.socket4677_azifs035p001c01~
(chips)';

SECTION_NUMBER 40
 '@T6G_MB_LIB.T6G(SCH_1):PAGE75_I8@PURE_QUANTA.SOCKET4677_AZIFS035P001C01(CHIPS)':
 C_PATH='@t6g_mb_lib.t6g(sch_1):page75_i8@pure_quanta.socket4677_azifs035p001c01~
(chips)';

SECTION_NUMBER 41
 '@T6G_MB_LIB.T6G(SCH_1):PAGE76_I6@PURE_QUANTA.SOCKET4677_AZIFS035P001C01(CHIPS)':
 C_PATH='@t6g_mb_lib.t6g(sch_1):page76_i6@pure_quanta.socket4677_azifs035p001c01~
(chips)';

SECTION_NUMBER 42
 '@T6G_MB_LIB.T6G(SCH_1):PAGE76_I7@PURE_QUANTA.SOCKET4677_AZIFS035P001C01(CHIPS)':
 C_PATH='@t6g_mb_lib.t6g(sch_1):page76_i7@pure_quanta.socket4677_azifs035p001c01~
(chips)';

PART_NAME
 C71 'Q_CAP_C0402-0.1UF,16V,10%,X7R,CH4103K1B08':
;

SECTION_NUMBER 1
 '@T6G_MB_LIB.T6G(SCH_1):PAGE71_I36@PURE_QUANTA.Q_CAP(CHIPS)':
 C_PATH='@t6g_mb_lib.t6g(sch_1):page71_i36@pure_quanta.q_cap(chips)';

PART_NAME
 R48 'Q_RES_0402LF-127K,1%,1/16W,CHIP,CS41272FB19':;

SECTION_NUMBER 1
 '@T6G_MB_LIB.T6G(SCH_1):PAGE124_I348@PURE_QUANTA.Q_RES(CHIPS)':
 C_PATH='@t6g_mb_lib.t6g(sch_1):page124_i348@pure_quanta.q_res(chips)';

PART_NAME
 J23 'SCONN288_ADR50001P013C01-SCONN288_ADR50001-P013C01,SMLF,IO,DFHST8FS302':;

SECTION_NUMBER 1
 '@T6G_MB_LIB.T6G(SCH_1):PAGE124_I345@PURE_QUANTA.SCONN288_ADR50001P013C01(CHIPS)':
 C_PATH='@t6g_mb_lib.t6g(sch_1):page124_i345@pure_quanta.sconn288_adr50001p013c0~
1(chips)';

SECTION_NUMBER 2
 '@T6G_MB_LIB.T6G(SCH_1):PAGE124_I346@PURE_QUANTA.SCONN288_ADR50001P013C01(CHIPS)':
 C_PATH='@t6g_mb_lib.t6g(sch_1):page124_i346@pure_quanta.sconn288_adr50001p013c0~
1(chips)';

SECTION_NUMBER 3
 '@T6G_MB_LIB.T6G(SCH_1):PAGE124_I347@PURE_QUANTA.SCONN288_ADR50001P013C01(CHIPS)':
 C_PATH='@t6g_mb_lib.t6g(sch_1):page124_i347@pure_quanta.sconn288_adr50001p013c0~
1(chips)';

PART_NAME
 C70 'Q_CAP_C0805-10UF,16V,10%,X7R,CH6103K1A00':
;

SECTION_NUMBER 1
 '@T6G_MB_LIB.T6G(SCH_1):PAGE124_I338@PURE_QUANTA.Q_CAP(CHIPS)':
 C_PATH='@t6g_mb_lib.t6g(sch_1):page124_i338@pure_quanta.q_cap(chips)';

PART_NAME
 C69 'Q_CAP_C0805-10UF,16V,10%,X7R,CH6103K1A00':
;

SECTION_NUMBER 1
 '@T6G_MB_LIB.T6G(SCH_1):PAGE124_I344@PURE_QUANTA.Q_CAP(CHIPS)':
 C_PATH='@t6g_mb_lib.t6g(sch_1):page124_i344@pure_quanta.q_cap(chips)';

PART_NAME
 C68 'Q_CAP_C0402-2.2UF,6.3V,20%,X6S,CH5221MEB00':
;

SECTION_NUMBER 1
 '@T6G_MB_LIB.T6G(SCH_1):PAGE124_I341@PURE_QUANTA.Q_CAP(CHIPS)':
 C_PATH='@t6g_mb_lib.t6g(sch_1):page124_i341@pure_quanta.q_cap(chips)';

PART_NAME
 R47 'Q_RES_0402LF-84.5K,1%,1/16W,CHIP,CS38452FB14':;

SECTION_NUMBER 1
 '@T6G_MB_LIB.T6G(SCH_1):PAGE123_I348@PURE_QUANTA.Q_RES(CHIPS)':
 C_PATH='@t6g_mb_lib.t6g(sch_1):page123_i348@pure_quanta.q_res(chips)';

PART_NAME
 J22 'SCONN288_ADR50001P003C01-SCONN288_ADR50001-P003C01,SMLF,IO,DFHST8FS301':;

SECTION_NUMBER 1
 '@T6G_MB_LIB.T6G(SCH_1):PAGE123_I347@PURE_QUANTA.SCONN288_ADR50001P003C01(CHIPS)':
 C_PATH='@t6g_mb_lib.t6g(sch_1):page123_i347@pure_quanta.sconn288_adr50001p003c0~
1(chips)';

SECTION_NUMBER 2
 '@T6G_MB_LIB.T6G(SCH_1):PAGE123_I346@PURE_QUANTA.SCONN288_ADR50001P003C01(CHIPS)':
 C_PATH='@t6g_mb_lib.t6g(sch_1):page123_i346@pure_quanta.sconn288_adr50001p003c0~
1(chips)';

SECTION_NUMBER 3
 '@T6G_MB_LIB.T6G(SCH_1):PAGE123_I345@PURE_QUANTA.SCONN288_ADR50001P003C01(CHIPS)':
 C_PATH='@t6g_mb_lib.t6g(sch_1):page123_i345@pure_quanta.sconn288_adr50001p003c0~
1(chips)';

PART_NAME
 C67 'Q_CAP_C0805-10UF,16V,10%,X7R,CH6103K1A00':
;

SECTION_NUMBER 1
 '@T6G_MB_LIB.T6G(SCH_1):PAGE123_I338@PURE_QUANTA.Q_CAP(CHIPS)':
 C_PATH='@t6g_mb_lib.t6g(sch_1):page123_i338@pure_quanta.q_cap(chips)';

PART_NAME
 C66 'Q_CAP_C0805-10UF,16V,10%,X7R,CH6103K1A00':
;

SECTION_NUMBER 1
 '@T6G_MB_LIB.T6G(SCH_1):PAGE123_I344@PURE_QUANTA.Q_CAP(CHIPS)':
 C_PATH='@t6g_mb_lib.t6g(sch_1):page123_i344@pure_quanta.q_cap(chips)';

PART_NAME
 C65 'Q_CAP_C0402-2.2UF,6.3V,20%,X6S,CH5221MEB00':
;

SECTION_NUMBER 1
 '@T6G_MB_LIB.T6G(SCH_1):PAGE123_I341@PURE_QUANTA.Q_CAP(CHIPS)':
 C_PATH='@t6g_mb_lib.t6g(sch_1):page123_i341@pure_quanta.q_cap(chips)';

PART_NAME
 R46 'Q_RES_0402LF-54.9K,1%,1/16W,CHIP,TMP_QCS35492FB14':;

SECTION_NUMBER 1
 '@T6G_MB_LIB.T6G(SCH_1):PAGE122_I348@PURE_QUANTA.Q_RES(CHIPS)':
 C_PATH='@t6g_mb_lib.t6g(sch_1):page122_i348@pure_quanta.q_res(chips)';

PART_NAME
 J21 'SCONN288_ADR50001P013C01-SCONN288_ADR50001-P013C01,SMLF,IO,DFHST8FS302':;

SECTION_NUMBER 1
 '@T6G_MB_LIB.T6G(SCH_1):PAGE122_I345@PURE_QUANTA.SCONN288_ADR50001P013C01(CHIPS)':
 C_PATH='@t6g_mb_lib.t6g(sch_1):page122_i345@pure_quanta.sconn288_adr50001p013c0~
1(chips)';

SECTION_NUMBER 2
 '@T6G_MB_LIB.T6G(SCH_1):PAGE122_I346@PURE_QUANTA.SCONN288_ADR50001P013C01(CHIPS)':
 C_PATH='@t6g_mb_lib.t6g(sch_1):page122_i346@pure_quanta.sconn288_adr50001p013c0~
1(chips)';

SECTION_NUMBER 3
 '@T6G_MB_LIB.T6G(SCH_1):PAGE122_I347@PURE_QUANTA.SCONN288_ADR50001P013C01(CHIPS)':
 C_PATH='@t6g_mb_lib.t6g(sch_1):page122_i347@pure_quanta.sconn288_adr50001p013c0~
1(chips)';

PART_NAME
 C64 'Q_CAP_C0805-10UF,16V,10%,X7R,CH6103K1A00':
;

SECTION_NUMBER 1
 '@T6G_MB_LIB.T6G(SCH_1):PAGE122_I338@PURE_QUANTA.Q_CAP(CHIPS)':
 C_PATH='@t6g_mb_lib.t6g(sch_1):page122_i338@pure_quanta.q_cap(chips)';

PART_NAME
 C63 'Q_CAP_C0805-10UF,16V,10%,X7R,CH6103K1A00':
;

SECTION_NUMBER 1
 '@T6G_MB_LIB.T6G(SCH_1):PAGE122_I344@PURE_QUANTA.Q_CAP(CHIPS)':
 C_PATH='@t6g_mb_lib.t6g(sch_1):page122_i344@pure_quanta.q_cap(chips)';

PART_NAME
 C62 'Q_CAP_C0402-2.2UF,6.3V,20%,X6S,CH5221MEB00':
;

SECTION_NUMBER 1
 '@T6G_MB_LIB.T6G(SCH_1):PAGE122_I341@PURE_QUANTA.Q_CAP(CHIPS)':
 C_PATH='@t6g_mb_lib.t6g(sch_1):page122_i341@pure_quanta.q_cap(chips)';

PART_NAME
 R45 'Q_RES_0402LF-35.7K,1%,1/16W,CHIP,CS33572FB01':;

SECTION_NUMBER 1
 '@T6G_MB_LIB.T6G(SCH_1):PAGE121_I348@PURE_QUANTA.Q_RES(CHIPS)':
 C_PATH='@t6g_mb_lib.t6g(sch_1):page121_i348@pure_quanta.q_res(chips)';

PART_NAME
 J20 'SCONN288_ADR50001P003C01-SCONN288_ADR50001-P003C01,SMLF,IO,DFHST8FS301':;

SECTION_NUMBER 1
 '@T6G_MB_LIB.T6G(SCH_1):PAGE121_I345@PURE_QUANTA.SCONN288_ADR50001P003C01(CHIPS)':
 C_PATH='@t6g_mb_lib.t6g(sch_1):page121_i345@pure_quanta.sconn288_adr50001p003c0~
1(chips)';

SECTION_NUMBER 2
 '@T6G_MB_LIB.T6G(SCH_1):PAGE121_I346@PURE_QUANTA.SCONN288_ADR50001P003C01(CHIPS)':
 C_PATH='@t6g_mb_lib.t6g(sch_1):page121_i346@pure_quanta.sconn288_adr50001p003c0~
1(chips)';

SECTION_NUMBER 3
 '@T6G_MB_LIB.T6G(SCH_1):PAGE121_I347@PURE_QUANTA.SCONN288_ADR50001P003C01(CHIPS)':
 C_PATH='@t6g_mb_lib.t6g(sch_1):page121_i347@pure_quanta.sconn288_adr50001p003c0~
1(chips)';

PART_NAME
 C61 'Q_CAP_C0805-10UF,16V,10%,X7R,CH6103K1A00':
;

SECTION_NUMBER 1
 '@T6G_MB_LIB.T6G(SCH_1):PAGE121_I338@PURE_QUANTA.Q_CAP(CHIPS)':
 C_PATH='@t6g_mb_lib.t6g(sch_1):page121_i338@pure_quanta.q_cap(chips)';

PART_NAME
 C60 'Q_CAP_C0805-10UF,16V,10%,X7R,CH6103K1A00':
;

SECTION_NUMBER 1
 '@T6G_MB_LIB.T6G(SCH_1):PAGE121_I344@PURE_QUANTA.Q_CAP(CHIPS)':
 C_PATH='@t6g_mb_lib.t6g(sch_1):page121_i344@pure_quanta.q_cap(chips)';

PART_NAME
 C59 'Q_CAP_C0402-2.2UF,6.3V,20%,X6S,CH5221MEB00':
;

SECTION_NUMBER 1
 '@T6G_MB_LIB.T6G(SCH_1):PAGE121_I341@PURE_QUANTA.Q_CAP(CHIPS)':
 C_PATH='@t6g_mb_lib.t6g(sch_1):page121_i341@pure_quanta.q_cap(chips)';

PART_NAME
 R44 'Q_RES_0402LF-23.2K,1%,1/16W,CHIP,TMP_QCS32322FB11':;

SECTION_NUMBER 1
 '@T6G_MB_LIB.T6G(SCH_1):PAGE120_I348@PURE_QUANTA.Q_RES(CHIPS)':
 C_PATH='@t6g_mb_lib.t6g(sch_1):page120_i348@pure_quanta.q_res(chips)';

PART_NAME
 J19 'SCONN288_ADR50001P013C01-SCONN288_ADR50001-P013C01,SMLF,IO,DFHST8FS302':;

SECTION_NUMBER 1
 '@T6G_MB_LIB.T6G(SCH_1):PAGE120_I345@PURE_QUANTA.SCONN288_ADR50001P013C01(CHIPS)':
 C_PATH='@t6g_mb_lib.t6g(sch_1):page120_i345@pure_quanta.sconn288_adr50001p013c0~
1(chips)';

SECTION_NUMBER 2
 '@T6G_MB_LIB.T6G(SCH_1):PAGE120_I346@PURE_QUANTA.SCONN288_ADR50001P013C01(CHIPS)':
 C_PATH='@t6g_mb_lib.t6g(sch_1):page120_i346@pure_quanta.sconn288_adr50001p013c0~
1(chips)';

SECTION_NUMBER 3
 '@T6G_MB_LIB.T6G(SCH_1):PAGE120_I347@PURE_QUANTA.SCONN288_ADR50001P013C01(CHIPS)':
 C_PATH='@t6g_mb_lib.t6g(sch_1):page120_i347@pure_quanta.sconn288_adr50001p013c0~
1(chips)';

PART_NAME
 C58 'Q_CAP_C0805-10UF,16V,10%,X7R,CH6103K1A00':
;

SECTION_NUMBER 1
 '@T6G_MB_LIB.T6G(SCH_1):PAGE120_I338@PURE_QUANTA.Q_CAP(CHIPS)':
 C_PATH='@t6g_mb_lib.t6g(sch_1):page120_i338@pure_quanta.q_cap(chips)';

PART_NAME
 C57 'Q_CAP_C0805-10UF,16V,10%,X7R,CH6103K1A00':
;

SECTION_NUMBER 1
 '@T6G_MB_LIB.T6G(SCH_1):PAGE120_I344@PURE_QUANTA.Q_CAP(CHIPS)':
 C_PATH='@t6g_mb_lib.t6g(sch_1):page120_i344@pure_quanta.q_cap(chips)';

PART_NAME
 C56 'Q_CAP_C0402-2.2UF,6.3V,20%,X6S,CH5221MEB00':
;

SECTION_NUMBER 1
 '@T6G_MB_LIB.T6G(SCH_1):PAGE120_I341@PURE_QUANTA.Q_CAP(CHIPS)':
 C_PATH='@t6g_mb_lib.t6g(sch_1):page120_i341@pure_quanta.q_cap(chips)';

PART_NAME
 R43 'Q_RES_0402LF-15.4K,1%,1/16W,CHIP,CS31542FB14':;

SECTION_NUMBER 1
 '@T6G_MB_LIB.T6G(SCH_1):PAGE119_I361@PURE_QUANTA.Q_RES(CHIPS)':
 C_PATH='@t6g_mb_lib.t6g(sch_1):page119_i361@pure_quanta.q_res(chips)';

PART_NAME
 J18 'SCONN288_ADR50001P003C01-SCONN288_ADR50001-P003C01,SMLF,IO,DFHST8FS301':;

SECTION_NUMBER 1
 '@T6G_MB_LIB.T6G(SCH_1):PAGE119_I358@PURE_QUANTA.SCONN288_ADR50001P003C01(CHIPS)':
 C_PATH='@t6g_mb_lib.t6g(sch_1):page119_i358@pure_quanta.sconn288_adr50001p003c0~
1(chips)';

SECTION_NUMBER 2
 '@T6G_MB_LIB.T6G(SCH_1):PAGE119_I359@PURE_QUANTA.SCONN288_ADR50001P003C01(CHIPS)':
 C_PATH='@t6g_mb_lib.t6g(sch_1):page119_i359@pure_quanta.sconn288_adr50001p003c0~
1(chips)';

SECTION_NUMBER 3
 '@T6G_MB_LIB.T6G(SCH_1):PAGE119_I360@PURE_QUANTA.SCONN288_ADR50001P003C01(CHIPS)':
 C_PATH='@t6g_mb_lib.t6g(sch_1):page119_i360@pure_quanta.sconn288_adr50001p003c0~
1(chips)';

PART_NAME
 C55 'Q_CAP_C0805-10UF,16V,10%,X7R,CH6103K1A00':
;

SECTION_NUMBER 1
 '@T6G_MB_LIB.T6G(SCH_1):PAGE119_I351@PURE_QUANTA.Q_CAP(CHIPS)':
 C_PATH='@t6g_mb_lib.t6g(sch_1):page119_i351@pure_quanta.q_cap(chips)';

PART_NAME
 C54 'Q_CAP_C0805-10UF,16V,10%,X7R,CH6103K1A00':
;

SECTION_NUMBER 1
 '@T6G_MB_LIB.T6G(SCH_1):PAGE119_I357@PURE_QUANTA.Q_CAP(CHIPS)':
 C_PATH='@t6g_mb_lib.t6g(sch_1):page119_i357@pure_quanta.q_cap(chips)';

PART_NAME
 C53 'Q_CAP_C0402-2.2UF,6.3V,20%,X6S,CH5221MEB00':
;

SECTION_NUMBER 1
 '@T6G_MB_LIB.T6G(SCH_1):PAGE119_I354@PURE_QUANTA.Q_CAP(CHIPS)':
 C_PATH='@t6g_mb_lib.t6g(sch_1):page119_i354@pure_quanta.q_cap(chips)';

PART_NAME
 R42 'Q_RES_0402LF-10K,1%,1/16W,CHIP,CS31002FB08':
;

SECTION_NUMBER 1
 '@T6G_MB_LIB.T6G(SCH_1):PAGE118_I499@PURE_QUANTA.Q_RES(CHIPS)':
 C_PATH='@t6g_mb_lib.t6g(sch_1):page118_i499@pure_quanta.q_res(chips)';

PART_NAME
 J17 'SCONN288_ADR50001P013C01-SCONN288_ADR50001-P013C01,SMLF,IO,DFHST8FS302':;

SECTION_NUMBER 1
 '@T6G_MB_LIB.T6G(SCH_1):PAGE118_I511@PURE_QUANTA.SCONN288_ADR50001P013C01(CHIPS)':
 C_PATH='@t6g_mb_lib.t6g(sch_1):page118_i511@pure_quanta.sconn288_adr50001p013c0~
1(chips)';

SECTION_NUMBER 2
 '@T6G_MB_LIB.T6G(SCH_1):PAGE118_I512@PURE_QUANTA.SCONN288_ADR50001P013C01(CHIPS)':
 C_PATH='@t6g_mb_lib.t6g(sch_1):page118_i512@pure_quanta.sconn288_adr50001p013c0~
1(chips)';

SECTION_NUMBER 3
 '@T6G_MB_LIB.T6G(SCH_1):PAGE118_I513@PURE_QUANTA.SCONN288_ADR50001P013C01(CHIPS)':
 C_PATH='@t6g_mb_lib.t6g(sch_1):page118_i513@pure_quanta.sconn288_adr50001p013c0~
1(chips)';

PART_NAME
 C52 'Q_CAP_C0805-10UF,16V,10%,X7R,CH6103K1A00':
;

SECTION_NUMBER 1
 '@T6G_MB_LIB.T6G(SCH_1):PAGE118_I504@PURE_QUANTA.Q_CAP(CHIPS)':
 C_PATH='@t6g_mb_lib.t6g(sch_1):page118_i504@pure_quanta.q_cap(chips)';

PART_NAME
 C51 'Q_CAP_C0805-10UF,16V,10%,X7R,CH6103K1A00':
;

SECTION_NUMBER 1
 '@T6G_MB_LIB.T6G(SCH_1):PAGE118_I510@PURE_QUANTA.Q_CAP(CHIPS)':
 C_PATH='@t6g_mb_lib.t6g(sch_1):page118_i510@pure_quanta.q_cap(chips)';

PART_NAME
 C50 'Q_CAP_C0402-2.2UF,6.3V,20%,X6S,CH5221MEB00':
;

SECTION_NUMBER 1
 '@T6G_MB_LIB.T6G(SCH_1):PAGE118_I506@PURE_QUANTA.Q_CAP(CHIPS)':
 C_PATH='@t6g_mb_lib.t6g(sch_1):page118_i506@pure_quanta.q_cap(chips)';

PART_NAME
 R41 'Q_RES_0402LF-196K,1%,1/16W,CHIP,CS41962FB01':;

SECTION_NUMBER 1
 '@T6G_MB_LIB.T6G(SCH_1):PAGE117_I348@PURE_QUANTA.Q_RES(CHIPS)':
 C_PATH='@t6g_mb_lib.t6g(sch_1):page117_i348@pure_quanta.q_res(chips)';

PART_NAME
 J16 'SCONN288_ADR50001P003C01-SCONN288_ADR50001-P003C01,SMLF,IO,DFHST8FS301':;

SECTION_NUMBER 1
 '@T6G_MB_LIB.T6G(SCH_1):PAGE117_I345@PURE_QUANTA.SCONN288_ADR50001P003C01(CHIPS)':
 C_PATH='@t6g_mb_lib.t6g(sch_1):page117_i345@pure_quanta.sconn288_adr50001p003c0~
1(chips)';

SECTION_NUMBER 2
 '@T6G_MB_LIB.T6G(SCH_1):PAGE117_I346@PURE_QUANTA.SCONN288_ADR50001P003C01(CHIPS)':
 C_PATH='@t6g_mb_lib.t6g(sch_1):page117_i346@pure_quanta.sconn288_adr50001p003c0~
1(chips)';

SECTION_NUMBER 3
 '@T6G_MB_LIB.T6G(SCH_1):PAGE117_I347@PURE_QUANTA.SCONN288_ADR50001P003C01(CHIPS)':
 C_PATH='@t6g_mb_lib.t6g(sch_1):page117_i347@pure_quanta.sconn288_adr50001p003c0~
1(chips)';

PART_NAME
 C49 'Q_CAP_C0805-10UF,16V,10%,X7R,CH6103K1A00':
;

SECTION_NUMBER 1
 '@T6G_MB_LIB.T6G(SCH_1):PAGE117_I339@PURE_QUANTA.Q_CAP(CHIPS)':
 C_PATH='@t6g_mb_lib.t6g(sch_1):page117_i339@pure_quanta.q_cap(chips)';

PART_NAME
 C48 'Q_CAP_C0805-10UF,16V,10%,X7R,CH6103K1A00':
;

SECTION_NUMBER 1
 '@T6G_MB_LIB.T6G(SCH_1):PAGE117_I344@PURE_QUANTA.Q_CAP(CHIPS)':
 C_PATH='@t6g_mb_lib.t6g(sch_1):page117_i344@pure_quanta.q_cap(chips)';

PART_NAME
 C47 'Q_CAP_C0402-2.2UF,6.3V,20%,X6S,CH5221MEB00':
;

SECTION_NUMBER 1
 '@T6G_MB_LIB.T6G(SCH_1):PAGE117_I341@PURE_QUANTA.Q_CAP(CHIPS)':
 C_PATH='@t6g_mb_lib.t6g(sch_1):page117_i341@pure_quanta.q_cap(chips)';

PART_NAME
 R40 'Q_RES_0402LF-127K,1%,1/16W,CHIP,CS41272FB19':;

SECTION_NUMBER 1
 '@T6G_MB_LIB.T6G(SCH_1):PAGE116_I348@PURE_QUANTA.Q_RES(CHIPS)':
 C_PATH='@t6g_mb_lib.t6g(sch_1):page116_i348@pure_quanta.q_res(chips)';

PART_NAME
 J15 'SCONN288_ADR50001P013C01-SCONN288_ADR50001-P013C01,SMLF,IO,DFHST8FS302':;

SECTION_NUMBER 1
 '@T6G_MB_LIB.T6G(SCH_1):PAGE116_I345@PURE_QUANTA.SCONN288_ADR50001P013C01(CHIPS)':
 C_PATH='@t6g_mb_lib.t6g(sch_1):page116_i345@pure_quanta.sconn288_adr50001p013c0~
1(chips)';

SECTION_NUMBER 2
 '@T6G_MB_LIB.T6G(SCH_1):PAGE116_I346@PURE_QUANTA.SCONN288_ADR50001P013C01(CHIPS)':
 C_PATH='@t6g_mb_lib.t6g(sch_1):page116_i346@pure_quanta.sconn288_adr50001p013c0~
1(chips)';

SECTION_NUMBER 3
 '@T6G_MB_LIB.T6G(SCH_1):PAGE116_I347@PURE_QUANTA.SCONN288_ADR50001P013C01(CHIPS)':
 C_PATH='@t6g_mb_lib.t6g(sch_1):page116_i347@pure_quanta.sconn288_adr50001p013c0~
1(chips)';

PART_NAME
 C46 'Q_CAP_C0805-10UF,16V,10%,X7R,CH6103K1A00':
;

SECTION_NUMBER 1
 '@T6G_MB_LIB.T6G(SCH_1):PAGE116_I338@PURE_QUANTA.Q_CAP(CHIPS)':
 C_PATH='@t6g_mb_lib.t6g(sch_1):page116_i338@pure_quanta.q_cap(chips)';

PART_NAME
 C45 'Q_CAP_C0805-10UF,16V,10%,X7R,CH6103K1A00':
;

SECTION_NUMBER 1
 '@T6G_MB_LIB.T6G(SCH_1):PAGE116_I344@PURE_QUANTA.Q_CAP(CHIPS)':
 C_PATH='@t6g_mb_lib.t6g(sch_1):page116_i344@pure_quanta.q_cap(chips)';

PART_NAME
 C44 'Q_CAP_C0402-2.2UF,6.3V,20%,X6S,CH5221MEB00':
;

SECTION_NUMBER 1
 '@T6G_MB_LIB.T6G(SCH_1):PAGE116_I341@PURE_QUANTA.Q_CAP(CHIPS)':
 C_PATH='@t6g_mb_lib.t6g(sch_1):page116_i341@pure_quanta.q_cap(chips)';

PART_NAME
 R39 'Q_RES_0402LF-84.5K,1%,1/16W,CHIP,CS38452FB14':;

SECTION_NUMBER 1
 '@T6G_MB_LIB.T6G(SCH_1):PAGE115_I348@PURE_QUANTA.Q_RES(CHIPS)':
 C_PATH='@t6g_mb_lib.t6g(sch_1):page115_i348@pure_quanta.q_res(chips)';

PART_NAME
 J14 'SCONN288_ADR50001P003C01-SCONN288_ADR50001-P003C01,SMLF,IO,DFHST8FS301':;

SECTION_NUMBER 1
 '@T6G_MB_LIB.T6G(SCH_1):PAGE115_I345@PURE_QUANTA.SCONN288_ADR50001P003C01(CHIPS)':
 C_PATH='@t6g_mb_lib.t6g(sch_1):page115_i345@pure_quanta.sconn288_adr50001p003c0~
1(chips)';

SECTION_NUMBER 2
 '@T6G_MB_LIB.T6G(SCH_1):PAGE115_I346@PURE_QUANTA.SCONN288_ADR50001P003C01(CHIPS)':
 C_PATH='@t6g_mb_lib.t6g(sch_1):page115_i346@pure_quanta.sconn288_adr50001p003c0~
1(chips)';

SECTION_NUMBER 3
 '@T6G_MB_LIB.T6G(SCH_1):PAGE115_I347@PURE_QUANTA.SCONN288_ADR50001P003C01(CHIPS)':
 C_PATH='@t6g_mb_lib.t6g(sch_1):page115_i347@pure_quanta.sconn288_adr50001p003c0~
1(chips)';

PART_NAME
 C43 'Q_CAP_C0805-10UF,16V,10%,X7R,CH6103K1A00':
;

SECTION_NUMBER 1
 '@T6G_MB_LIB.T6G(SCH_1):PAGE115_I338@PURE_QUANTA.Q_CAP(CHIPS)':
 C_PATH='@t6g_mb_lib.t6g(sch_1):page115_i338@pure_quanta.q_cap(chips)';

PART_NAME
 C42 'Q_CAP_C0805-10UF,16V,10%,X7R,CH6103K1A00':
;

SECTION_NUMBER 1
 '@T6G_MB_LIB.T6G(SCH_1):PAGE115_I344@PURE_QUANTA.Q_CAP(CHIPS)':
 C_PATH='@t6g_mb_lib.t6g(sch_1):page115_i344@pure_quanta.q_cap(chips)';

PART_NAME
 C41 'Q_CAP_C0402-2.2UF,6.3V,20%,X6S,CH5221MEB00':
;

SECTION_NUMBER 1
 '@T6G_MB_LIB.T6G(SCH_1):PAGE115_I341@PURE_QUANTA.Q_CAP(CHIPS)':
 C_PATH='@t6g_mb_lib.t6g(sch_1):page115_i341@pure_quanta.q_cap(chips)';

PART_NAME
 R38 'Q_RES_0402LF-54.9K,1%,1/16W,CHIP,TMP_QCS35492FB14':;

SECTION_NUMBER 1
 '@T6G_MB_LIB.T6G(SCH_1):PAGE114_I348@PURE_QUANTA.Q_RES(CHIPS)':
 C_PATH='@t6g_mb_lib.t6g(sch_1):page114_i348@pure_quanta.q_res(chips)';

PART_NAME
 J13 'SCONN288_ADR50001P013C01-SCONN288_ADR50001-P013C01,SMLF,IO,DFHST8FS302':;

SECTION_NUMBER 1
 '@T6G_MB_LIB.T6G(SCH_1):PAGE114_I345@PURE_QUANTA.SCONN288_ADR50001P013C01(CHIPS)':
 C_PATH='@t6g_mb_lib.t6g(sch_1):page114_i345@pure_quanta.sconn288_adr50001p013c0~
1(chips)';

SECTION_NUMBER 2
 '@T6G_MB_LIB.T6G(SCH_1):PAGE114_I346@PURE_QUANTA.SCONN288_ADR50001P013C01(CHIPS)':
 C_PATH='@t6g_mb_lib.t6g(sch_1):page114_i346@pure_quanta.sconn288_adr50001p013c0~
1(chips)';

SECTION_NUMBER 3
 '@T6G_MB_LIB.T6G(SCH_1):PAGE114_I347@PURE_QUANTA.SCONN288_ADR50001P013C01(CHIPS)':
 C_PATH='@t6g_mb_lib.t6g(sch_1):page114_i347@pure_quanta.sconn288_adr50001p013c0~
1(chips)';

PART_NAME
 C40 'Q_CAP_C0805-10UF,16V,10%,X7R,CH6103K1A00':
;

SECTION_NUMBER 1
 '@T6G_MB_LIB.T6G(SCH_1):PAGE114_I338@PURE_QUANTA.Q_CAP(CHIPS)':
 C_PATH='@t6g_mb_lib.t6g(sch_1):page114_i338@pure_quanta.q_cap(chips)';

PART_NAME
 C39 'Q_CAP_C0805-10UF,16V,10%,X7R,CH6103K1A00':
;

SECTION_NUMBER 1
 '@T6G_MB_LIB.T6G(SCH_1):PAGE114_I344@PURE_QUANTA.Q_CAP(CHIPS)':
 C_PATH='@t6g_mb_lib.t6g(sch_1):page114_i344@pure_quanta.q_cap(chips)';

PART_NAME
 C38 'Q_CAP_C0402-2.2UF,6.3V,20%,X6S,CH5221MEB00':
;

SECTION_NUMBER 1
 '@T6G_MB_LIB.T6G(SCH_1):PAGE114_I341@PURE_QUANTA.Q_CAP(CHIPS)':
 C_PATH='@t6g_mb_lib.t6g(sch_1):page114_i341@pure_quanta.q_cap(chips)';

PART_NAME
 R37 'Q_RES_0402LF-35.7K,1%,1/16W,CHIP,CS33572FB01':;

SECTION_NUMBER 1
 '@T6G_MB_LIB.T6G(SCH_1):PAGE113_I348@PURE_QUANTA.Q_RES(CHIPS)':
 C_PATH='@t6g_mb_lib.t6g(sch_1):page113_i348@pure_quanta.q_res(chips)';

PART_NAME
 J12 'SCONN288_ADR50001P003C01-SCONN288_ADR50001-P003C01,SMLF,IO,DFHST8FS301':;

SECTION_NUMBER 1
 '@T6G_MB_LIB.T6G(SCH_1):PAGE113_I345@PURE_QUANTA.SCONN288_ADR50001P003C01(CHIPS)':
 C_PATH='@t6g_mb_lib.t6g(sch_1):page113_i345@pure_quanta.sconn288_adr50001p003c0~
1(chips)';

SECTION_NUMBER 2
 '@T6G_MB_LIB.T6G(SCH_1):PAGE113_I346@PURE_QUANTA.SCONN288_ADR50001P003C01(CHIPS)':
 C_PATH='@t6g_mb_lib.t6g(sch_1):page113_i346@pure_quanta.sconn288_adr50001p003c0~
1(chips)';

SECTION_NUMBER 3
 '@T6G_MB_LIB.T6G(SCH_1):PAGE113_I347@PURE_QUANTA.SCONN288_ADR50001P003C01(CHIPS)':
 C_PATH='@t6g_mb_lib.t6g(sch_1):page113_i347@pure_quanta.sconn288_adr50001p003c0~
1(chips)';

PART_NAME
 C37 'Q_CAP_C0805-10UF,16V,10%,X7R,CH6103K1A00':
;

SECTION_NUMBER 1
 '@T6G_MB_LIB.T6G(SCH_1):PAGE113_I338@PURE_QUANTA.Q_CAP(CHIPS)':
 C_PATH='@t6g_mb_lib.t6g(sch_1):page113_i338@pure_quanta.q_cap(chips)';

PART_NAME
 C36 'Q_CAP_C0805-10UF,16V,10%,X7R,CH6103K1A00':
;

SECTION_NUMBER 1
 '@T6G_MB_LIB.T6G(SCH_1):PAGE113_I344@PURE_QUANTA.Q_CAP(CHIPS)':
 C_PATH='@t6g_mb_lib.t6g(sch_1):page113_i344@pure_quanta.q_cap(chips)';

PART_NAME
 C35 'Q_CAP_C0402-2.2UF,6.3V,20%,X6S,CH5221MEB00':
;

SECTION_NUMBER 1
 '@T6G_MB_LIB.T6G(SCH_1):PAGE113_I341@PURE_QUANTA.Q_CAP(CHIPS)':
 C_PATH='@t6g_mb_lib.t6g(sch_1):page113_i341@pure_quanta.q_cap(chips)';

PART_NAME
 R36 'Q_RES_0402LF-23.2K,1%,1/16W,CHIP,TMP_QCS32322FB11':;

SECTION_NUMBER 1
 '@T6G_MB_LIB.T6G(SCH_1):PAGE112_I349@PURE_QUANTA.Q_RES(CHIPS)':
 C_PATH='@t6g_mb_lib.t6g(sch_1):page112_i349@pure_quanta.q_res(chips)';

PART_NAME
 J11 'SCONN288_ADR50001P013C01-SCONN288_ADR50001-P013C01,SMLF,IO,DFHST8FS302':;

SECTION_NUMBER 1
 '@T6G_MB_LIB.T6G(SCH_1):PAGE112_I345@PURE_QUANTA.SCONN288_ADR50001P013C01(CHIPS)':
 C_PATH='@t6g_mb_lib.t6g(sch_1):page112_i345@pure_quanta.sconn288_adr50001p013c0~
1(chips)';

SECTION_NUMBER 2
 '@T6G_MB_LIB.T6G(SCH_1):PAGE112_I346@PURE_QUANTA.SCONN288_ADR50001P013C01(CHIPS)':
 C_PATH='@t6g_mb_lib.t6g(sch_1):page112_i346@pure_quanta.sconn288_adr50001p013c0~
1(chips)';

SECTION_NUMBER 3
 '@T6G_MB_LIB.T6G(SCH_1):PAGE112_I347@PURE_QUANTA.SCONN288_ADR50001P013C01(CHIPS)':
 C_PATH='@t6g_mb_lib.t6g(sch_1):page112_i347@pure_quanta.sconn288_adr50001p013c0~
1(chips)';

PART_NAME
 C34 'Q_CAP_C0805-10UF,16V,10%,X7R,CH6103K1A00':
;

SECTION_NUMBER 1
 '@T6G_MB_LIB.T6G(SCH_1):PAGE112_I338@PURE_QUANTA.Q_CAP(CHIPS)':
 C_PATH='@t6g_mb_lib.t6g(sch_1):page112_i338@pure_quanta.q_cap(chips)';

PART_NAME
 C33 'Q_CAP_C0805-10UF,16V,10%,X7R,CH6103K1A00':
;

SECTION_NUMBER 1
 '@T6G_MB_LIB.T6G(SCH_1):PAGE112_I344@PURE_QUANTA.Q_CAP(CHIPS)':
 C_PATH='@t6g_mb_lib.t6g(sch_1):page112_i344@pure_quanta.q_cap(chips)';

PART_NAME
 C32 'Q_CAP_C0402-2.2UF,6.3V,20%,X6S,CH5221MEB00':
;

SECTION_NUMBER 1
 '@T6G_MB_LIB.T6G(SCH_1):PAGE112_I341@PURE_QUANTA.Q_CAP(CHIPS)':
 C_PATH='@t6g_mb_lib.t6g(sch_1):page112_i341@pure_quanta.q_cap(chips)';

PART_NAME
 R35 'Q_RES_0402LF-15.4K,1%,1/16W,CHIP,CS31542FB14':;

SECTION_NUMBER 1
 '@T6G_MB_LIB.T6G(SCH_1):PAGE111_I349@PURE_QUANTA.Q_RES(CHIPS)':
 C_PATH='@t6g_mb_lib.t6g(sch_1):page111_i349@pure_quanta.q_res(chips)';

PART_NAME
 J10 'SCONN288_ADR50001P003C01-SCONN288_ADR50001-P003C01,SMLF,IO,DFHST8FS301':;

SECTION_NUMBER 1
 '@T6G_MB_LIB.T6G(SCH_1):PAGE111_I345@PURE_QUANTA.SCONN288_ADR50001P003C01(CHIPS)':
 C_PATH='@t6g_mb_lib.t6g(sch_1):page111_i345@pure_quanta.sconn288_adr50001p003c0~
1(chips)';

SECTION_NUMBER 2
 '@T6G_MB_LIB.T6G(SCH_1):PAGE111_I346@PURE_QUANTA.SCONN288_ADR50001P003C01(CHIPS)':
 C_PATH='@t6g_mb_lib.t6g(sch_1):page111_i346@pure_quanta.sconn288_adr50001p003c0~
1(chips)';

SECTION_NUMBER 3
 '@T6G_MB_LIB.T6G(SCH_1):PAGE111_I347@PURE_QUANTA.SCONN288_ADR50001P003C01(CHIPS)':
 C_PATH='@t6g_mb_lib.t6g(sch_1):page111_i347@pure_quanta.sconn288_adr50001p003c0~
1(chips)';

PART_NAME
 C31 'Q_CAP_C0805-10UF,16V,10%,X7R,CH6103K1A00':
;

SECTION_NUMBER 1
 '@T6G_MB_LIB.T6G(SCH_1):PAGE111_I338@PURE_QUANTA.Q_CAP(CHIPS)':
 C_PATH='@t6g_mb_lib.t6g(sch_1):page111_i338@pure_quanta.q_cap(chips)';

PART_NAME
 C30 'Q_CAP_C0805-10UF,16V,10%,X7R,CH6103K1A00':
;

SECTION_NUMBER 1
 '@T6G_MB_LIB.T6G(SCH_1):PAGE111_I344@PURE_QUANTA.Q_CAP(CHIPS)':
 C_PATH='@t6g_mb_lib.t6g(sch_1):page111_i344@pure_quanta.q_cap(chips)';

PART_NAME
 C29 'Q_CAP_C0402-2.2UF,6.3V,20%,X6S,CH5221MEB00':
;

SECTION_NUMBER 1
 '@T6G_MB_LIB.T6G(SCH_1):PAGE111_I341@PURE_QUANTA.Q_CAP(CHIPS)':
 C_PATH='@t6g_mb_lib.t6g(sch_1):page111_i341@pure_quanta.q_cap(chips)';

PART_NAME
 R34 'Q_RES_0402LF-10K,1%,1/16W,CHIP,CS31002FB08':;

SECTION_NUMBER 1
 '@T6G_MB_LIB.T6G(SCH_1):PAGE110_I331@PURE_QUANTA.Q_RES(CHIPS)':
 C_PATH='@t6g_mb_lib.t6g(sch_1):page110_i331@pure_quanta.q_res(chips)';

PART_NAME
 J9 'SCONN288_ADR50001P013C01-SCONN288_ADR50001-P013C01,SMLF,IO,DFHST8FS302':;

SECTION_NUMBER 1
 '@T6G_MB_LIB.T6G(SCH_1):PAGE110_I344@PURE_QUANTA.SCONN288_ADR50001P013C01(CHIPS)':
 C_PATH='@t6g_mb_lib.t6g(sch_1):page110_i344@pure_quanta.sconn288_adr50001p013c0~
1(chips)';

SECTION_NUMBER 2
 '@T6G_MB_LIB.T6G(SCH_1):PAGE110_I345@PURE_QUANTA.SCONN288_ADR50001P013C01(CHIPS)':
 C_PATH='@t6g_mb_lib.t6g(sch_1):page110_i345@pure_quanta.sconn288_adr50001p013c0~
1(chips)';

SECTION_NUMBER 3
 '@T6G_MB_LIB.T6G(SCH_1):PAGE110_I346@PURE_QUANTA.SCONN288_ADR50001P013C01(CHIPS)':
 C_PATH='@t6g_mb_lib.t6g(sch_1):page110_i346@pure_quanta.sconn288_adr50001p013c0~
1(chips)';

PART_NAME
 C28 'Q_CAP_C0805-10UF,16V,10%,X7R,CH6103K1A00':
;

SECTION_NUMBER 1
 '@T6G_MB_LIB.T6G(SCH_1):PAGE110_I336@PURE_QUANTA.Q_CAP(CHIPS)':
 C_PATH='@t6g_mb_lib.t6g(sch_1):page110_i336@pure_quanta.q_cap(chips)';

PART_NAME
 C27 'Q_CAP_C0805-10UF,16V,10%,X7R,CH6103K1A00':
;

SECTION_NUMBER 1
 '@T6G_MB_LIB.T6G(SCH_1):PAGE110_I343@PURE_QUANTA.Q_CAP(CHIPS)':
 C_PATH='@t6g_mb_lib.t6g(sch_1):page110_i343@pure_quanta.q_cap(chips)';

PART_NAME
 C26 'Q_CAP_C0402-2.2UF,6.3V,20%,X6S,CH5221MEB00':
;

SECTION_NUMBER 1
 '@T6G_MB_LIB.T6G(SCH_1):PAGE110_I338@PURE_QUANTA.Q_CAP(CHIPS)':
 C_PATH='@t6g_mb_lib.t6g(sch_1):page110_i338@pure_quanta.q_cap(chips)';

PART_NAME
 R33 'Q_RES_0402LF-196K,1%,1/16W,CHIP,CS41962FB01':;

SECTION_NUMBER 1
 '@T6G_MB_LIB.T6G(SCH_1):PAGE109_I350@PURE_QUANTA.Q_RES(CHIPS)':
 C_PATH='@t6g_mb_lib.t6g(sch_1):page109_i350@pure_quanta.q_res(chips)';

PART_NAME
 J8 'SCONN288_ADR50001P003C01-SCONN288_ADR50001-P003C01,SMLF,IO,DFHST8FS301':;

SECTION_NUMBER 1
 '@T6G_MB_LIB.T6G(SCH_1):PAGE109_I346@PURE_QUANTA.SCONN288_ADR50001P003C01(CHIPS)':
 C_PATH='@t6g_mb_lib.t6g(sch_1):page109_i346@pure_quanta.sconn288_adr50001p003c0~
1(chips)';

SECTION_NUMBER 2
 '@T6G_MB_LIB.T6G(SCH_1):PAGE109_I347@PURE_QUANTA.SCONN288_ADR50001P003C01(CHIPS)':
 C_PATH='@t6g_mb_lib.t6g(sch_1):page109_i347@pure_quanta.sconn288_adr50001p003c0~
1(chips)';

SECTION_NUMBER 3
 '@T6G_MB_LIB.T6G(SCH_1):PAGE109_I348@PURE_QUANTA.SCONN288_ADR50001P003C01(CHIPS)':
 C_PATH='@t6g_mb_lib.t6g(sch_1):page109_i348@pure_quanta.sconn288_adr50001p003c0~
1(chips)';

PART_NAME
 C25 'Q_CAP_C0805-10UF,16V,10%,X7R,CH6103K1A00':
;

SECTION_NUMBER 1
 '@T6G_MB_LIB.T6G(SCH_1):PAGE109_I339@PURE_QUANTA.Q_CAP(CHIPS)':
 C_PATH='@t6g_mb_lib.t6g(sch_1):page109_i339@pure_quanta.q_cap(chips)';

PART_NAME
 C24 'Q_CAP_C0805-10UF,16V,10%,X7R,CH6103K1A00':
;

SECTION_NUMBER 1
 '@T6G_MB_LIB.T6G(SCH_1):PAGE109_I345@PURE_QUANTA.Q_CAP(CHIPS)':
 C_PATH='@t6g_mb_lib.t6g(sch_1):page109_i345@pure_quanta.q_cap(chips)';

PART_NAME
 C23 'Q_CAP_C0402-2.2UF,6.3V,20%,X6S,CH5221MEB00':
;

SECTION_NUMBER 1
 '@T6G_MB_LIB.T6G(SCH_1):PAGE109_I341@PURE_QUANTA.Q_CAP(CHIPS)':
 C_PATH='@t6g_mb_lib.t6g(sch_1):page109_i341@pure_quanta.q_cap(chips)';

PART_NAME
 R32 'Q_RES_0402LF-127K,1%,1/16W,CHIP,CS41272FB19':;

SECTION_NUMBER 1
 '@T6G_MB_LIB.T6G(SCH_1):PAGE108_I349@PURE_QUANTA.Q_RES(CHIPS)':
 C_PATH='@t6g_mb_lib.t6g(sch_1):page108_i349@pure_quanta.q_res(chips)';

PART_NAME
 J7 'SCONN288_ADR50001P013C01-SCONN288_ADR50001-P013C01,SMLF,IO,DFHST8FS302':;

SECTION_NUMBER 1
 '@T6G_MB_LIB.T6G(SCH_1):PAGE108_I345@PURE_QUANTA.SCONN288_ADR50001P013C01(CHIPS)':
 C_PATH='@t6g_mb_lib.t6g(sch_1):page108_i345@pure_quanta.sconn288_adr50001p013c0~
1(chips)';

SECTION_NUMBER 2
 '@T6G_MB_LIB.T6G(SCH_1):PAGE108_I346@PURE_QUANTA.SCONN288_ADR50001P013C01(CHIPS)':
 C_PATH='@t6g_mb_lib.t6g(sch_1):page108_i346@pure_quanta.sconn288_adr50001p013c0~
1(chips)';

SECTION_NUMBER 3
 '@T6G_MB_LIB.T6G(SCH_1):PAGE108_I347@PURE_QUANTA.SCONN288_ADR50001P013C01(CHIPS)':
 C_PATH='@t6g_mb_lib.t6g(sch_1):page108_i347@pure_quanta.sconn288_adr50001p013c0~
1(chips)';

PART_NAME
 C22 'Q_CAP_C0805-10UF,16V,10%,X7R,CH6103K1A00':
;

SECTION_NUMBER 1
 '@T6G_MB_LIB.T6G(SCH_1):PAGE108_I338@PURE_QUANTA.Q_CAP(CHIPS)':
 C_PATH='@t6g_mb_lib.t6g(sch_1):page108_i338@pure_quanta.q_cap(chips)';

PART_NAME
 C21 'Q_CAP_C0805-10UF,16V,10%,X7R,CH6103K1A00':
;

SECTION_NUMBER 1
 '@T6G_MB_LIB.T6G(SCH_1):PAGE108_I344@PURE_QUANTA.Q_CAP(CHIPS)':
 C_PATH='@t6g_mb_lib.t6g(sch_1):page108_i344@pure_quanta.q_cap(chips)';

PART_NAME
 C20 'Q_CAP_C0402-2.2UF,6.3V,20%,X6S,CH5221MEB00':
;

SECTION_NUMBER 1
 '@T6G_MB_LIB.T6G(SCH_1):PAGE108_I340@PURE_QUANTA.Q_CAP(CHIPS)':
 C_PATH='@t6g_mb_lib.t6g(sch_1):page108_i340@pure_quanta.q_cap(chips)';

PART_NAME
 R31 'Q_RES_0402LF-84.5K,1%,1/16W,CHIP,CS38452FB14':;

SECTION_NUMBER 1
 '@T6G_MB_LIB.T6G(SCH_1):PAGE107_I349@PURE_QUANTA.Q_RES(CHIPS)':
 C_PATH='@t6g_mb_lib.t6g(sch_1):page107_i349@pure_quanta.q_res(chips)';

PART_NAME
 J6 'SCONN288_ADR50001P003C01-SCONN288_ADR50001-P003C01,SMLF,IO,DFHST8FS301':;

SECTION_NUMBER 1
 '@T6G_MB_LIB.T6G(SCH_1):PAGE107_I345@PURE_QUANTA.SCONN288_ADR50001P003C01(CHIPS)':
 C_PATH='@t6g_mb_lib.t6g(sch_1):page107_i345@pure_quanta.sconn288_adr50001p003c0~
1(chips)';

SECTION_NUMBER 2
 '@T6G_MB_LIB.T6G(SCH_1):PAGE107_I346@PURE_QUANTA.SCONN288_ADR50001P003C01(CHIPS)':
 C_PATH='@t6g_mb_lib.t6g(sch_1):page107_i346@pure_quanta.sconn288_adr50001p003c0~
1(chips)';

SECTION_NUMBER 3
 '@T6G_MB_LIB.T6G(SCH_1):PAGE107_I347@PURE_QUANTA.SCONN288_ADR50001P003C01(CHIPS)':
 C_PATH='@t6g_mb_lib.t6g(sch_1):page107_i347@pure_quanta.sconn288_adr50001p003c0~
1(chips)';

PART_NAME
 C19 'Q_CAP_C0805-10UF,16V,10%,X7R,CH6103K1A00':
;

SECTION_NUMBER 1
 '@T6G_MB_LIB.T6G(SCH_1):PAGE107_I338@PURE_QUANTA.Q_CAP(CHIPS)':
 C_PATH='@t6g_mb_lib.t6g(sch_1):page107_i338@pure_quanta.q_cap(chips)';

PART_NAME
 C18 'Q_CAP_C0805-10UF,16V,10%,X7R,CH6103K1A00':
;

SECTION_NUMBER 1
 '@T6G_MB_LIB.T6G(SCH_1):PAGE107_I344@PURE_QUANTA.Q_CAP(CHIPS)':
 C_PATH='@t6g_mb_lib.t6g(sch_1):page107_i344@pure_quanta.q_cap(chips)';

PART_NAME
 C17 'Q_CAP_C0402-2.2UF,6.3V,20%,X6S,CH5221MEB00':
;

SECTION_NUMBER 1
 '@T6G_MB_LIB.T6G(SCH_1):PAGE107_I340@PURE_QUANTA.Q_CAP(CHIPS)':
 C_PATH='@t6g_mb_lib.t6g(sch_1):page107_i340@pure_quanta.q_cap(chips)';

PART_NAME
 R30 'Q_RES_0402LF-54.9K,1%,1/16W,CHIP,TMP_QCS35492FB14':;

SECTION_NUMBER 1
 '@T6G_MB_LIB.T6G(SCH_1):PAGE106_I349@PURE_QUANTA.Q_RES(CHIPS)':
 C_PATH='@t6g_mb_lib.t6g(sch_1):page106_i349@pure_quanta.q_res(chips)';

PART_NAME
 J5 'SCONN288_ADR50001P013C01-SCONN288_ADR50001-P013C01,SMLF,IO,DFHST8FS302':;

SECTION_NUMBER 1
 '@T6G_MB_LIB.T6G(SCH_1):PAGE106_I345@PURE_QUANTA.SCONN288_ADR50001P013C01(CHIPS)':
 C_PATH='@t6g_mb_lib.t6g(sch_1):page106_i345@pure_quanta.sconn288_adr50001p013c0~
1(chips)';

SECTION_NUMBER 2
 '@T6G_MB_LIB.T6G(SCH_1):PAGE106_I346@PURE_QUANTA.SCONN288_ADR50001P013C01(CHIPS)':
 C_PATH='@t6g_mb_lib.t6g(sch_1):page106_i346@pure_quanta.sconn288_adr50001p013c0~
1(chips)';

SECTION_NUMBER 3
 '@T6G_MB_LIB.T6G(SCH_1):PAGE106_I347@PURE_QUANTA.SCONN288_ADR50001P013C01(CHIPS)':
 C_PATH='@t6g_mb_lib.t6g(sch_1):page106_i347@pure_quanta.sconn288_adr50001p013c0~
1(chips)';

PART_NAME
 C16 'Q_CAP_C0805-10UF,16V,10%,X7R,CH6103K1A00':
;

SECTION_NUMBER 1
 '@T6G_MB_LIB.T6G(SCH_1):PAGE106_I338@PURE_QUANTA.Q_CAP(CHIPS)':
 C_PATH='@t6g_mb_lib.t6g(sch_1):page106_i338@pure_quanta.q_cap(chips)';

PART_NAME
 C15 'Q_CAP_C0805-10UF,16V,10%,X7R,CH6103K1A00':
;

SECTION_NUMBER 1
 '@T6G_MB_LIB.T6G(SCH_1):PAGE106_I344@PURE_QUANTA.Q_CAP(CHIPS)':
 C_PATH='@t6g_mb_lib.t6g(sch_1):page106_i344@pure_quanta.q_cap(chips)';

PART_NAME
 C14 'Q_CAP_C0402-2.2UF,6.3V,20%,X6S,CH5221MEB00':
;

SECTION_NUMBER 1
 '@T6G_MB_LIB.T6G(SCH_1):PAGE106_I340@PURE_QUANTA.Q_CAP(CHIPS)':
 C_PATH='@t6g_mb_lib.t6g(sch_1):page106_i340@pure_quanta.q_cap(chips)';

PART_NAME
 U38 'TPS259541DSGR-TPS259541DSGR,SMLF,IC,AL259541000':;

SECTION_NUMBER 1
 '@T6G_MB_LIB.T6G(SCH_1):PAGE150_I50@PURE_QUANTA.TPS259541DSGR(CHIPS)':
 C_PATH='@t6g_mb_lib.t6g(sch_1):page150_i50@pure_quanta.tps259541dsgr(chips)';

PART_NAME
 U24 'TPS259521DSGR-TPS259521DSGR,SMLF,IC,AL259521000':;

SECTION_NUMBER 1
 '@T6G_MB_LIB.T6G(SCH_1):PAGE150_I62@PURE_QUANTA.TPS259521DSGR(CHIPS)':
 C_PATH='@t6g_mb_lib.t6g(sch_1):page150_i62@pure_quanta.tps259521dsgr(chips)';

PART_NAME
 R2655 'Q_RES_0402LF-576,1%,1/16W,CHIP,CS15762FB26':;

SECTION_NUMBER 1
 '@T6G_MB_LIB.T6G(SCH_1):PAGE150_I43@PURE_QUANTA.Q_RES(CHIPS)':
 C_PATH='@t6g_mb_lib.t6g(sch_1):page150_i43@pure_quanta.q_res(chips)';

PART_NAME
 R2654 'Q_RES_0402LF-10K,5%,1/16W,CHIP,TMP_QCS31002JB28':;

SECTION_NUMBER 1
 '@T6G_MB_LIB.T6G(SCH_1):PAGE150_I67@PURE_QUANTA.Q_RES(CHIPS)':
 C_PATH='@t6g_mb_lib.t6g(sch_1):page150_i67@pure_quanta.q_res(chips)';

PART_NAME
 R1137 'Q_RES_0402LF-750,1%,1/16W,CHIP,CS17502FB19':;

SECTION_NUMBER 1
 '@T6G_MB_LIB.T6G(SCH_1):PAGE150_I55@PURE_QUANTA.Q_RES(CHIPS)':
 C_PATH='@t6g_mb_lib.t6g(sch_1):page150_i55@pure_quanta.q_res(chips)';

PART_NAME
 J272 'Q_SHORT_SM-EMPTY,SHORT7':;

SECTION_NUMBER 1
 '@T6G_MB_LIB.T6G(SCH_1):PAGE150_I68@PURE_QUANTA.Q_SHORT(CHIPS)':
 C_PATH='@t6g_mb_lib.t6g(sch_1):page150_i68@pure_quanta.q_short(chips)';

PART_NAME
 J271 'Q_SHORT_SM-EMPTY,SHORT7':;

SECTION_NUMBER 1
 '@T6G_MB_LIB.T6G(SCH_1):PAGE150_I69@PURE_QUANTA.Q_SHORT(CHIPS)':
 C_PATH='@t6g_mb_lib.t6g(sch_1):page150_i69@pure_quanta.q_short(chips)';

PART_NAME
 D59 'SCHOTTKY_AC-SS1040,SMLF,IC,BCSS1040005':;

SECTION_NUMBER 1
 '@T6G_MB_LIB.T6G(SCH_1):PAGE150_I48@PURE_QUANTA.SCHOTTKY_AC(CHIPS)':
 C_PATH='@t6g_mb_lib.t6g(sch_1):page150_i48@pure_quanta.schottky_ac(chips)';

PART_NAME
 D58 'DIODE_TVS-SMF13A,SMLF,IC,BCSMF13AZ01':;

SECTION_NUMBER 1
 '@T6G_MB_LIB.T6G(SCH_1):PAGE150_I74@PURE_QUANTA.DIODE_TVS(CHIPS)':
 C_PATH='@t6g_mb_lib.t6g(sch_1):page150_i74@pure_quanta.diode_tvs(chips)';

PART_NAME
 C2510 'Q_CAP_C0805-10UF,16V,10%,X6S,CH6103KEA00':;

SECTION_NUMBER 1
 '@T6G_MB_LIB.T6G(SCH_1):PAGE150_I57@PURE_QUANTA.Q_CAP(CHIPS)':
 C_PATH='@t6g_mb_lib.t6g(sch_1):page150_i57@pure_quanta.q_cap(chips)';

PART_NAME
 C2509 'Q_CAP_C0603-0.15UF,10V,10%,X7R,CH41502K909':;

SECTION_NUMBER 1
 '@T6G_MB_LIB.T6G(SCH_1):PAGE150_I76@PURE_QUANTA.Q_CAP(CHIPS)':
 C_PATH='@t6g_mb_lib.t6g(sch_1):page150_i76@pure_quanta.q_cap(chips)';

PART_NAME
 C900 'Q_CAP_C0805-10UF,16V,10%,X6S,CH6103KEA00':;

SECTION_NUMBER 1
 '@T6G_MB_LIB.T6G(SCH_1):PAGE150_I45@PURE_QUANTA.Q_CAP(CHIPS)':
 C_PATH='@t6g_mb_lib.t6g(sch_1):page150_i45@pure_quanta.q_cap(chips)';

PART_NAME
 C899 'Q_CAP_0402-0.1UF,25V,10%,X7R,CH4104K1B00':;

SECTION_NUMBER 1
 '@T6G_MB_LIB.T6G(SCH_1):PAGE150_I51@PURE_QUANTA.Q_CAP(CHIPS)':
 C_PATH='@t6g_mb_lib.t6g(sch_1):page150_i51@pure_quanta.q_cap(chips)';

PART_NAME
 C898 'Q_CAP_C0402-39NF,16V,10%,X7R,CH3393K1B00':;

SECTION_NUMBER 1
 '@T6G_MB_LIB.T6G(SCH_1):PAGE150_I72@PURE_QUANTA.Q_CAP(CHIPS)':
 C_PATH='@t6g_mb_lib.t6g(sch_1):page150_i72@pure_quanta.q_cap(chips)';

PART_NAME
 C13 'Q_CAP_0402-0.1UF,25V,10%,X7R,CH4104K1B00':;

SECTION_NUMBER 1
 '@T6G_MB_LIB.T6G(SCH_1):PAGE150_I64@PURE_QUANTA.Q_CAP(CHIPS)':
 C_PATH='@t6g_mb_lib.t6g(sch_1):page150_i64@pure_quanta.q_cap(chips)';

PART_NAME
 R29 'Q_RES_0402LF-35.7K,1%,1/16W,CHIP,CS33572FB01':;

SECTION_NUMBER 1
 '@T6G_MB_LIB.T6G(SCH_1):PAGE105_I348@PURE_QUANTA.Q_RES(CHIPS)':
 C_PATH='@t6g_mb_lib.t6g(sch_1):page105_i348@pure_quanta.q_res(chips)';

PART_NAME
 J4 'SCONN288_ADR50001P003C01-SCONN288_ADR50001-P003C01,SMLF,IO,DFHST8FS301':;

SECTION_NUMBER 1
 '@T6G_MB_LIB.T6G(SCH_1):PAGE105_I345@PURE_QUANTA.SCONN288_ADR50001P003C01(CHIPS)':
 C_PATH='@t6g_mb_lib.t6g(sch_1):page105_i345@pure_quanta.sconn288_adr50001p003c0~
1(chips)';

SECTION_NUMBER 2
 '@T6G_MB_LIB.T6G(SCH_1):PAGE105_I346@PURE_QUANTA.SCONN288_ADR50001P003C01(CHIPS)':
 C_PATH='@t6g_mb_lib.t6g(sch_1):page105_i346@pure_quanta.sconn288_adr50001p003c0~
1(chips)';

SECTION_NUMBER 3
 '@T6G_MB_LIB.T6G(SCH_1):PAGE105_I347@PURE_QUANTA.SCONN288_ADR50001P003C01(CHIPS)':
 C_PATH='@t6g_mb_lib.t6g(sch_1):page105_i347@pure_quanta.sconn288_adr50001p003c0~
1(chips)';

PART_NAME
 C1372 'Q_CAP_C0805-10UF,16V,10%,X7R,CH6103K1A00':
;

SECTION_NUMBER 1
 '@T6G_MB_LIB.T6G(SCH_1):PAGE105_I338@PURE_QUANTA.Q_CAP(CHIPS)':
 C_PATH='@t6g_mb_lib.t6g(sch_1):page105_i338@pure_quanta.q_cap(chips)';

PART_NAME
 C12 'Q_CAP_C0805-10UF,16V,10%,X7R,CH6103K1A00':
;

SECTION_NUMBER 1
 '@T6G_MB_LIB.T6G(SCH_1):PAGE105_I344@PURE_QUANTA.Q_CAP(CHIPS)':
 C_PATH='@t6g_mb_lib.t6g(sch_1):page105_i344@pure_quanta.q_cap(chips)';

PART_NAME
 C11 'Q_CAP_C0402-2.2UF,6.3V,20%,X6S,CH5221MEB00':
;

SECTION_NUMBER 1
 '@T6G_MB_LIB.T6G(SCH_1):PAGE105_I340@PURE_QUANTA.Q_CAP(CHIPS)':
 C_PATH='@t6g_mb_lib.t6g(sch_1):page105_i340@pure_quanta.q_cap(chips)';

PART_NAME
 R28 'Q_RES_0402LF-23.2K,1%,1/16W,CHIP,TMP_QCS32322FB11':;

SECTION_NUMBER 1
 '@T6G_MB_LIB.T6G(SCH_1):PAGE104_I349@PURE_QUANTA.Q_RES(CHIPS)':
 C_PATH='@t6g_mb_lib.t6g(sch_1):page104_i349@pure_quanta.q_res(chips)';

PART_NAME
 J3 'SCONN288_ADR50001P013C01-SCONN288_ADR50001-P013C01,SMLF,IO,DFHST8FS302':;

SECTION_NUMBER 1
 '@T6G_MB_LIB.T6G(SCH_1):PAGE104_I345@PURE_QUANTA.SCONN288_ADR50001P013C01(CHIPS)':
 C_PATH='@t6g_mb_lib.t6g(sch_1):page104_i345@pure_quanta.sconn288_adr50001p013c0~
1(chips)';

SECTION_NUMBER 2
 '@T6G_MB_LIB.T6G(SCH_1):PAGE104_I346@PURE_QUANTA.SCONN288_ADR50001P013C01(CHIPS)':
 C_PATH='@t6g_mb_lib.t6g(sch_1):page104_i346@pure_quanta.sconn288_adr50001p013c0~
1(chips)';

SECTION_NUMBER 3
 '@T6G_MB_LIB.T6G(SCH_1):PAGE104_I347@PURE_QUANTA.SCONN288_ADR50001P013C01(CHIPS)':
 C_PATH='@t6g_mb_lib.t6g(sch_1):page104_i347@pure_quanta.sconn288_adr50001p013c0~
1(chips)';

PART_NAME
 C10 'Q_CAP_C0805-10UF,16V,10%,X7R,CH6103K1A00':
;

SECTION_NUMBER 1
 '@T6G_MB_LIB.T6G(SCH_1):PAGE104_I341@PURE_QUANTA.Q_CAP(CHIPS)':
 C_PATH='@t6g_mb_lib.t6g(sch_1):page104_i341@pure_quanta.q_cap(chips)';

PART_NAME
 C9 'Q_CAP_C0805-10UF,16V,10%,X7R,CH6103K1A00':
;

SECTION_NUMBER 1
 '@T6G_MB_LIB.T6G(SCH_1):PAGE104_I344@PURE_QUANTA.Q_CAP(CHIPS)':
 C_PATH='@t6g_mb_lib.t6g(sch_1):page104_i344@pure_quanta.q_cap(chips)';

PART_NAME
 C8 'Q_CAP_C0402-2.2UF,6.3V,20%,X6S,CH5221MEB00':
;

SECTION_NUMBER 1
 '@T6G_MB_LIB.T6G(SCH_1):PAGE104_I338@PURE_QUANTA.Q_CAP(CHIPS)':
 C_PATH='@t6g_mb_lib.t6g(sch_1):page104_i338@pure_quanta.q_cap(chips)';

PART_NAME
 R27 'Q_RES_0402LF-15.4K,1%,1/16W,CHIP,CS31542FB14':;

SECTION_NUMBER 1
 '@T6G_MB_LIB.T6G(SCH_1):PAGE103_I362@PURE_QUANTA.Q_RES(CHIPS)':
 C_PATH='@t6g_mb_lib.t6g(sch_1):page103_i362@pure_quanta.q_res(chips)';

PART_NAME
 J2 'SCONN288_ADR50001P003C01-SCONN288_ADR50001-P003C01,SMLF,IO,DFHST8FS301':;

SECTION_NUMBER 1
 '@T6G_MB_LIB.T6G(SCH_1):PAGE103_I358@PURE_QUANTA.SCONN288_ADR50001P003C01(CHIPS)':
 C_PATH='@t6g_mb_lib.t6g(sch_1):page103_i358@pure_quanta.sconn288_adr50001p003c0~
1(chips)';

SECTION_NUMBER 2
 '@T6G_MB_LIB.T6G(SCH_1):PAGE103_I359@PURE_QUANTA.SCONN288_ADR50001P003C01(CHIPS)':
 C_PATH='@t6g_mb_lib.t6g(sch_1):page103_i359@pure_quanta.sconn288_adr50001p003c0~
1(chips)';

SECTION_NUMBER 3
 '@T6G_MB_LIB.T6G(SCH_1):PAGE103_I360@PURE_QUANTA.SCONN288_ADR50001P003C01(CHIPS)':
 C_PATH='@t6g_mb_lib.t6g(sch_1):page103_i360@pure_quanta.sconn288_adr50001p003c0~
1(chips)';

PART_NAME
 C7 'Q_CAP_C0805-10UF,16V,10%,X7R,CH6103K1A00':
;

SECTION_NUMBER 1
 '@T6G_MB_LIB.T6G(SCH_1):PAGE103_I351@PURE_QUANTA.Q_CAP(CHIPS)':
 C_PATH='@t6g_mb_lib.t6g(sch_1):page103_i351@pure_quanta.q_cap(chips)';

PART_NAME
 C6 'Q_CAP_C0805-10UF,16V,10%,X7R,CH6103K1A00':
;

SECTION_NUMBER 1
 '@T6G_MB_LIB.T6G(SCH_1):PAGE103_I357@PURE_QUANTA.Q_CAP(CHIPS)':
 C_PATH='@t6g_mb_lib.t6g(sch_1):page103_i357@pure_quanta.q_cap(chips)';

PART_NAME
 C5 'Q_CAP_C0402-2.2UF,6.3V,20%,X6S,CH5221MEB00':
;

SECTION_NUMBER 1
 '@T6G_MB_LIB.T6G(SCH_1):PAGE103_I354@PURE_QUANTA.Q_CAP(CHIPS)':
 C_PATH='@t6g_mb_lib.t6g(sch_1):page103_i354@pure_quanta.q_cap(chips)';

PART_NAME
 R26 'Q_RES_0402LF-10K,1%,1/16W,CHIP,CS31002FB08':
;

SECTION_NUMBER 1
 '@T6G_MB_LIB.T6G(SCH_1):PAGE102_I499@PURE_QUANTA.Q_RES(CHIPS)':
 C_PATH='@t6g_mb_lib.t6g(sch_1):page102_i499@pure_quanta.q_res(chips)';

PART_NAME
 J1 'SCONN288_ADR50001P013C01-SCONN288_ADR50001-P013C01,SMLF,IO,DFHST8FS302':;

SECTION_NUMBER 1
 '@T6G_MB_LIB.T6G(SCH_1):PAGE102_I511@PURE_QUANTA.SCONN288_ADR50001P013C01(CHIPS)':
 C_PATH='@t6g_mb_lib.t6g(sch_1):page102_i511@pure_quanta.sconn288_adr50001p013c0~
1(chips)';

SECTION_NUMBER 2
 '@T6G_MB_LIB.T6G(SCH_1):PAGE102_I512@PURE_QUANTA.SCONN288_ADR50001P013C01(CHIPS)':
 C_PATH='@t6g_mb_lib.t6g(sch_1):page102_i512@pure_quanta.sconn288_adr50001p013c0~
1(chips)';

SECTION_NUMBER 3
 '@T6G_MB_LIB.T6G(SCH_1):PAGE102_I513@PURE_QUANTA.SCONN288_ADR50001P013C01(CHIPS)':
 C_PATH='@t6g_mb_lib.t6g(sch_1):page102_i513@pure_quanta.sconn288_adr50001p013c0~
1(chips)';

PART_NAME
 C4 'Q_CAP_C0805-10UF,16V,10%,X7R,CH6103K1A00':
;

SECTION_NUMBER 1
 '@T6G_MB_LIB.T6G(SCH_1):PAGE102_I502@PURE_QUANTA.Q_CAP(CHIPS)':
 C_PATH='@t6g_mb_lib.t6g(sch_1):page102_i502@pure_quanta.q_cap(chips)';

PART_NAME
 C3 'Q_CAP_C0805-10UF,16V,10%,X7R,CH6103K1A00':
;

SECTION_NUMBER 1
 '@T6G_MB_LIB.T6G(SCH_1):PAGE102_I510@PURE_QUANTA.Q_CAP(CHIPS)':
 C_PATH='@t6g_mb_lib.t6g(sch_1):page102_i510@pure_quanta.q_cap(chips)';

PART_NAME
 C2 'Q_CAP_C0402-2.2UF,6.3V,20%,X6S,CH5221MEB00':
;

SECTION_NUMBER 1
 '@T6G_MB_LIB.T6G(SCH_1):PAGE102_I506@PURE_QUANTA.Q_CAP(CHIPS)':
 C_PATH='@t6g_mb_lib.t6g(sch_1):page102_i506@pure_quanta.q_cap(chips)';

PART_NAME
 U2 'SOCKET4677_AZIFS035P001C01-SOCKET4677_AZIFS035-P001C01,SMLF,IO,DGA^7000012':;

SECTION_NUMBER 1
 '@T6G_MB_LIB.T6G(SCH_1):PAGE16_I650@PURE_QUANTA.SOCKET4677_AZIFS035P001C01(CHIPS)':
 C_PATH='@t6g_mb_lib.t6g(sch_1):page16_i650@pure_quanta.socket4677_azifs035p001c~
01(chips)';

SECTION_NUMBER 2
 '@T6G_MB_LIB.T6G(SCH_1):PAGE17_I355@PURE_QUANTA.SOCKET4677_AZIFS035P001C01(CHIPS)':
 C_PATH='@t6g_mb_lib.t6g(sch_1):page17_i355@pure_quanta.socket4677_azifs035p001c~
01(chips)';

SECTION_NUMBER 3
 '@T6G_MB_LIB.T6G(SCH_1):PAGE18_I176@PURE_QUANTA.SOCKET4677_AZIFS035P001C01(CHIPS)':
 C_PATH='@t6g_mb_lib.t6g(sch_1):page18_i176@pure_quanta.socket4677_azifs035p001c~
01(chips)';

SECTION_NUMBER 4
 '@T6G_MB_LIB.T6G(SCH_1):PAGE19_I156@PURE_QUANTA.SOCKET4677_AZIFS035P001C01(CHIPS)':
 C_PATH='@t6g_mb_lib.t6g(sch_1):page19_i156@pure_quanta.socket4677_azifs035p001c~
01(chips)';

SECTION_NUMBER 5
 '@T6G_MB_LIB.T6G(SCH_1):PAGE20_I5@PURE_QUANTA.SOCKET4677_AZIFS035P001C01(CHIPS)':
 C_PATH='@t6g_mb_lib.t6g(sch_1):page20_i5@pure_quanta.socket4677_azifs035p001c01~
(chips)';

SECTION_NUMBER 6
 '@T6G_MB_LIB.T6G(SCH_1):PAGE21_I4@PURE_QUANTA.SOCKET4677_AZIFS035P001C01(CHIPS)':
 C_PATH='@t6g_mb_lib.t6g(sch_1):page21_i4@pure_quanta.socket4677_azifs035p001c01~
(chips)';

SECTION_NUMBER 7
 '@T6G_MB_LIB.T6G(SCH_1):PAGE22_I269@PURE_QUANTA.SOCKET4677_AZIFS035P001C01(CHIPS)':
 C_PATH='@t6g_mb_lib.t6g(sch_1):page22_i269@pure_quanta.socket4677_azifs035p001c~
01(chips)';

SECTION_NUMBER 8
 '@T6G_MB_LIB.T6G(SCH_1):PAGE23_I661@PURE_QUANTA.SOCKET4677_AZIFS035P001C01(CHIPS)':
 C_PATH='@t6g_mb_lib.t6g(sch_1):page23_i661@pure_quanta.socket4677_azifs035p001c~
01(chips)';

SECTION_NUMBER 9
 '@T6G_MB_LIB.T6G(SCH_1):PAGE24_I654@PURE_QUANTA.SOCKET4677_AZIFS035P001C01(CHIPS)':
 C_PATH='@t6g_mb_lib.t6g(sch_1):page24_i654@pure_quanta.socket4677_azifs035p001c~
01(chips)';

SECTION_NUMBER 10
 '@T6G_MB_LIB.T6G(SCH_1):PAGE25_I713@PURE_QUANTA.SOCKET4677_AZIFS035P001C01(CHIPS)':
 C_PATH='@t6g_mb_lib.t6g(sch_1):page25_i713@pure_quanta.socket4677_azifs035p001c~
01(chips)';

SECTION_NUMBER 11
 '@T6G_MB_LIB.T6G(SCH_1):PAGE26_I616@PURE_QUANTA.SOCKET4677_AZIFS035P001C01(CHIPS)':
 C_PATH='@t6g_mb_lib.t6g(sch_1):page26_i616@pure_quanta.socket4677_azifs035p001c~
01(chips)';

SECTION_NUMBER 12
 '@T6G_MB_LIB.T6G(SCH_1):PAGE27_I944@PURE_QUANTA.SOCKET4677_AZIFS035P001C01(CHIPS)':
 C_PATH='@t6g_mb_lib.t6g(sch_1):page27_i944@pure_quanta.socket4677_azifs035p001c~
01(chips)';

SECTION_NUMBER 13
 '@T6G_MB_LIB.T6G(SCH_1):PAGE28_I631@PURE_QUANTA.SOCKET4677_AZIFS035P001C01(CHIPS)':
 C_PATH='@t6g_mb_lib.t6g(sch_1):page28_i631@pure_quanta.socket4677_azifs035p001c~
01(chips)';

SECTION_NUMBER 14
 '@T6G_MB_LIB.T6G(SCH_1):PAGE29_I637@PURE_QUANTA.SOCKET4677_AZIFS035P001C01(CHIPS)':
 C_PATH='@t6g_mb_lib.t6g(sch_1):page29_i637@pure_quanta.socket4677_azifs035p001c~
01(chips)';

SECTION_NUMBER 15
 '@T6G_MB_LIB.T6G(SCH_1):PAGE30_I637@PURE_QUANTA.SOCKET4677_AZIFS035P001C01(CHIPS)':
 C_PATH='@t6g_mb_lib.t6g(sch_1):page30_i637@pure_quanta.socket4677_azifs035p001c~
01(chips)';

SECTION_NUMBER 16
 '@T6G_MB_LIB.T6G(SCH_1):PAGE31_I179@PURE_QUANTA.SOCKET4677_AZIFS035P001C01(CHIPS)':
 C_PATH='@t6g_mb_lib.t6g(sch_1):page31_i179@pure_quanta.socket4677_azifs035p001c~
01(chips)';

SECTION_NUMBER 17
 '@T6G_MB_LIB.T6G(SCH_1):PAGE31_I108@PURE_QUANTA.SOCKET4677_AZIFS035P001C01(CHIPS)':
 C_PATH='@t6g_mb_lib.t6g(sch_1):page31_i108@pure_quanta.socket4677_azifs035p001c~
01(chips)';

SECTION_NUMBER 18
 '@T6G_MB_LIB.T6G(SCH_1):PAGE32_I139@PURE_QUANTA.SOCKET4677_AZIFS035P001C01(CHIPS)':
 C_PATH='@t6g_mb_lib.t6g(sch_1):page32_i139@pure_quanta.socket4677_azifs035p001c~
01(chips)';

SECTION_NUMBER 19
 '@T6G_MB_LIB.T6G(SCH_1):PAGE32_I140@PURE_QUANTA.SOCKET4677_AZIFS035P001C01(CHIPS)':
 C_PATH='@t6g_mb_lib.t6g(sch_1):page32_i140@pure_quanta.socket4677_azifs035p001c~
01(chips)';

SECTION_NUMBER 20
 '@T6G_MB_LIB.T6G(SCH_1):PAGE33_I69@PURE_QUANTA.SOCKET4677_AZIFS035P001C01(CHIPS)':
 C_PATH='@t6g_mb_lib.t6g(sch_1):page33_i69@pure_quanta.socket4677_azifs035p001c0~
1(chips)';

SECTION_NUMBER 21
 '@T6G_MB_LIB.T6G(SCH_1):PAGE34_I69@PURE_QUANTA.SOCKET4677_AZIFS035P001C01(CHIPS)':
 C_PATH='@t6g_mb_lib.t6g(sch_1):page34_i69@pure_quanta.socket4677_azifs035p001c0~
1(chips)';

SECTION_NUMBER 22
 '@T6G_MB_LIB.T6G(SCH_1):PAGE35_I101@PURE_QUANTA.SOCKET4677_AZIFS035P001C01(CHIPS)':
 C_PATH='@t6g_mb_lib.t6g(sch_1):page35_i101@pure_quanta.socket4677_azifs035p001c~
01(chips)';

SECTION_NUMBER 23
 '@T6G_MB_LIB.T6G(SCH_1):PAGE36_I101@PURE_QUANTA.SOCKET4677_AZIFS035P001C01(CHIPS)':
 C_PATH='@t6g_mb_lib.t6g(sch_1):page36_i101@pure_quanta.socket4677_azifs035p001c~
01(chips)';

SECTION_NUMBER 24
 '@T6G_MB_LIB.T6G(SCH_1):PAGE37_I101@PURE_QUANTA.SOCKET4677_AZIFS035P001C01(CHIPS)':
 C_PATH='@t6g_mb_lib.t6g(sch_1):page37_i101@pure_quanta.socket4677_azifs035p001c~
01(chips)';

SECTION_NUMBER 25
 '@T6G_MB_LIB.T6G(SCH_1):PAGE38_I101@PURE_QUANTA.SOCKET4677_AZIFS035P001C01(CHIPS)':
 C_PATH='@t6g_mb_lib.t6g(sch_1):page38_i101@pure_quanta.socket4677_azifs035p001c~
01(chips)';

SECTION_NUMBER 26
 '@T6G_MB_LIB.T6G(SCH_1):PAGE39_I19@PURE_QUANTA.SOCKET4677_AZIFS035P001C01(CHIPS)':
 C_PATH='@t6g_mb_lib.t6g(sch_1):page39_i19@pure_quanta.socket4677_azifs035p001c0~
1(chips)';

SECTION_NUMBER 27
 '@T6G_MB_LIB.T6G(SCH_1):PAGE39_I20@PURE_QUANTA.SOCKET4677_AZIFS035P001C01(CHIPS)':
 C_PATH='@t6g_mb_lib.t6g(sch_1):page39_i20@pure_quanta.socket4677_azifs035p001c0~
1(chips)';

SECTION_NUMBER 28
 '@T6G_MB_LIB.T6G(SCH_1):PAGE40_I52@PURE_QUANTA.SOCKET4677_AZIFS035P001C01(CHIPS)':
 C_PATH='@t6g_mb_lib.t6g(sch_1):page40_i52@pure_quanta.socket4677_azifs035p001c0~
1(chips)';

SECTION_NUMBER 29
 '@T6G_MB_LIB.T6G(SCH_1):PAGE40_I53@PURE_QUANTA.SOCKET4677_AZIFS035P001C01(CHIPS)':
 C_PATH='@t6g_mb_lib.t6g(sch_1):page40_i53@pure_quanta.socket4677_azifs035p001c0~
1(chips)';

SECTION_NUMBER 30
 '@T6G_MB_LIB.T6G(SCH_1):PAGE41_I26@PURE_QUANTA.SOCKET4677_AZIFS035P001C01(CHIPS)':
 C_PATH='@t6g_mb_lib.t6g(sch_1):page41_i26@pure_quanta.socket4677_azifs035p001c0~
1(chips)';

SECTION_NUMBER 31
 '@T6G_MB_LIB.T6G(SCH_1):PAGE41_I27@PURE_QUANTA.SOCKET4677_AZIFS035P001C01(CHIPS)':
 C_PATH='@t6g_mb_lib.t6g(sch_1):page41_i27@pure_quanta.socket4677_azifs035p001c0~
1(chips)';

SECTION_NUMBER 32
 '@T6G_MB_LIB.T6G(SCH_1):PAGE41_I28@PURE_QUANTA.SOCKET4677_AZIFS035P001C01(CHIPS)':
 C_PATH='@t6g_mb_lib.t6g(sch_1):page41_i28@pure_quanta.socket4677_azifs035p001c0~
1(chips)';

SECTION_NUMBER 33
 '@T6G_MB_LIB.T6G(SCH_1):PAGE42_I15@PURE_QUANTA.SOCKET4677_AZIFS035P001C01(CHIPS)':
 C_PATH='@t6g_mb_lib.t6g(sch_1):page42_i15@pure_quanta.socket4677_azifs035p001c0~
1(chips)';

SECTION_NUMBER 34
 '@T6G_MB_LIB.T6G(SCH_1):PAGE42_I16@PURE_QUANTA.SOCKET4677_AZIFS035P001C01(CHIPS)':
 C_PATH='@t6g_mb_lib.t6g(sch_1):page42_i16@pure_quanta.socket4677_azifs035p001c0~
1(chips)';

SECTION_NUMBER 35
 '@T6G_MB_LIB.T6G(SCH_1):PAGE42_I17@PURE_QUANTA.SOCKET4677_AZIFS035P001C01(CHIPS)':
 C_PATH='@t6g_mb_lib.t6g(sch_1):page42_i17@pure_quanta.socket4677_azifs035p001c0~
1(chips)';

SECTION_NUMBER 36
 '@T6G_MB_LIB.T6G(SCH_1):PAGE43_I11@PURE_QUANTA.SOCKET4677_AZIFS035P001C01(CHIPS)':
 C_PATH='@t6g_mb_lib.t6g(sch_1):page43_i11@pure_quanta.socket4677_azifs035p001c0~
1(chips)';

SECTION_NUMBER 37
 '@T6G_MB_LIB.T6G(SCH_1):PAGE43_I12@PURE_QUANTA.SOCKET4677_AZIFS035P001C01(CHIPS)':
 C_PATH='@t6g_mb_lib.t6g(sch_1):page43_i12@pure_quanta.socket4677_azifs035p001c0~
1(chips)';

SECTION_NUMBER 38
 '@T6G_MB_LIB.T6G(SCH_1):PAGE43_I13@PURE_QUANTA.SOCKET4677_AZIFS035P001C01(CHIPS)':
 C_PATH='@t6g_mb_lib.t6g(sch_1):page43_i13@pure_quanta.socket4677_azifs035p001c0~
1(chips)';

SECTION_NUMBER 39
 '@T6G_MB_LIB.T6G(SCH_1):PAGE44_I19@PURE_QUANTA.SOCKET4677_AZIFS035P001C01(CHIPS)':
 C_PATH='@t6g_mb_lib.t6g(sch_1):page44_i19@pure_quanta.socket4677_azifs035p001c0~
1(chips)';

SECTION_NUMBER 40
 '@T6G_MB_LIB.T6G(SCH_1):PAGE44_I20@PURE_QUANTA.SOCKET4677_AZIFS035P001C01(CHIPS)':
 C_PATH='@t6g_mb_lib.t6g(sch_1):page44_i20@pure_quanta.socket4677_azifs035p001c0~
1(chips)';

SECTION_NUMBER 41
 '@T6G_MB_LIB.T6G(SCH_1):PAGE45_I7@PURE_QUANTA.SOCKET4677_AZIFS035P001C01(CHIPS)':
 C_PATH='@t6g_mb_lib.t6g(sch_1):page45_i7@pure_quanta.socket4677_azifs035p001c01~
(chips)';

SECTION_NUMBER 42
 '@T6G_MB_LIB.T6G(SCH_1):PAGE45_I8@PURE_QUANTA.SOCKET4677_AZIFS035P001C01(CHIPS)':
 C_PATH='@t6g_mb_lib.t6g(sch_1):page45_i8@pure_quanta.socket4677_azifs035p001c01~
(chips)';

PART_NAME
 C1 'Q_CAP_C0402-0.1UF,16V,10%,X7R,CH4103K1B08':
;

SECTION_NUMBER 1
 '@T6G_MB_LIB.T6G(SCH_1):PAGE40_I34@PURE_QUANTA.Q_CAP(CHIPS)':
 C_PATH='@t6g_mb_lib.t6g(sch_1):page40_i34@pure_quanta.q_cap(chips)';

PART_NAME
 U62 'BAS70057F-BAS70-05-7-F,SMLF,IC,BC0BAS70Z01':;

SECTION_NUMBER 1
 '@T6G_MB_LIB.T6G(SCH_1):PAGE182_I174@PURE_QUANTA.BAS70057F(CHIPS)':
 C_PATH='@t6g_mb_lib.t6g(sch_1):page182_i174@pure_quanta.bas70057f(chips)';

PART_NAME
 U8 'EMMITSBURG_REV0P9-GFNOCPU04302300-QV2N-MM#99A1WT,SMLF,IC,AJ0QV2N0T00':;

SECTION_NUMBER 1
 '@T6G_MB_LIB.T6G(SCH_1):PAGE176_I350@PURE_QUANTA.EMMITSBURG_REV0P9(CHIPS)':
 C_PATH='@t6g_mb_lib.t6g(sch_1):page176_i350@pure_quanta.emmitsburg_rev0p9(chips~
)';

SECTION_NUMBER 2
 '@T6G_MB_LIB.T6G(SCH_1):PAGE177_I118@PURE_QUANTA.EMMITSBURG_REV0P9(CHIPS)':
 C_PATH='@t6g_mb_lib.t6g(sch_1):page177_i118@pure_quanta.emmitsburg_rev0p9(chips~
)';

SECTION_NUMBER 3
 '@T6G_MB_LIB.T6G(SCH_1):PAGE178_I672@PURE_QUANTA.EMMITSBURG_REV0P9(CHIPS)':
 C_PATH='@t6g_mb_lib.t6g(sch_1):page178_i672@pure_quanta.emmitsburg_rev0p9(chips~
)';

SECTION_NUMBER 4
 '@T6G_MB_LIB.T6G(SCH_1):PAGE179_I224@PURE_QUANTA.EMMITSBURG_REV0P9(CHIPS)':
 C_PATH='@t6g_mb_lib.t6g(sch_1):page179_i224@pure_quanta.emmitsburg_rev0p9(chips~
)';

SECTION_NUMBER 5
 '@T6G_MB_LIB.T6G(SCH_1):PAGE180_I461@PURE_QUANTA.EMMITSBURG_REV0P9(CHIPS)':
 C_PATH='@t6g_mb_lib.t6g(sch_1):page180_i461@pure_quanta.emmitsburg_rev0p9(chips~
)';

SECTION_NUMBER 6
 '@T6G_MB_LIB.T6G(SCH_1):PAGE181_I401@PURE_QUANTA.EMMITSBURG_REV0P9(CHIPS)':
 C_PATH='@t6g_mb_lib.t6g(sch_1):page181_i401@pure_quanta.emmitsburg_rev0p9(chips~
)';

SECTION_NUMBER 7
 '@T6G_MB_LIB.T6G(SCH_1):PAGE182_I137@PURE_QUANTA.EMMITSBURG_REV0P9(CHIPS)':
 C_PATH='@t6g_mb_lib.t6g(sch_1):page182_i137@pure_quanta.emmitsburg_rev0p9(chips~
)';

SECTION_NUMBER 8
 '@T6G_MB_LIB.T6G(SCH_1):PAGE183_I63@PURE_QUANTA.EMMITSBURG_REV0P9(CHIPS)':
 C_PATH='@s6q_mb_lib.s6q(sch_1):page183_i63@pure_quanta.emmitsburg_rev0p9(chips)~
';

SECTION_NUMBER 9
 '@T6G_MB_LIB.T6G(SCH_1):PAGE184_I24@PURE_QUANTA.EMMITSBURG_REV0P9(CHIPS)':
 C_PATH='@s6q_mb_lib.s6q(sch_1):page184_i24@pure_quanta.emmitsburg_rev0p9(chips)~
';

SECTION_NUMBER 10
 '@T6G_MB_LIB.T6G(SCH_1):PAGE184_I25@PURE_QUANTA.EMMITSBURG_REV0P9(CHIPS)':
 C_PATH='@s6q_mb_lib.s6q(sch_1):page184_i25@pure_quanta.emmitsburg_rev0p9(chips)~
';

SECTION_NUMBER 11
 '@T6G_MB_LIB.T6G(SCH_1):PAGE185_I23@PURE_QUANTA.EMMITSBURG_REV0P9(CHIPS)':
 C_PATH='@s6q_mb_lib.s6q(sch_1):page185_i23@pure_quanta.emmitsburg_rev0p9(chips)~
';

PART_NAME
 R3761 'Q_RES_0402LF-2K,1%,1/16W,CHIP,TMP_QCS22002FB19':;

SECTION_NUMBER 1
 '@T6G_MB_LIB.T6G(SCH_1):PAGE182_I186@PURE_QUANTA.Q_RES(CHIPS)':
 C_PATH='@t6g_mb_lib.t6g(sch_1):page182_i186@pure_quanta.q_res(chips)';

PART_NAME
 R3760 'Q_RES_0402LF-2K,1%,1/16W,CHIP,TMP_QCS22002FB19':;

SECTION_NUMBER 1
 '@T6G_MB_LIB.T6G(SCH_1):PAGE182_I184@PURE_QUANTA.Q_RES(CHIPS)':
 C_PATH='@t6g_mb_lib.t6g(sch_1):page182_i184@pure_quanta.q_res(chips)';

PART_NAME
 R2457 'Q_RES_0402LF-0,5%,1/16W,CHIP,CS00002JB38':;

SECTION_NUMBER 1
 '@T6G_MB_LIB.T6G(SCH_1):PAGE182_I163@PURE_QUANTA.Q_RES(CHIPS)':
 C_PATH='@t6g_mb_lib.t6g(sch_1):page182_i163@pure_quanta.q_res(chips)';

PART_NAME
 R2456 'Q_RES_0402LF-1K,1%,1/16W,CHIP,TMP_QCS21002FB24':;

SECTION_NUMBER 1
 '@T6G_MB_LIB.T6G(SCH_1):PAGE182_I180@PURE_QUANTA.Q_RES(CHIPS)':
 C_PATH='@t6g_mb_lib.t6g(sch_1):page182_i180@pure_quanta.q_res(chips)';

PART_NAME
 R1840 'Q_RES_0402LF-0,5%,1/16W,EMPTY,CS00002JB38':;

SECTION_NUMBER 1
 '@T6G_MB_LIB.T6G(SCH_1):PAGE182_I165@PURE_QUANTA.Q_RES(CHIPS)':
 C_PATH='@t6g_mb_lib.t6g(sch_1):page182_i165@pure_quanta.q_res(chips)';

PART_NAME
 R1839 'Q_RES_0402LF-0,5%,1/16W,EMPTY,CS00002JB38':;

SECTION_NUMBER 1
 '@T6G_MB_LIB.T6G(SCH_1):PAGE182_I164@PURE_QUANTA.Q_RES(CHIPS)':
 C_PATH='@t6g_mb_lib.t6g(sch_1):page182_i164@pure_quanta.q_res(chips)';

PART_NAME
 R1202 'Q_RES_0402LF-20K,1%,1/16W,CHIP,CS32002FB29':;

SECTION_NUMBER 1
 '@T6G_MB_LIB.T6G(SCH_1):PAGE182_I191@PURE_QUANTA.Q_RES(CHIPS)':
 C_PATH='@t6g_mb_lib.t6g(sch_1):page182_i191@pure_quanta.q_res(chips)';

PART_NAME
 R7P4 'Q_RES_0402LF-10K,1%,1/16W,CHIP,CS31002FB08':
;

SECTION_NUMBER 1
 '@T6G_MB_LIB.T6G(SCH_1):PAGE182_I109@PURE_QUANTA.Q_RES(CHIPS)':
 C_PATH='@t6g_mb_lib.t6g(sch_1):page182_i109@pure_quanta.q_res(chips)';

PART_NAME
 Q109 'MOSFET_N_GSD-NX7002AK,SMLF,IC,BAM70020062':;

SECTION_NUMBER 1
 '@T6G_MB_LIB.T6G(SCH_1):PAGE182_I157@PURE_QUANTA.MOSFET_N_GSD(CHIPS)':
 C_PATH='@t6g_mb_lib.t6g(sch_1):page182_i157@pure_quanta.mosfet_n_gsd(chips)';

PART_NAME
 Q108 'MOSFET_N_GSD-NX7002AK,SMLF,IC,BAM70020062':;

SECTION_NUMBER 1
 '@T6G_MB_LIB.T6G(SCH_1):PAGE182_I161@PURE_QUANTA.MOSFET_N_GSD(CHIPS)':
 C_PATH='@t6g_mb_lib.t6g(sch_1):page182_i161@pure_quanta.mosfet_n_gsd(chips)';

PART_NAME
 C611 'Q_CAP_C0402-1UF,25V,10%,X6S,CH5104KEB02':;

SECTION_NUMBER 1
 '@T6G_MB_LIB.T6G(SCH_1):PAGE182_I171@PURE_QUANTA.Q_CAP(CHIPS)':
 C_PATH='@t6g_mb_lib.t6g(sch_1):page182_i171@pure_quanta.q_cap(chips)';

PART_NAME
 C610 'Q_CAP_C0402-1UF,25V,10%,X6S,CH5104KEB02':;

SECTION_NUMBER 1
 '@T6G_MB_LIB.T6G(SCH_1):PAGE182_I190@PURE_QUANTA.Q_CAP(CHIPS)':
 C_PATH='@t6g_mb_lib.t6g(sch_1):page182_i190@pure_quanta.q_cap(chips)';

PART_NAME
 BT1 'CONN2_AAABAT029P15-CONN2_AAA-BAT-029-P15,THLF,IO,DFHS02FR031':;

SECTION_NUMBER 1
 '@T6G_MB_LIB.T6G(SCH_1):PAGE182_I183@PURE_QUANTA.CONN2_AAABAT029P15(CHIPS)':
 C_PATH='@t6g_mb_lib.t6g(sch_1):page182_i183@pure_quanta.conn2_aaabat029p15(chip~
s)';

END.
